G04 ================== begin FILE IDENTIFICATION RECORD ==================*
G04 Layout Name:  17301-sa.brd*
G04 Film Name:    NOTICE*
G04 File Format:  Gerber RS274X*
G04 File Origin:  Cadence Allegro 16.6-2015-S079*
G04 Origin Date:  Thu Jun 22 17:49:58 2017*
G04 *
G04 Layer:  MANUFACTURING/THERMAL*
G04 *
G04 Offset:    (0.00 0.00)*
G04 Mirror:    No*
G04 Mode:      Positive*
G04 Rotation:  0*
G04 FullContactRelief:  No*
G04 UndefLineWidth:     6.00*
G04 ================== end FILE IDENTIFICATION RECORD ====================*
%FSLAX35Y35*MOIN*%
%IR0*IPPOS*OFA0.00000B0.00000*MIA0B0*SFA1.00000B1.00000*%
%ADD10C,.004*%
%ADD11C,.006*%
%ADD12C,.0033*%
%ADD13C,.008*%
%ADD14C,.0055*%
G75*
%LPD*%
G75*
G36*
G01X-132611Y-19813D02*
G02X-81911Y-19553I25558J-40503D01*
G01X-93061Y-40883D01*
X-121561D01*
X-132611Y-19813D01*
G37*
G36*
G01X-135791Y41277D02*
X-127111D01*
G03X-93001Y41267I17058J11442D01*
G01X-85451D01*
X-96321Y20267D01*
X-124821D01*
X-135791Y41277D01*
G37*
G54D10*
G01X335598Y-55814D02*
X355598D01*
G01X385598Y-65814D02*
X335598D01*
G01D02*
Y-55814D01*
G01Y-15814D02*
X355598D01*
G01X335598Y-25814D02*
Y-15814D01*
G01X355598Y-25814D02*
X335598D01*
G01Y24186D02*
X355598D01*
G01X335598Y14186D02*
Y24186D01*
G01X355598Y14186D02*
X335598D01*
G01Y54186D02*
Y64186D01*
G01X355598Y54186D02*
X335598D01*
G01Y64186D02*
X375598D01*
G01X362183Y-79835D02*
X386183D01*
G01X355598Y-55814D02*
Y-25814D01*
G01Y-15814D02*
Y14186D01*
G01Y24186D02*
Y54186D01*
G01X386183Y-79835D02*
X374183Y-77835D01*
G01X386183Y-71835D02*
Y-91835D01*
G01X374183Y-77835D02*
Y-81835D01*
G01D02*
X386183Y-79835D01*
G01X385598Y-8963D02*
Y-65814D01*
G01X375594Y1041D02*
X375598Y1037D01*
G01Y64186D02*
Y1037D01*
G01D02*
X385598Y-8963D01*
G01X376103Y85845D02*
Y65845D01*
G01X388103Y71845D02*
Y75845D01*
G01X376103Y73845D02*
X388103Y71845D01*
G01Y75845D02*
X376103Y73845D01*
G01D02*
X416103D01*
G01X425043Y-79835D02*
X406183D01*
G01X418183Y-77835D02*
X406183Y-79835D01*
G01Y-91835D02*
Y-71835D01*
G01Y-79835D02*
X418183Y-81835D01*
G01X405598Y-65814D02*
X455598D01*
G01X405598Y-8454D02*
Y-65814D01*
G01X410598Y-8454D02*
X526589D01*
G01X415598Y1546D02*
X405598Y-8454D01*
G01X404103Y75845D02*
Y71845D01*
G01X416103Y73845D02*
X404103Y75845D01*
G01Y71845D02*
X416103Y73845D01*
G01X418183Y-81835D02*
Y-77835D01*
G01X415598Y64186D02*
Y1546D01*
G01X416103Y85845D02*
Y65845D01*
G01Y73845D02*
X424963D01*
G01X455598Y64186D02*
X415598D01*
G01X455598Y-65814D02*
Y-55814D01*
G01X435598D02*
Y-25814D01*
G01X455598Y-55814D02*
X435598D01*
G01X455598Y-25814D02*
X455589Y-15903D01*
G01X435598Y-15814D02*
Y14186D01*
G01X455598Y-15814D02*
X435598D01*
G01Y-25814D02*
X455598D01*
G01Y14186D02*
Y24186D01*
G01X435598D02*
Y54186D01*
G01X455598Y24186D02*
X435598D01*
G01Y14186D02*
X455598D01*
G01Y54186D02*
Y64186D01*
G01X435598Y54186D02*
X455598D01*
G01X460598Y-15814D02*
X526589D01*
G01X521589Y-39814D02*
Y-15814D01*
G01X523589Y-27814D02*
X521589Y-15814D01*
X519589Y-27814D01*
X523589D01*
G01X519589Y3546D02*
X521589Y-8454D01*
X523589Y3546D01*
X519589D01*
G01X521589Y15546D02*
Y-8454D01*
G01X647243Y-64315D02*
X687243D01*
G01X647243Y-54315D02*
Y-64315D01*
G01X667243Y-54315D02*
X647243D01*
G01Y-24315D02*
X667243D01*
G01X647243Y-14315D02*
Y-24315D01*
G01X667243Y-14315D02*
X647243D01*
G01Y15685D02*
X667243D01*
G01X647243Y25685D02*
Y15685D01*
G01X667243Y25685D02*
X647243D01*
G01Y55685D02*
X667243D01*
G01X647243Y65685D02*
Y55685D01*
G01X697243Y65685D02*
X647243D01*
G01X667243Y-24315D02*
Y-54315D01*
G01Y15685D02*
Y-14315D01*
G01Y55685D02*
Y25685D01*
G01X673243Y85685D02*
X697243D01*
G01X699243Y-84315D02*
Y-80315D01*
G01X687243Y-82315D02*
X699243Y-84315D01*
G01Y-80315D02*
X687243Y-82315D01*
G01D02*
X727243D01*
G01X687243Y-70315D02*
Y-90315D01*
G01Y-64315D02*
Y-1675D01*
G01X697243Y8325D02*
Y65685D01*
G01X687243Y-1675D02*
X697243Y8325D01*
G01Y93685D02*
Y73685D01*
G01X685243Y87685D02*
Y83685D01*
G01X697243Y85685D02*
X685243Y87685D01*
G01Y83685D02*
X697243Y85685D01*
G01X715243Y-80315D02*
Y-84315D01*
G01X727243Y-82315D02*
X715243Y-80315D01*
G01Y-84315D02*
X727243Y-82315D01*
G01D02*
X736103D01*
G01X727243Y-70315D02*
Y-90315D01*
G01Y-64315D02*
Y-1166D01*
G01X767243Y-64315D02*
X727243D01*
G01X727247Y-1170D02*
X727243Y-1166D01*
G01X717243Y8834D02*
Y65685D01*
G01X727243Y-1166D02*
X717243Y8834D01*
G01Y73685D02*
Y93685D01*
G01Y65685D02*
X767243D01*
G01X729243Y83685D02*
Y87685D01*
G01X736103Y85685D02*
X717243D01*
G01D02*
X729243Y83685D01*
G01Y87685D02*
X717243Y85685D01*
G01X747243Y-54315D02*
X767243D01*
G01X747243Y-24315D02*
Y-54315D01*
G01X767243Y-24315D02*
X747243D01*
G01Y-14315D02*
X767243D01*
G01X747243Y15685D02*
Y-14315D01*
G01X767243Y15685D02*
X747243D01*
G01Y25685D02*
X767243D01*
G01X747243Y55685D02*
Y25685D01*
G01X767243Y55685D02*
X747243D01*
G01X767243Y-54315D02*
Y-64315D01*
G01Y-14315D02*
Y-24315D01*
G01Y25685D02*
Y15685D01*
G01Y65685D02*
Y55685D01*
G54D11*
G01X-430111Y290997D02*
X-430161D01*
G01X-380111Y536997D02*
X-380161D01*
G01X-150821Y107127D02*
X-155821D01*
Y81127D01*
X-150821D01*
G01X-146061Y-24883D02*
X-151061D01*
Y-50883D01*
X-146061D01*
G01Y-45883D02*
X-126561D01*
X-137561Y-24883D01*
X-146061D01*
Y-19883D01*
X-132561D01*
X-121561Y-40883D01*
X-93061D01*
X-82061Y-19883D01*
X-68561D01*
Y-24883D01*
X-77061D01*
X-88061Y-45883D01*
X-68561D01*
G01X-146061D02*
Y-50883D01*
X-68561D01*
Y-45883D01*
G01X-149321Y36267D02*
X-154321D01*
Y10267D01*
X-149321D01*
G01Y15267D02*
Y10267D01*
X-71821D01*
Y15267D01*
G01X-149321D02*
X-129821D01*
X-140821Y36267D01*
X-149321D01*
Y41267D01*
X-135821D01*
X-124821Y20267D01*
X-96321D01*
X-85321Y41267D01*
X-71821D01*
Y36267D01*
X-80321D01*
X-91321Y15267D01*
X-71821D01*
G01X-150821Y86127D02*
Y81127D01*
X-73321D01*
Y86127D01*
G01X-150821D02*
X-131321D01*
X-142321Y107127D01*
X-150821D01*
Y112127D01*
X-137321D01*
X-126321Y91127D01*
X-97821D01*
X-86821Y112127D01*
X-73321D01*
Y107127D01*
X-81821D01*
X-92821Y86127D01*
X-73321D01*
G01X-130321Y121127D02*
X-142321Y119127D01*
X-130321Y117127D01*
Y121127D01*
G01X-123121Y119127D02*
X-142321D01*
G01X-119321Y77127D02*
X-131321Y75127D01*
X-119321Y73127D01*
Y77127D01*
G01X-128121Y75127D02*
X-131321D01*
G01X-94821D02*
X-130321D01*
G01X-102041Y-12393D02*
X-46271D01*
G01X-105121Y32297D02*
X-46421D01*
G01X-88201Y41307D02*
X-46421D01*
G01X-104821Y73127D02*
X-92821Y75127D01*
X-104821Y77127D01*
Y73127D01*
G01X-94521Y75127D02*
X-92821D01*
G01X-93821Y117127D02*
X-81821Y119127D01*
X-93821Y121127D01*
Y117127D01*
G01X-99521Y119127D02*
X-81821D01*
G01X-68561Y-24883D02*
X-63561D01*
Y-50883D01*
X-68561D01*
G01X-77041Y-19573D02*
X-46271D01*
G01X-71821Y36267D02*
X-66821D01*
Y10267D01*
X-71821D01*
G01X-73321Y107127D02*
X-68321D01*
Y81127D01*
X-73321D01*
G01X-51271Y-36453D02*
Y-19573D01*
G01X-49271Y-393D02*
X-51271Y-12393D01*
X-53271Y-393D01*
X-49271D01*
G01X-51271Y4147D02*
Y-12393D01*
G01X-49271Y-31573D02*
X-51271Y-19573D01*
X-53271Y-31573D01*
X-49271D01*
G01X-49421Y20297D02*
X-51421Y32297D01*
X-53421Y20297D01*
X-49421D01*
G01X-51421Y16797D02*
Y32297D01*
G01X-49421Y53307D02*
X-51421Y41307D01*
X-53421Y53307D01*
X-49421D01*
G01X-51421Y41307D02*
Y56447D01*
G01X415089Y-246154D02*
X386589Y-246203D01*
G01X496929Y390926D02*
X385589D01*
G01X411929Y492126D02*
X385589D01*
G01X403092Y-248175D02*
X415089Y-246154D01*
X403086Y-244175D01*
X403092Y-248175D01*
G01X393089Y405926D02*
X395589Y390926D01*
X398089Y405926D01*
X393089D01*
G01X395589Y428172D02*
Y390926D01*
G01Y459422D02*
Y492126D01*
G01X398089Y477126D02*
X395589Y492126D01*
X393089Y477126D01*
X398089D01*
G01X415089Y-246203D02*
Y-174203D01*
X459089D01*
Y-246203D01*
X415089D01*
G01Y-169203D02*
Y-154203D01*
G01X430089Y-161703D02*
X415089Y-164203D01*
X430089Y-166703D01*
Y-161703D01*
G01X459089Y-164203D02*
X415089D01*
G01X444089Y-166703D02*
X459089Y-164203D01*
X444089Y-161703D01*
Y-166703D01*
G01X469089Y-246203D02*
X510089D01*
G01X469089Y-174203D02*
X510089D01*
G01X459089Y-169203D02*
Y-154203D01*
G01X467064Y-164203D02*
X459089D01*
G01X497589Y-231203D02*
X500089Y-246203D01*
X502589Y-231203D01*
X497589D01*
G01X500089Y-221828D02*
Y-246203D01*
G01X502589Y-189203D02*
X500089Y-174203D01*
X497589Y-189203D01*
X502589D01*
G01X500089Y-190578D02*
Y-174203D01*
G01X680542Y394776D02*
X697089Y383297D01*
X698089D01*
G01X685505Y393158D02*
X680542Y394776D01*
X683795Y390694D01*
X685505Y393158D01*
G01X722243Y8834D02*
X840089D01*
G01X772243Y15685D02*
X840089D01*
G01X835089Y-15166D02*
Y8834D01*
G01X837089Y-3166D02*
X835089Y8834D01*
X833089Y-3166D01*
X837089D01*
G01X833089Y27685D02*
X835089Y15685D01*
X837089Y27685D01*
X833089D01*
G01X835089Y43497D02*
Y15685D01*
G01X-434411Y482297D02*
Y-303203D01*
G01D02*
X260089D01*
G01X-434411Y-258203D02*
X260089D01*
G01X-434411Y-214203D02*
X260089D01*
G01X-434411Y-128203D02*
X260089D01*
G01X-434411Y-113203D02*
X260089D01*
G01X-432911Y-58203D02*
X260089D01*
G01X-434411Y365297D02*
X260089D01*
G01X-435411Y420297D02*
X260089D01*
G01X-434411Y445297D02*
X260089D01*
G01X-434411Y616797D02*
Y475297D01*
X260089D01*
Y616797D01*
G01X-427411Y598797D02*
Y603797D01*
X-428411Y602797D01*
G01Y598797D02*
X-426411D01*
G01X-421811Y598630D02*
X-421978Y598714D01*
Y598880D01*
X-421811Y598964D01*
X-421644Y598880D01*
Y598714D01*
X-421811Y598630D01*
G01X-417961Y599464D02*
X-417294Y599047D01*
X-416544Y598797D01*
X-415878D01*
X-415211Y599047D01*
X-414711Y599464D01*
X-414461Y600047D01*
X-414628Y600630D01*
X-415044Y601130D01*
X-415794Y601464D01*
X-416794Y601630D01*
X-417378Y601964D01*
X-417628Y602547D01*
X-417461Y603130D01*
X-417044Y603547D01*
X-416461Y603797D01*
X-415878D01*
X-415294Y603630D01*
X-414794Y603214D01*
G01X-412111Y597130D02*
Y602130D01*
G01Y601380D02*
X-411694Y601797D01*
X-411278Y602047D01*
X-410611Y602130D01*
X-410028Y602047D01*
X-409444Y601630D01*
X-409194Y601047D01*
X-409111Y600464D01*
X-409194Y599880D01*
X-409444Y599297D01*
X-409944Y598964D01*
X-410611Y598797D01*
X-411194Y598880D01*
X-411778Y599130D01*
X-412111Y599464D01*
G01X-406261Y601047D02*
X-403594D01*
X-403844Y601630D01*
X-404261Y601964D01*
X-404844Y602130D01*
X-405428Y602047D01*
X-405928Y601797D01*
X-406261Y601214D01*
X-406428Y600714D01*
Y600214D01*
X-406261Y599714D01*
X-405844Y599214D01*
X-405344Y598880D01*
X-404761Y598797D01*
X-404178Y598964D01*
X-403594Y599464D01*
G01X-398078Y601714D02*
X-398661Y602047D01*
X-399161Y602130D01*
X-399828Y601964D01*
X-400328Y601630D01*
X-400661Y601047D01*
X-400744Y600464D01*
X-400661Y599880D01*
X-400328Y599380D01*
X-399828Y598964D01*
X-399161Y598797D01*
X-398578Y598964D01*
X-398078Y599297D01*
G01X-393811Y602130D02*
Y598797D01*
G01Y603464D02*
X-393978Y603547D01*
Y603714D01*
X-393811Y603797D01*
X-393644Y603714D01*
Y603547D01*
X-393811Y603464D01*
G01X-388711Y598797D02*
Y603047D01*
X-388544Y603464D01*
X-388211Y603714D01*
X-387711Y603797D01*
X-387211Y603630D01*
X-386961Y603214D01*
G01X-387961Y601797D02*
X-389628D01*
G01X-382611Y602130D02*
Y598797D01*
G01Y603464D02*
X-382778Y603547D01*
Y603714D01*
X-382611Y603797D01*
X-382444Y603714D01*
Y603547D01*
X-382611Y603464D01*
G01X-375678Y601714D02*
X-376261Y602047D01*
X-376761Y602130D01*
X-377428Y601964D01*
X-377928Y601630D01*
X-378261Y601047D01*
X-378344Y600464D01*
X-378261Y599880D01*
X-377928Y599380D01*
X-377428Y598964D01*
X-376761Y598797D01*
X-376178Y598964D01*
X-375678Y599297D01*
G01X-369911Y598797D02*
Y602130D01*
G01Y601547D02*
X-370244Y601880D01*
X-370744Y602047D01*
X-371328Y602130D01*
X-371911Y601964D01*
X-372411Y601630D01*
X-372744Y601130D01*
X-372911Y600464D01*
X-372744Y599797D01*
X-372411Y599297D01*
X-371911Y598964D01*
X-371328Y598797D01*
X-370744Y598880D01*
X-370244Y599130D01*
X-369911Y599464D01*
G01X-365811Y603797D02*
Y598797D01*
G01X-366978Y602130D02*
X-364644D01*
G01X-360211D02*
Y598797D01*
G01Y603464D02*
X-360378Y603547D01*
Y603714D01*
X-360211Y603797D01*
X-360044Y603714D01*
Y603547D01*
X-360211Y603464D01*
G01X-354611Y598797D02*
X-355111Y598880D01*
X-355611Y599214D01*
X-355944Y599797D01*
X-356111Y600464D01*
X-355944Y601130D01*
X-355611Y601714D01*
X-355111Y602047D01*
X-354611Y602130D01*
X-354111Y602047D01*
X-353611Y601714D01*
X-353278Y601130D01*
X-353194Y600464D01*
X-353278Y599797D01*
X-353611Y599214D01*
X-354111Y598880D01*
X-354611Y598797D01*
G01X-350428D02*
Y602130D01*
G01Y601297D02*
X-350094Y601714D01*
X-349594Y602047D01*
X-348928Y602130D01*
X-348344Y602047D01*
X-347844Y601714D01*
X-347594Y601130D01*
Y598797D01*
G01X-336311Y603797D02*
Y598797D01*
G01Y599547D02*
X-336644Y599130D01*
X-337144Y598880D01*
X-337728Y598797D01*
X-338394Y598964D01*
X-338894Y599380D01*
X-339228Y599880D01*
X-339311Y600464D01*
X-339228Y601047D01*
X-338894Y601547D01*
X-338394Y601964D01*
X-337728Y602130D01*
X-337144Y602047D01*
X-336728Y601880D01*
X-336311Y601547D01*
G01X-332211Y598797D02*
X-332711Y598880D01*
X-333211Y599214D01*
X-333544Y599797D01*
X-333711Y600464D01*
X-333544Y601130D01*
X-333211Y601714D01*
X-332711Y602047D01*
X-332211Y602130D01*
X-331711Y602047D01*
X-331211Y601714D01*
X-330878Y601130D01*
X-330794Y600464D01*
X-330878Y599797D01*
X-331211Y599214D01*
X-331711Y598880D01*
X-332211Y598797D01*
G01X-325278Y601714D02*
X-325861Y602047D01*
X-326361Y602130D01*
X-327028Y601964D01*
X-327528Y601630D01*
X-327861Y601047D01*
X-327944Y600464D01*
X-327861Y599880D01*
X-327528Y599380D01*
X-327028Y598964D01*
X-326361Y598797D01*
X-325778Y598964D01*
X-325278Y599297D01*
G01X-322428Y602130D02*
Y599797D01*
X-322094Y599214D01*
X-321594Y598880D01*
X-321011Y598797D01*
X-320428Y598880D01*
X-319928Y599214D01*
X-319594Y599797D01*
G01Y598797D02*
Y602130D01*
G01X-317911Y598797D02*
Y602130D01*
G01Y601214D02*
X-317661Y601630D01*
X-317244Y601964D01*
X-316661Y602130D01*
X-316078Y601964D01*
X-315661Y601630D01*
X-315411Y601214D01*
Y598797D01*
G01Y601214D02*
X-315161Y601630D01*
X-314744Y601964D01*
X-314161Y602130D01*
X-313578Y601964D01*
X-313161Y601630D01*
X-312911Y601130D01*
Y598797D01*
G01X-311061Y601047D02*
X-308394D01*
X-308644Y601630D01*
X-309061Y601964D01*
X-309644Y602130D01*
X-310228Y602047D01*
X-310728Y601797D01*
X-311061Y601214D01*
X-311228Y600714D01*
Y600214D01*
X-311061Y599714D01*
X-310644Y599214D01*
X-310144Y598880D01*
X-309561Y598797D01*
X-308978Y598964D01*
X-308394Y599464D01*
G01X-305628Y598797D02*
Y602130D01*
G01Y601297D02*
X-305294Y601714D01*
X-304794Y602047D01*
X-304128Y602130D01*
X-303544Y602047D01*
X-303044Y601714D01*
X-302794Y601130D01*
Y598797D01*
G01X-298611Y603797D02*
Y598797D01*
G01X-299778Y602130D02*
X-297444D01*
G01X-293011Y598630D02*
X-293178Y598714D01*
Y598880D01*
X-293011Y598964D01*
X-292844Y598880D01*
Y598714D01*
X-293011Y598630D01*
G01Y600880D02*
X-293178Y600964D01*
Y601130D01*
X-293011Y601214D01*
X-292844Y601130D01*
Y600964D01*
X-293011Y600880D01*
G01X-434411Y586797D02*
X260089D01*
G01X-434411Y616797D02*
X260089D01*
G01X-422661Y-282536D02*
X-421994Y-282953D01*
X-421244Y-283203D01*
X-420578D01*
X-419911Y-282953D01*
X-419411Y-282536D01*
X-419161Y-281953D01*
X-419328Y-281370D01*
X-419744Y-280870D01*
X-420494Y-280536D01*
X-421494Y-280370D01*
X-422078Y-280036D01*
X-422328Y-279453D01*
X-422161Y-278870D01*
X-421744Y-278453D01*
X-421161Y-278203D01*
X-420578D01*
X-419994Y-278370D01*
X-419494Y-278786D01*
G01X-415311Y-279870D02*
Y-283203D01*
G01Y-278536D02*
X-415478Y-278453D01*
Y-278286D01*
X-415311Y-278203D01*
X-415144Y-278286D01*
Y-278453D01*
X-415311Y-278536D01*
G01X-409711Y-283203D02*
Y-278203D01*
G01X-405528Y-283203D02*
Y-278203D01*
G01X-402861Y-279870D02*
X-405528Y-281786D01*
G01X-404444Y-281036D02*
X-402694Y-283203D01*
G01X-399761Y-282620D02*
X-399344Y-282953D01*
X-398761Y-283203D01*
X-398261D01*
X-397761Y-283036D01*
X-397428Y-282786D01*
X-397261Y-282453D01*
X-397344Y-281953D01*
X-397678Y-281703D01*
X-399178Y-281203D01*
X-399511Y-280620D01*
X-399344Y-280203D01*
X-399011Y-279953D01*
X-398511Y-279870D01*
X-398011Y-279953D01*
X-397511Y-280203D01*
G01X-391578Y-280286D02*
X-392161Y-279953D01*
X-392661Y-279870D01*
X-393328Y-280036D01*
X-393828Y-280370D01*
X-394161Y-280953D01*
X-394244Y-281536D01*
X-394161Y-282120D01*
X-393828Y-282620D01*
X-393328Y-283036D01*
X-392661Y-283203D01*
X-392078Y-283036D01*
X-391578Y-282703D01*
G01X-388478Y-283203D02*
Y-279870D01*
G01Y-280536D02*
X-388061Y-280203D01*
X-387644Y-279953D01*
X-387061Y-279870D01*
X-386644Y-279953D01*
X-386144Y-280203D01*
G01X-382961Y-280953D02*
X-380294D01*
X-380544Y-280370D01*
X-380961Y-280036D01*
X-381544Y-279870D01*
X-382128Y-279953D01*
X-382628Y-280203D01*
X-382961Y-280786D01*
X-383128Y-281286D01*
Y-281786D01*
X-382961Y-282286D01*
X-382544Y-282786D01*
X-382044Y-283120D01*
X-381461Y-283203D01*
X-380878Y-283036D01*
X-380294Y-282536D01*
G01X-377361Y-280953D02*
X-374694D01*
X-374944Y-280370D01*
X-375361Y-280036D01*
X-375944Y-279870D01*
X-376528Y-279953D01*
X-377028Y-280203D01*
X-377361Y-280786D01*
X-377528Y-281286D01*
Y-281786D01*
X-377361Y-282286D01*
X-376944Y-282786D01*
X-376444Y-283120D01*
X-375861Y-283203D01*
X-375278Y-283036D01*
X-374694Y-282536D01*
G01X-371928Y-283203D02*
Y-279870D01*
G01Y-280703D02*
X-371594Y-280286D01*
X-371094Y-279953D01*
X-370428Y-279870D01*
X-369844Y-279953D01*
X-369344Y-280286D01*
X-369094Y-280870D01*
Y-283203D01*
G01X-422661Y-237536D02*
X-421994Y-237953D01*
X-421244Y-238203D01*
X-420578D01*
X-419911Y-237953D01*
X-419411Y-237536D01*
X-419161Y-236953D01*
X-419328Y-236370D01*
X-419744Y-235870D01*
X-420494Y-235536D01*
X-421494Y-235370D01*
X-422078Y-235036D01*
X-422328Y-234453D01*
X-422161Y-233870D01*
X-421744Y-233453D01*
X-421161Y-233203D01*
X-420578D01*
X-419994Y-233370D01*
X-419494Y-233786D01*
G01X-415311Y-238203D02*
X-415811Y-238120D01*
X-416311Y-237786D01*
X-416644Y-237203D01*
X-416811Y-236536D01*
X-416644Y-235870D01*
X-416311Y-235286D01*
X-415811Y-234953D01*
X-415311Y-234870D01*
X-414811Y-234953D01*
X-414311Y-235286D01*
X-413978Y-235870D01*
X-413894Y-236536D01*
X-413978Y-237203D01*
X-414311Y-237786D01*
X-414811Y-238120D01*
X-415311Y-238203D01*
G01X-409711D02*
Y-233203D01*
G01X-402611D02*
Y-238203D01*
G01Y-237453D02*
X-402944Y-237870D01*
X-403444Y-238120D01*
X-404028Y-238203D01*
X-404694Y-238036D01*
X-405194Y-237620D01*
X-405528Y-237120D01*
X-405611Y-236536D01*
X-405528Y-235953D01*
X-405194Y-235453D01*
X-404694Y-235036D01*
X-404028Y-234870D01*
X-403444Y-234953D01*
X-403028Y-235120D01*
X-402611Y-235453D01*
G01X-399761Y-235953D02*
X-397094D01*
X-397344Y-235370D01*
X-397761Y-235036D01*
X-398344Y-234870D01*
X-398928Y-234953D01*
X-399428Y-235203D01*
X-399761Y-235786D01*
X-399928Y-236286D01*
Y-236786D01*
X-399761Y-237286D01*
X-399344Y-237786D01*
X-398844Y-238120D01*
X-398261Y-238203D01*
X-397678Y-238036D01*
X-397094Y-237536D01*
G01X-394078Y-238203D02*
Y-234870D01*
G01Y-235536D02*
X-393661Y-235203D01*
X-393244Y-234953D01*
X-392661Y-234870D01*
X-392244Y-234953D01*
X-391744Y-235203D01*
G01X-384211Y-238203D02*
Y-234870D01*
G01Y-235786D02*
X-383961Y-235370D01*
X-383544Y-235036D01*
X-382961Y-234870D01*
X-382378Y-235036D01*
X-381961Y-235370D01*
X-381711Y-235786D01*
Y-238203D01*
G01Y-235786D02*
X-381461Y-235370D01*
X-381044Y-235036D01*
X-380461Y-234870D01*
X-379878Y-235036D01*
X-379461Y-235370D01*
X-379211Y-235870D01*
Y-238203D01*
G01X-374611D02*
Y-234870D01*
G01Y-235453D02*
X-374944Y-235120D01*
X-375444Y-234953D01*
X-376028Y-234870D01*
X-376611Y-235036D01*
X-377111Y-235370D01*
X-377444Y-235870D01*
X-377611Y-236536D01*
X-377444Y-237203D01*
X-377111Y-237703D01*
X-376611Y-238036D01*
X-376028Y-238203D01*
X-375444Y-238120D01*
X-374944Y-237870D01*
X-374611Y-237536D01*
G01X-371761Y-237620D02*
X-371344Y-237953D01*
X-370761Y-238203D01*
X-370261D01*
X-369761Y-238036D01*
X-369428Y-237786D01*
X-369261Y-237453D01*
X-369344Y-236953D01*
X-369678Y-236703D01*
X-371178Y-236203D01*
X-371511Y-235620D01*
X-371344Y-235203D01*
X-371011Y-234953D01*
X-370511Y-234870D01*
X-370011Y-234953D01*
X-369511Y-235203D01*
G01X-366328Y-238203D02*
Y-233203D01*
G01X-363661Y-234870D02*
X-366328Y-236786D01*
G01X-365244Y-236036D02*
X-363494Y-238203D01*
G01X-419244Y-169703D02*
X-422578D01*
Y-164703D01*
X-419244D01*
G01X-420578Y-167120D02*
X-422578D01*
G01X-415311Y-164703D02*
Y-169703D01*
G01X-416478Y-166370D02*
X-414144D01*
G01X-408378Y-166786D02*
X-408961Y-166453D01*
X-409461Y-166370D01*
X-410128Y-166536D01*
X-410628Y-166870D01*
X-410961Y-167453D01*
X-411044Y-168036D01*
X-410961Y-168620D01*
X-410628Y-169120D01*
X-410128Y-169536D01*
X-409461Y-169703D01*
X-408878Y-169536D01*
X-408378Y-169203D01*
G01X-405528Y-169703D02*
Y-164703D01*
G01Y-167120D02*
X-405111Y-166703D01*
X-404694Y-166453D01*
X-404028Y-166370D01*
X-403528Y-166453D01*
X-402944Y-166786D01*
X-402694Y-167286D01*
Y-169703D01*
G01X-419244Y-122203D02*
X-422578D01*
Y-117203D01*
X-419244D01*
G01X-420578Y-119620D02*
X-422578D01*
G01X-416561Y-118870D02*
X-414061Y-122203D01*
G01Y-118870D02*
X-416561Y-122203D01*
G01X-409711Y-117203D02*
Y-122203D01*
G01X-410878Y-118870D02*
X-408544D01*
G01X-405361Y-119953D02*
X-402694D01*
X-402944Y-119370D01*
X-403361Y-119036D01*
X-403944Y-118870D01*
X-404528Y-118953D01*
X-405028Y-119203D01*
X-405361Y-119786D01*
X-405528Y-120286D01*
Y-120786D01*
X-405361Y-121286D01*
X-404944Y-121786D01*
X-404444Y-122120D01*
X-403861Y-122203D01*
X-403278Y-122036D01*
X-402694Y-121536D01*
G01X-399678Y-122203D02*
Y-118870D01*
G01Y-119536D02*
X-399261Y-119203D01*
X-398844Y-118953D01*
X-398261Y-118870D01*
X-397844Y-118953D01*
X-397344Y-119203D01*
G01X-394328Y-122203D02*
Y-118870D01*
G01Y-119703D02*
X-393994Y-119286D01*
X-393494Y-118953D01*
X-392828Y-118870D01*
X-392244Y-118953D01*
X-391744Y-119286D01*
X-391494Y-119870D01*
Y-122203D01*
G01X-385811D02*
Y-118870D01*
G01Y-119453D02*
X-386144Y-119120D01*
X-386644Y-118953D01*
X-387228Y-118870D01*
X-387811Y-119036D01*
X-388311Y-119370D01*
X-388644Y-119870D01*
X-388811Y-120536D01*
X-388644Y-121203D01*
X-388311Y-121703D01*
X-387811Y-122036D01*
X-387228Y-122203D01*
X-386644Y-122120D01*
X-386144Y-121870D01*
X-385811Y-121536D01*
G01X-381711Y-122203D02*
Y-117203D01*
G01X-370511Y-122203D02*
Y-117203D01*
G01X-363411Y-122203D02*
Y-118870D01*
G01Y-119453D02*
X-363744Y-119120D01*
X-364244Y-118953D01*
X-364828Y-118870D01*
X-365411Y-119036D01*
X-365911Y-119370D01*
X-366244Y-119870D01*
X-366411Y-120536D01*
X-366244Y-121203D01*
X-365911Y-121703D01*
X-365411Y-122036D01*
X-364828Y-122203D01*
X-364244Y-122120D01*
X-363744Y-121870D01*
X-363411Y-121536D01*
G01X-361061Y-123703D02*
X-360561Y-123870D01*
X-359894Y-123703D01*
X-359478Y-123370D01*
X-359144Y-122953D01*
X-358644Y-121620D01*
X-357561Y-118870D01*
G01X-360228D02*
X-358644Y-121620D01*
G01X-354961Y-119953D02*
X-352294D01*
X-352544Y-119370D01*
X-352961Y-119036D01*
X-353544Y-118870D01*
X-354128Y-118953D01*
X-354628Y-119203D01*
X-354961Y-119786D01*
X-355128Y-120286D01*
Y-120786D01*
X-354961Y-121286D01*
X-354544Y-121786D01*
X-354044Y-122120D01*
X-353461Y-122203D01*
X-352878Y-122036D01*
X-352294Y-121536D01*
G01X-349278Y-122203D02*
Y-118870D01*
G01Y-119536D02*
X-348861Y-119203D01*
X-348444Y-118953D01*
X-347861Y-118870D01*
X-347444Y-118953D01*
X-346944Y-119203D01*
G01X-419078Y-87620D02*
X-419578Y-87370D01*
X-420161Y-87203D01*
X-420828D01*
X-421578Y-87453D01*
X-422161Y-87870D01*
X-422578Y-88370D01*
X-422911Y-89203D01*
X-422994Y-89953D01*
X-422828Y-90703D01*
X-422578Y-91203D01*
X-422078Y-91703D01*
X-421494Y-92036D01*
X-420911Y-92203D01*
X-420328D01*
X-419744Y-92036D01*
X-419244Y-91786D01*
X-418828Y-91453D01*
G01X-415311Y-92203D02*
X-415811Y-92120D01*
X-416311Y-91786D01*
X-416644Y-91203D01*
X-416811Y-90536D01*
X-416644Y-89870D01*
X-416311Y-89286D01*
X-415811Y-88953D01*
X-415311Y-88870D01*
X-414811Y-88953D01*
X-414311Y-89286D01*
X-413978Y-89870D01*
X-413894Y-90536D01*
X-413978Y-91203D01*
X-414311Y-91786D01*
X-414811Y-92120D01*
X-415311Y-92203D01*
G01X-411211Y-93870D02*
Y-88870D01*
G01Y-89620D02*
X-410794Y-89203D01*
X-410378Y-88953D01*
X-409711Y-88870D01*
X-409128Y-88953D01*
X-408544Y-89370D01*
X-408294Y-89953D01*
X-408211Y-90536D01*
X-408294Y-91120D01*
X-408544Y-91703D01*
X-409044Y-92036D01*
X-409711Y-92203D01*
X-410294Y-92120D01*
X-410878Y-91870D01*
X-411211Y-91536D01*
G01X-405611Y-93870D02*
Y-88870D01*
G01Y-89620D02*
X-405194Y-89203D01*
X-404778Y-88953D01*
X-404111Y-88870D01*
X-403528Y-88953D01*
X-402944Y-89370D01*
X-402694Y-89953D01*
X-402611Y-90536D01*
X-402694Y-91120D01*
X-402944Y-91703D01*
X-403444Y-92036D01*
X-404111Y-92203D01*
X-404694Y-92120D01*
X-405278Y-91870D01*
X-405611Y-91536D01*
G01X-399761Y-89953D02*
X-397094D01*
X-397344Y-89370D01*
X-397761Y-89036D01*
X-398344Y-88870D01*
X-398928Y-88953D01*
X-399428Y-89203D01*
X-399761Y-89786D01*
X-399928Y-90286D01*
Y-90786D01*
X-399761Y-91286D01*
X-399344Y-91786D01*
X-398844Y-92120D01*
X-398261Y-92203D01*
X-397678Y-92036D01*
X-397094Y-91536D01*
G01X-394078Y-92203D02*
Y-88870D01*
G01Y-89536D02*
X-393661Y-89203D01*
X-393244Y-88953D01*
X-392661Y-88870D01*
X-392244Y-88953D01*
X-391744Y-89203D01*
G01X-383378Y-92203D02*
Y-87203D01*
X-381378D01*
X-380711Y-87453D01*
X-380211Y-88036D01*
X-380044Y-88703D01*
X-380211Y-89370D01*
X-380628Y-89870D01*
X-381378Y-90120D01*
X-383378D01*
G01X-376111Y-92203D02*
Y-87203D01*
G01X-369011Y-92203D02*
Y-88870D01*
G01Y-89453D02*
X-369344Y-89120D01*
X-369844Y-88953D01*
X-370428Y-88870D01*
X-371011Y-89036D01*
X-371511Y-89370D01*
X-371844Y-89870D01*
X-372011Y-90536D01*
X-371844Y-91203D01*
X-371511Y-91703D01*
X-371011Y-92036D01*
X-370428Y-92203D01*
X-369844Y-92120D01*
X-369344Y-91870D01*
X-369011Y-91536D01*
G01X-364911Y-87203D02*
Y-92203D01*
G01X-366078Y-88870D02*
X-363744D01*
G01X-359311D02*
Y-92203D01*
G01Y-87536D02*
X-359478Y-87453D01*
Y-87286D01*
X-359311Y-87203D01*
X-359144Y-87286D01*
Y-87453D01*
X-359311Y-87536D01*
G01X-355128Y-92203D02*
Y-88870D01*
G01Y-89703D02*
X-354794Y-89286D01*
X-354294Y-88953D01*
X-353628Y-88870D01*
X-353044Y-88953D01*
X-352544Y-89286D01*
X-352294Y-89870D01*
Y-92203D01*
G01X-349278Y-93453D02*
X-348694Y-93786D01*
X-348028Y-93870D01*
X-347444Y-93786D01*
X-346944Y-93370D01*
X-346611Y-92786D01*
Y-88870D01*
G01Y-89536D02*
X-346944Y-89203D01*
X-347444Y-88953D01*
X-348028Y-88870D01*
X-348694Y-89036D01*
X-349111Y-89370D01*
X-349444Y-89953D01*
X-349611Y-90536D01*
X-349528Y-91036D01*
X-349194Y-91620D01*
X-348694Y-92036D01*
X-348028Y-92203D01*
X-347528Y-92120D01*
X-346944Y-91786D01*
X-346611Y-91453D01*
G01X-422744Y225297D02*
Y230297D01*
X-421078D01*
X-420411Y230047D01*
X-419911Y229714D01*
X-419494Y229214D01*
X-419161Y228630D01*
X-419078Y227797D01*
X-419161Y226964D01*
X-419494Y226380D01*
X-419911Y225880D01*
X-420411Y225547D01*
X-421078Y225297D01*
X-422744D01*
G01X-416478D02*
Y228630D01*
G01Y227964D02*
X-416061Y228297D01*
X-415644Y228547D01*
X-415061Y228630D01*
X-414644Y228547D01*
X-414144Y228297D01*
G01X-409711Y228630D02*
Y225297D01*
G01Y229964D02*
X-409878Y230047D01*
Y230214D01*
X-409711Y230297D01*
X-409544Y230214D01*
Y230047D01*
X-409711Y229964D01*
G01X-404111Y225297D02*
Y230297D01*
G01X-398511Y225297D02*
Y230297D01*
G01X-409451Y393037D02*
X-407451D01*
G01X-408451D02*
Y388037D01*
G01X-409451D02*
X-407451D01*
G01X-404268D02*
Y391370D01*
G01Y390537D02*
X-403934Y390954D01*
X-403434Y391287D01*
X-402768Y391370D01*
X-402184Y391287D01*
X-401684Y390954D01*
X-401434Y390370D01*
Y388037D01*
G01X-398668D02*
Y391370D01*
G01Y390537D02*
X-398334Y390954D01*
X-397834Y391287D01*
X-397168Y391370D01*
X-396584Y391287D01*
X-396084Y390954D01*
X-395834Y390370D01*
Y388037D01*
G01X-392901Y390287D02*
X-390234D01*
X-390484Y390870D01*
X-390901Y391204D01*
X-391484Y391370D01*
X-392068Y391287D01*
X-392568Y391037D01*
X-392901Y390454D01*
X-393068Y389954D01*
Y389454D01*
X-392901Y388954D01*
X-392484Y388454D01*
X-391984Y388120D01*
X-391401Y388037D01*
X-390818Y388204D01*
X-390234Y388704D01*
G01X-387218Y388037D02*
Y391370D01*
G01Y390704D02*
X-386801Y391037D01*
X-386384Y391287D01*
X-385801Y391370D01*
X-385384Y391287D01*
X-384884Y391037D01*
G01X-374851Y388037D02*
Y393037D01*
G01X-367751Y388037D02*
Y391370D01*
G01Y390787D02*
X-368084Y391120D01*
X-368584Y391287D01*
X-369168Y391370D01*
X-369751Y391204D01*
X-370251Y390870D01*
X-370584Y390370D01*
X-370751Y389704D01*
X-370584Y389037D01*
X-370251Y388537D01*
X-369751Y388204D01*
X-369168Y388037D01*
X-368584Y388120D01*
X-368084Y388370D01*
X-367751Y388704D01*
G01X-365401Y386537D02*
X-364901Y386370D01*
X-364234Y386537D01*
X-363818Y386870D01*
X-363484Y387287D01*
X-362984Y388620D01*
X-361901Y391370D01*
G01X-364568D02*
X-362984Y388620D01*
G01X-359301Y390287D02*
X-356634D01*
X-356884Y390870D01*
X-357301Y391204D01*
X-357884Y391370D01*
X-358468Y391287D01*
X-358968Y391037D01*
X-359301Y390454D01*
X-359468Y389954D01*
Y389454D01*
X-359301Y388954D01*
X-358884Y388454D01*
X-358384Y388120D01*
X-357801Y388037D01*
X-357218Y388204D01*
X-356634Y388704D01*
G01X-353618Y388037D02*
Y391370D01*
G01Y390704D02*
X-353201Y391037D01*
X-352784Y391287D01*
X-352201Y391370D01*
X-351784Y391287D01*
X-351284Y391037D01*
G01X-424494Y459964D02*
X-423994Y460464D01*
X-423411Y460714D01*
X-422744Y460797D01*
X-421911Y460630D01*
X-421328Y460214D01*
X-421161Y459714D01*
X-421244Y459214D01*
X-421578Y458797D01*
X-423244Y457964D01*
X-423994Y457380D01*
X-424494Y456547D01*
X-424661Y455797D01*
X-421161D01*
G01X-417311Y455630D02*
X-417478Y455714D01*
Y455880D01*
X-417311Y455964D01*
X-417144Y455880D01*
Y455714D01*
X-417311Y455630D01*
G01X-411711Y460797D02*
Y455797D01*
G01X-413628Y460797D02*
X-409794D01*
G01X-406111Y455797D02*
X-406611Y455880D01*
X-407111Y456214D01*
X-407444Y456797D01*
X-407611Y457464D01*
X-407444Y458130D01*
X-407111Y458714D01*
X-406611Y459047D01*
X-406111Y459130D01*
X-405611Y459047D01*
X-405111Y458714D01*
X-404778Y458130D01*
X-404694Y457464D01*
X-404778Y456797D01*
X-405111Y456214D01*
X-405611Y455880D01*
X-406111Y455797D01*
G01X-400511D02*
Y460797D01*
G01X-396161Y458047D02*
X-393494D01*
X-393744Y458630D01*
X-394161Y458964D01*
X-394744Y459130D01*
X-395328Y459047D01*
X-395828Y458797D01*
X-396161Y458214D01*
X-396328Y457714D01*
Y457214D01*
X-396161Y456714D01*
X-395744Y456214D01*
X-395244Y455880D01*
X-394661Y455797D01*
X-394078Y455964D01*
X-393494Y456464D01*
G01X-390478Y455797D02*
Y459130D01*
G01Y458464D02*
X-390061Y458797D01*
X-389644Y459047D01*
X-389061Y459130D01*
X-388644Y459047D01*
X-388144Y458797D01*
G01X-382211Y455797D02*
Y459130D01*
G01Y458547D02*
X-382544Y458880D01*
X-383044Y459047D01*
X-383628Y459130D01*
X-384211Y458964D01*
X-384711Y458630D01*
X-385044Y458130D01*
X-385211Y457464D01*
X-385044Y456797D01*
X-384711Y456297D01*
X-384211Y455964D01*
X-383628Y455797D01*
X-383044Y455880D01*
X-382544Y456130D01*
X-382211Y456464D01*
G01X-379528Y455797D02*
Y459130D01*
G01Y458297D02*
X-379194Y458714D01*
X-378694Y459047D01*
X-378028Y459130D01*
X-377444Y459047D01*
X-376944Y458714D01*
X-376694Y458130D01*
Y455797D01*
G01X-371178Y458714D02*
X-371761Y459047D01*
X-372261Y459130D01*
X-372928Y458964D01*
X-373428Y458630D01*
X-373761Y458047D01*
X-373844Y457464D01*
X-373761Y456880D01*
X-373428Y456380D01*
X-372928Y455964D01*
X-372261Y455797D01*
X-371678Y455964D01*
X-371178Y456297D01*
G01X-368161Y458047D02*
X-365494D01*
X-365744Y458630D01*
X-366161Y458964D01*
X-366744Y459130D01*
X-367328Y459047D01*
X-367828Y458797D01*
X-368161Y458214D01*
X-368328Y457714D01*
Y457214D01*
X-368161Y456714D01*
X-367744Y456214D01*
X-367244Y455880D01*
X-366661Y455797D01*
X-366078Y455964D01*
X-365494Y456464D01*
G01X-355711Y460797D02*
Y455797D01*
G01X-356878Y459130D02*
X-354544D01*
G01X-348611Y455797D02*
Y459130D01*
G01Y458547D02*
X-348944Y458880D01*
X-349444Y459047D01*
X-350028Y459130D01*
X-350611Y458964D01*
X-351111Y458630D01*
X-351444Y458130D01*
X-351611Y457464D01*
X-351444Y456797D01*
X-351111Y456297D01*
X-350611Y455964D01*
X-350028Y455797D01*
X-349444Y455880D01*
X-348944Y456130D01*
X-348611Y456464D01*
G01X-346011Y455797D02*
Y460797D01*
G01Y458297D02*
X-345594Y458797D01*
X-345094Y459047D01*
X-344594Y459130D01*
X-343844Y458964D01*
X-343344Y458630D01*
X-343011Y458047D01*
Y457380D01*
X-343178Y456714D01*
X-343511Y456214D01*
X-344094Y455880D01*
X-344594Y455797D01*
X-345094Y455880D01*
X-345594Y456130D01*
X-346011Y456547D01*
G01X-338911Y455797D02*
Y460797D01*
G01X-334561Y458047D02*
X-331894D01*
X-332144Y458630D01*
X-332561Y458964D01*
X-333144Y459130D01*
X-333728Y459047D01*
X-334228Y458797D01*
X-334561Y458214D01*
X-334728Y457714D01*
Y457214D01*
X-334561Y456714D01*
X-334144Y456214D01*
X-333644Y455880D01*
X-333061Y455797D01*
X-332478Y455964D01*
X-331894Y456464D01*
G01X-327711Y455630D02*
X-327878Y455714D01*
Y455880D01*
X-327711Y455964D01*
X-327544Y455880D01*
Y455714D01*
X-327711Y455630D01*
G01Y457880D02*
X-327878Y457964D01*
Y458130D01*
X-327711Y458214D01*
X-327544Y458130D01*
Y457964D01*
X-327711Y457880D01*
G01X-400411Y429630D02*
Y434630D01*
G01Y433880D02*
X-399994Y434297D01*
X-399578Y434547D01*
X-398911Y434630D01*
X-398328Y434547D01*
X-397744Y434130D01*
X-397494Y433547D01*
X-397411Y432964D01*
X-397494Y432380D01*
X-397744Y431797D01*
X-398244Y431464D01*
X-398911Y431297D01*
X-399494Y431380D01*
X-400078Y431630D01*
X-400411Y431964D01*
G01X-394478Y431297D02*
Y434630D01*
G01Y433964D02*
X-394061Y434297D01*
X-393644Y434547D01*
X-393061Y434630D01*
X-392644Y434547D01*
X-392144Y434297D01*
G01X-387711Y431297D02*
X-388211Y431380D01*
X-388711Y431714D01*
X-389044Y432297D01*
X-389211Y432964D01*
X-389044Y433630D01*
X-388711Y434214D01*
X-388211Y434547D01*
X-387711Y434630D01*
X-387211Y434547D01*
X-386711Y434214D01*
X-386378Y433630D01*
X-386294Y432964D01*
X-386378Y432297D01*
X-386711Y431714D01*
X-387211Y431380D01*
X-387711Y431297D01*
G01X-380778Y434214D02*
X-381361Y434547D01*
X-381861Y434630D01*
X-382528Y434464D01*
X-383028Y434130D01*
X-383361Y433547D01*
X-383444Y432964D01*
X-383361Y432380D01*
X-383028Y431880D01*
X-382528Y431464D01*
X-381861Y431297D01*
X-381278Y431464D01*
X-380778Y431797D01*
G01X-377761Y433547D02*
X-375094D01*
X-375344Y434130D01*
X-375761Y434464D01*
X-376344Y434630D01*
X-376928Y434547D01*
X-377428Y434297D01*
X-377761Y433714D01*
X-377928Y433214D01*
Y432714D01*
X-377761Y432214D01*
X-377344Y431714D01*
X-376844Y431380D01*
X-376261Y431297D01*
X-375678Y431464D01*
X-375094Y431964D01*
G01X-372161Y431880D02*
X-371744Y431547D01*
X-371161Y431297D01*
X-370661D01*
X-370161Y431464D01*
X-369828Y431714D01*
X-369661Y432047D01*
X-369744Y432547D01*
X-370078Y432797D01*
X-371578Y433297D01*
X-371911Y433880D01*
X-371744Y434297D01*
X-371411Y434547D01*
X-370911Y434630D01*
X-370411Y434547D01*
X-369911Y434297D01*
G01X-366561Y431880D02*
X-366144Y431547D01*
X-365561Y431297D01*
X-365061D01*
X-364561Y431464D01*
X-364228Y431714D01*
X-364061Y432047D01*
X-364144Y432547D01*
X-364478Y432797D01*
X-365978Y433297D01*
X-366311Y433880D01*
X-366144Y434297D01*
X-365811Y434547D01*
X-365311Y434630D01*
X-364811Y434547D01*
X-364311Y434297D01*
G01X-363411Y495897D02*
X-361411D01*
G01X-362411D02*
Y490897D01*
G01X-363411D02*
X-361411D01*
G01X-358478D02*
Y495897D01*
X-356478D01*
X-355811Y495647D01*
X-355311Y495064D01*
X-355144Y494397D01*
X-355311Y493730D01*
X-355728Y493230D01*
X-356478Y492980D01*
X-358478D01*
G01X-349378Y495480D02*
X-349878Y495730D01*
X-350461Y495897D01*
X-351128D01*
X-351878Y495647D01*
X-352461Y495230D01*
X-352878Y494730D01*
X-353211Y493897D01*
X-353294Y493147D01*
X-353128Y492397D01*
X-352878Y491897D01*
X-352378Y491397D01*
X-351794Y491064D01*
X-351211Y490897D01*
X-350628D01*
X-350044Y491064D01*
X-349544Y491314D01*
X-349128Y491647D01*
G01X-346694Y492564D02*
X-344528D01*
G01X-341678Y495897D02*
Y490897D01*
X-338344D01*
G01X-335494Y492564D02*
X-333328D01*
G01X-328811Y490897D02*
Y495897D01*
X-329811Y494897D01*
G01Y490897D02*
X-327811D01*
G01X-323211Y495897D02*
X-323878Y495730D01*
X-324378Y495314D01*
X-324711Y494814D01*
X-324961Y494147D01*
X-325044Y493397D01*
X-324961Y492647D01*
X-324711Y491980D01*
X-324378Y491480D01*
X-323878Y491064D01*
X-323211Y490897D01*
X-322544Y491064D01*
X-322044Y491480D01*
X-321711Y491980D01*
X-321461Y492647D01*
X-321378Y493397D01*
X-321461Y494147D01*
X-321711Y494814D01*
X-322044Y495314D01*
X-322544Y495730D01*
X-323211Y495897D01*
G01X-319028Y491480D02*
X-318444Y491064D01*
X-317778Y490897D01*
X-317111Y491064D01*
X-316528Y491564D01*
X-316111Y492314D01*
X-315944Y493064D01*
Y493980D01*
X-316111Y494730D01*
X-316528Y495397D01*
X-317028Y495730D01*
X-317611Y495897D01*
X-318278Y495730D01*
X-318778Y495397D01*
X-319111Y494897D01*
X-319278Y494230D01*
X-319111Y493647D01*
X-318694Y493064D01*
X-318194Y492730D01*
X-317611Y492647D01*
X-316944Y492814D01*
X-316444Y493230D01*
X-315944Y493980D01*
G01X-308161Y491564D02*
X-307494Y491147D01*
X-306744Y490897D01*
X-306078D01*
X-305411Y491147D01*
X-304911Y491564D01*
X-304661Y492147D01*
X-304828Y492730D01*
X-305244Y493230D01*
X-305994Y493564D01*
X-306994Y493730D01*
X-307578Y494064D01*
X-307828Y494647D01*
X-307661Y495230D01*
X-307244Y495647D01*
X-306661Y495897D01*
X-306078D01*
X-305494Y495730D01*
X-304994Y495314D01*
G01X-302311Y489230D02*
Y494230D01*
G01Y493480D02*
X-301894Y493897D01*
X-301478Y494147D01*
X-300811Y494230D01*
X-300228Y494147D01*
X-299644Y493730D01*
X-299394Y493147D01*
X-299311Y492564D01*
X-299394Y491980D01*
X-299644Y491397D01*
X-300144Y491064D01*
X-300811Y490897D01*
X-301394Y490980D01*
X-301978Y491230D01*
X-302311Y491564D01*
G01X-296461Y493147D02*
X-293794D01*
X-294044Y493730D01*
X-294461Y494064D01*
X-295044Y494230D01*
X-295628Y494147D01*
X-296128Y493897D01*
X-296461Y493314D01*
X-296628Y492814D01*
Y492314D01*
X-296461Y491814D01*
X-296044Y491314D01*
X-295544Y490980D01*
X-294961Y490897D01*
X-294378Y491064D01*
X-293794Y491564D01*
G01X-288278Y493814D02*
X-288861Y494147D01*
X-289361Y494230D01*
X-290028Y494064D01*
X-290528Y493730D01*
X-290861Y493147D01*
X-290944Y492564D01*
X-290861Y491980D01*
X-290528Y491480D01*
X-290028Y491064D01*
X-289361Y490897D01*
X-288778Y491064D01*
X-288278Y491397D01*
G01X-284011Y494230D02*
Y490897D01*
G01Y495564D02*
X-284178Y495647D01*
Y495814D01*
X-284011Y495897D01*
X-283844Y495814D01*
Y495647D01*
X-284011Y495564D01*
G01X-278911Y490897D02*
Y495147D01*
X-278744Y495564D01*
X-278411Y495814D01*
X-277911Y495897D01*
X-277411Y495730D01*
X-277161Y495314D01*
G01X-278161Y493897D02*
X-279828D01*
G01X-272811Y494230D02*
Y490897D01*
G01Y495564D02*
X-272978Y495647D01*
Y495814D01*
X-272811Y495897D01*
X-272644Y495814D01*
Y495647D01*
X-272811Y495564D01*
G01X-265878Y493814D02*
X-266461Y494147D01*
X-266961Y494230D01*
X-267628Y494064D01*
X-268128Y493730D01*
X-268461Y493147D01*
X-268544Y492564D01*
X-268461Y491980D01*
X-268128Y491480D01*
X-267628Y491064D01*
X-266961Y490897D01*
X-266378Y491064D01*
X-265878Y491397D01*
G01X-260111Y490897D02*
Y494230D01*
G01Y493647D02*
X-260444Y493980D01*
X-260944Y494147D01*
X-261528Y494230D01*
X-262111Y494064D01*
X-262611Y493730D01*
X-262944Y493230D01*
X-263111Y492564D01*
X-262944Y491897D01*
X-262611Y491397D01*
X-262111Y491064D01*
X-261528Y490897D01*
X-260944Y490980D01*
X-260444Y491230D01*
X-260111Y491564D01*
G01X-256011Y495897D02*
Y490897D01*
G01X-257178Y494230D02*
X-254844D01*
G01X-250411D02*
Y490897D01*
G01Y495564D02*
X-250578Y495647D01*
Y495814D01*
X-250411Y495897D01*
X-250244Y495814D01*
Y495647D01*
X-250411Y495564D01*
G01X-244811Y490897D02*
X-245311Y490980D01*
X-245811Y491314D01*
X-246144Y491897D01*
X-246311Y492564D01*
X-246144Y493230D01*
X-245811Y493814D01*
X-245311Y494147D01*
X-244811Y494230D01*
X-244311Y494147D01*
X-243811Y493814D01*
X-243478Y493230D01*
X-243394Y492564D01*
X-243478Y491897D01*
X-243811Y491314D01*
X-244311Y490980D01*
X-244811Y490897D01*
G01X-240628D02*
Y494230D01*
G01Y493397D02*
X-240294Y493814D01*
X-239794Y494147D01*
X-239128Y494230D01*
X-238544Y494147D01*
X-238044Y493814D01*
X-237794Y493230D01*
Y490897D01*
G01X-228511D02*
Y495147D01*
X-228344Y495564D01*
X-228011Y495814D01*
X-227511Y495897D01*
X-227011Y495730D01*
X-226761Y495314D01*
G01X-227761Y493897D02*
X-229428D01*
G01X-222411Y490897D02*
X-222911Y490980D01*
X-223411Y491314D01*
X-223744Y491897D01*
X-223911Y492564D01*
X-223744Y493230D01*
X-223411Y493814D01*
X-222911Y494147D01*
X-222411Y494230D01*
X-221911Y494147D01*
X-221411Y493814D01*
X-221078Y493230D01*
X-220994Y492564D01*
X-221078Y491897D01*
X-221411Y491314D01*
X-221911Y490980D01*
X-222411Y490897D01*
G01X-217978D02*
Y494230D01*
G01Y493564D02*
X-217561Y493897D01*
X-217144Y494147D01*
X-216561Y494230D01*
X-216144Y494147D01*
X-215644Y493897D01*
G01X-207278Y490897D02*
Y495897D01*
X-205194D01*
X-204528Y495647D01*
X-204111Y495314D01*
X-203944Y494647D01*
X-204111Y493980D01*
X-204611Y493564D01*
X-205194Y493314D01*
X-207278D01*
G01X-205194D02*
X-203944Y490897D01*
G01X-201261Y493147D02*
X-198594D01*
X-198844Y493730D01*
X-199261Y494064D01*
X-199844Y494230D01*
X-200428Y494147D01*
X-200928Y493897D01*
X-201261Y493314D01*
X-201428Y492814D01*
Y492314D01*
X-201261Y491814D01*
X-200844Y491314D01*
X-200344Y490980D01*
X-199761Y490897D01*
X-199178Y491064D01*
X-198594Y491564D01*
G01X-195661Y491480D02*
X-195244Y491147D01*
X-194661Y490897D01*
X-194161D01*
X-193661Y491064D01*
X-193328Y491314D01*
X-193161Y491647D01*
X-193244Y492147D01*
X-193578Y492397D01*
X-195078Y492897D01*
X-195411Y493480D01*
X-195244Y493897D01*
X-194911Y494147D01*
X-194411Y494230D01*
X-193911Y494147D01*
X-193411Y493897D01*
G01X-188811Y494230D02*
Y490897D01*
G01Y495564D02*
X-188978Y495647D01*
Y495814D01*
X-188811Y495897D01*
X-188644Y495814D01*
Y495647D01*
X-188811Y495564D01*
G01X-184628Y490897D02*
Y494230D01*
G01Y493397D02*
X-184294Y493814D01*
X-183794Y494147D01*
X-183128Y494230D01*
X-182544Y494147D01*
X-182044Y493814D01*
X-181794Y493230D01*
Y490897D01*
G01X-173011Y495897D02*
X-171011D01*
G01X-172011D02*
Y490897D01*
G01X-173011D02*
X-171011D01*
G01X-168911D02*
Y494230D01*
G01Y493314D02*
X-168661Y493730D01*
X-168244Y494064D01*
X-167661Y494230D01*
X-167078Y494064D01*
X-166661Y493730D01*
X-166411Y493314D01*
Y490897D01*
G01Y493314D02*
X-166161Y493730D01*
X-165744Y494064D01*
X-165161Y494230D01*
X-164578Y494064D01*
X-164161Y493730D01*
X-163911Y493230D01*
Y490897D01*
G01X-162311Y489230D02*
Y494230D01*
G01Y493480D02*
X-161894Y493897D01*
X-161478Y494147D01*
X-160811Y494230D01*
X-160228Y494147D01*
X-159644Y493730D01*
X-159394Y493147D01*
X-159311Y492564D01*
X-159394Y491980D01*
X-159644Y491397D01*
X-160144Y491064D01*
X-160811Y490897D01*
X-161394Y490980D01*
X-161978Y491230D01*
X-162311Y491564D01*
G01X-156378Y490897D02*
Y494230D01*
G01Y493564D02*
X-155961Y493897D01*
X-155544Y494147D01*
X-154961Y494230D01*
X-154544Y494147D01*
X-154044Y493897D01*
G01X-150861Y493147D02*
X-148194D01*
X-148444Y493730D01*
X-148861Y494064D01*
X-149444Y494230D01*
X-150028Y494147D01*
X-150528Y493897D01*
X-150861Y493314D01*
X-151028Y492814D01*
Y492314D01*
X-150861Y491814D01*
X-150444Y491314D01*
X-149944Y490980D01*
X-149361Y490897D01*
X-148778Y491064D01*
X-148194Y491564D01*
G01X-145178Y489647D02*
X-144594Y489314D01*
X-143928Y489230D01*
X-143344Y489314D01*
X-142844Y489730D01*
X-142511Y490314D01*
Y494230D01*
G01Y493564D02*
X-142844Y493897D01*
X-143344Y494147D01*
X-143928Y494230D01*
X-144594Y494064D01*
X-145011Y493730D01*
X-145344Y493147D01*
X-145511Y492564D01*
X-145428Y492064D01*
X-145094Y491480D01*
X-144594Y491064D01*
X-143928Y490897D01*
X-143428Y490980D01*
X-142844Y491314D01*
X-142511Y491647D01*
G01X-139828Y490897D02*
Y494230D01*
G01Y493397D02*
X-139494Y493814D01*
X-138994Y494147D01*
X-138328Y494230D01*
X-137744Y494147D01*
X-137244Y493814D01*
X-136994Y493230D01*
Y490897D01*
G01X-131311D02*
Y494230D01*
G01Y493647D02*
X-131644Y493980D01*
X-132144Y494147D01*
X-132728Y494230D01*
X-133311Y494064D01*
X-133811Y493730D01*
X-134144Y493230D01*
X-134311Y492564D01*
X-134144Y491897D01*
X-133811Y491397D01*
X-133311Y491064D01*
X-132728Y490897D01*
X-132144Y490980D01*
X-131644Y491230D01*
X-131311Y491564D01*
G01X-127211Y495897D02*
Y490897D01*
G01X-128378Y494230D02*
X-126044D01*
G01X-122861Y493147D02*
X-120194D01*
X-120444Y493730D01*
X-120861Y494064D01*
X-121444Y494230D01*
X-122028Y494147D01*
X-122528Y493897D01*
X-122861Y493314D01*
X-123028Y492814D01*
Y492314D01*
X-122861Y491814D01*
X-122444Y491314D01*
X-121944Y490980D01*
X-121361Y490897D01*
X-120778Y491064D01*
X-120194Y491564D01*
G01X-114511Y495897D02*
Y490897D01*
G01Y491647D02*
X-114844Y491230D01*
X-115344Y490980D01*
X-115928Y490897D01*
X-116594Y491064D01*
X-117094Y491480D01*
X-117428Y491980D01*
X-117511Y492564D01*
X-117428Y493147D01*
X-117094Y493647D01*
X-116594Y494064D01*
X-115928Y494230D01*
X-115344Y494147D01*
X-114928Y493980D01*
X-114511Y493647D01*
G01X-106394Y490897D02*
Y495897D01*
X-103228D01*
G01X-104394Y493480D02*
X-106394D01*
G01X-97711Y490897D02*
Y494230D01*
G01Y493647D02*
X-98044Y493980D01*
X-98544Y494147D01*
X-99128Y494230D01*
X-99711Y494064D01*
X-100211Y493730D01*
X-100544Y493230D01*
X-100711Y492564D01*
X-100544Y491897D01*
X-100211Y491397D01*
X-99711Y491064D01*
X-99128Y490897D01*
X-98544Y490980D01*
X-98044Y491230D01*
X-97711Y491564D01*
G01X-95111Y490897D02*
Y495897D01*
G01Y493397D02*
X-94694Y493897D01*
X-94194Y494147D01*
X-93694Y494230D01*
X-92944Y494064D01*
X-92444Y493730D01*
X-92111Y493147D01*
Y492480D01*
X-92278Y491814D01*
X-92611Y491314D01*
X-93194Y490980D01*
X-93694Y490897D01*
X-94194Y490980D01*
X-94694Y491230D01*
X-95111Y491647D01*
G01X-89178Y490897D02*
Y494230D01*
G01Y493564D02*
X-88761Y493897D01*
X-88344Y494147D01*
X-87761Y494230D01*
X-87344Y494147D01*
X-86844Y493897D01*
G01X-82411Y494230D02*
Y490897D01*
G01Y495564D02*
X-82578Y495647D01*
Y495814D01*
X-82411Y495897D01*
X-82244Y495814D01*
Y495647D01*
X-82411Y495564D01*
G01X-75478Y493814D02*
X-76061Y494147D01*
X-76561Y494230D01*
X-77228Y494064D01*
X-77728Y493730D01*
X-78061Y493147D01*
X-78144Y492564D01*
X-78061Y491980D01*
X-77728Y491480D01*
X-77228Y491064D01*
X-76561Y490897D01*
X-75978Y491064D01*
X-75478Y491397D01*
G01X-71628Y489230D02*
X-72461Y490064D01*
X-72878Y490897D01*
Y494230D01*
X-72461Y495064D01*
X-71628Y495897D01*
G01X-67278Y490897D02*
Y495897D01*
X-65278D01*
X-64611Y495647D01*
X-64111Y495064D01*
X-63944Y494397D01*
X-64111Y493730D01*
X-64528Y493230D01*
X-65278Y492980D01*
X-67278D01*
G01X-61178Y490897D02*
Y494230D01*
G01Y493564D02*
X-60761Y493897D01*
X-60344Y494147D01*
X-59761Y494230D01*
X-59344Y494147D01*
X-58844Y493897D01*
G01X-55661Y493147D02*
X-52994D01*
X-53244Y493730D01*
X-53661Y494064D01*
X-54244Y494230D01*
X-54828Y494147D01*
X-55328Y493897D01*
X-55661Y493314D01*
X-55828Y492814D01*
Y492314D01*
X-55661Y491814D01*
X-55244Y491314D01*
X-54744Y490980D01*
X-54161Y490897D01*
X-53578Y491064D01*
X-52994Y491564D01*
G01X-50311Y489230D02*
Y494230D01*
G01Y493480D02*
X-49894Y493897D01*
X-49478Y494147D01*
X-48811Y494230D01*
X-48228Y494147D01*
X-47644Y493730D01*
X-47394Y493147D01*
X-47311Y492564D01*
X-47394Y491980D01*
X-47644Y491397D01*
X-48144Y491064D01*
X-48811Y490897D01*
X-49394Y490980D01*
X-49978Y491230D01*
X-50311Y491564D01*
G01X-44378Y490897D02*
Y494230D01*
G01Y493564D02*
X-43961Y493897D01*
X-43544Y494147D01*
X-42961Y494230D01*
X-42544Y494147D01*
X-42044Y493897D01*
G01X-38861Y493147D02*
X-36194D01*
X-36444Y493730D01*
X-36861Y494064D01*
X-37444Y494230D01*
X-38028Y494147D01*
X-38528Y493897D01*
X-38861Y493314D01*
X-39028Y492814D01*
Y492314D01*
X-38861Y491814D01*
X-38444Y491314D01*
X-37944Y490980D01*
X-37361Y490897D01*
X-36778Y491064D01*
X-36194Y491564D01*
G01X-33178Y489647D02*
X-32594Y489314D01*
X-31928Y489230D01*
X-31344Y489314D01*
X-30844Y489730D01*
X-30511Y490314D01*
Y494230D01*
G01Y493564D02*
X-30844Y493897D01*
X-31344Y494147D01*
X-31928Y494230D01*
X-32594Y494064D01*
X-33011Y493730D01*
X-33344Y493147D01*
X-33511Y492564D01*
X-33428Y492064D01*
X-33094Y491480D01*
X-32594Y491064D01*
X-31928Y490897D01*
X-31428Y490980D01*
X-30844Y491314D01*
X-30511Y491647D01*
G01X-25994Y489230D02*
X-25161Y490064D01*
X-24744Y490897D01*
Y494230D01*
X-25161Y495064D01*
X-25994Y495897D01*
G01X-15711Y490897D02*
Y495147D01*
X-15544Y495564D01*
X-15211Y495814D01*
X-14711Y495897D01*
X-14211Y495730D01*
X-13961Y495314D01*
G01X-14961Y493897D02*
X-16628D01*
G01X-9611Y490897D02*
X-10111Y490980D01*
X-10611Y491314D01*
X-10944Y491897D01*
X-11111Y492564D01*
X-10944Y493230D01*
X-10611Y493814D01*
X-10111Y494147D01*
X-9611Y494230D01*
X-9111Y494147D01*
X-8611Y493814D01*
X-8278Y493230D01*
X-8194Y492564D01*
X-8278Y491897D01*
X-8611Y491314D01*
X-9111Y490980D01*
X-9611Y490897D01*
G01X-5178D02*
Y494230D01*
G01Y493564D02*
X-4761Y493897D01*
X-4344Y494147D01*
X-3761Y494230D01*
X-3344Y494147D01*
X-2844Y493897D01*
G01X5022Y490897D02*
Y495897D01*
X7189Y491730D01*
X9356Y495897D01*
Y490897D01*
G01X11372Y494230D02*
Y491897D01*
X11706Y491314D01*
X12206Y490980D01*
X12789Y490897D01*
X13372Y490980D01*
X13872Y491314D01*
X14206Y491897D01*
G01Y490897D02*
Y494230D01*
G01X18389Y490897D02*
Y495897D01*
G01X23989D02*
Y490897D01*
G01X22822Y494230D02*
X25156D01*
G01X29589D02*
Y490897D01*
G01Y495564D02*
X29422Y495647D01*
Y495814D01*
X29589Y495897D01*
X29756Y495814D01*
Y495647D01*
X29589Y495564D01*
G01X35189Y490897D02*
Y495897D01*
G01X42289Y490897D02*
Y494230D01*
G01Y493647D02*
X41956Y493980D01*
X41456Y494147D01*
X40872Y494230D01*
X40289Y494064D01*
X39789Y493730D01*
X39456Y493230D01*
X39289Y492564D01*
X39456Y491897D01*
X39789Y491397D01*
X40289Y491064D01*
X40872Y490897D01*
X41456Y490980D01*
X41956Y491230D01*
X42289Y491564D01*
G01X44639Y489397D02*
X45139Y489230D01*
X45806Y489397D01*
X46222Y489730D01*
X46556Y490147D01*
X47056Y491480D01*
X48139Y494230D01*
G01X45472D02*
X47056Y491480D01*
G01X50739Y493147D02*
X53406D01*
X53156Y493730D01*
X52739Y494064D01*
X52156Y494230D01*
X51572Y494147D01*
X51072Y493897D01*
X50739Y493314D01*
X50572Y492814D01*
Y492314D01*
X50739Y491814D01*
X51156Y491314D01*
X51656Y490980D01*
X52239Y490897D01*
X52822Y491064D01*
X53406Y491564D01*
G01X56422Y490897D02*
Y494230D01*
G01Y493564D02*
X56839Y493897D01*
X57256Y494147D01*
X57839Y494230D01*
X58256Y494147D01*
X58756Y493897D01*
G01X67122Y490897D02*
Y495897D01*
X69122D01*
X69789Y495647D01*
X70289Y495064D01*
X70456Y494397D01*
X70289Y493730D01*
X69872Y493230D01*
X69122Y492980D01*
X67122D01*
G01X73222Y490897D02*
Y494230D01*
G01Y493564D02*
X73639Y493897D01*
X74056Y494147D01*
X74639Y494230D01*
X75056Y494147D01*
X75556Y493897D01*
G01X79989Y494230D02*
Y490897D01*
G01Y495564D02*
X79822Y495647D01*
Y495814D01*
X79989Y495897D01*
X80156Y495814D01*
Y495647D01*
X79989Y495564D01*
G01X84172Y490897D02*
Y494230D01*
G01Y493397D02*
X84506Y493814D01*
X85006Y494147D01*
X85672Y494230D01*
X86256Y494147D01*
X86756Y493814D01*
X87006Y493230D01*
Y490897D01*
G01X91189Y495897D02*
Y490897D01*
G01X90022Y494230D02*
X92356D01*
G01X95539Y493147D02*
X98206D01*
X97956Y493730D01*
X97539Y494064D01*
X96956Y494230D01*
X96372Y494147D01*
X95872Y493897D01*
X95539Y493314D01*
X95372Y492814D01*
Y492314D01*
X95539Y491814D01*
X95956Y491314D01*
X96456Y490980D01*
X97039Y490897D01*
X97622Y491064D01*
X98206Y491564D01*
G01X103889Y495897D02*
Y490897D01*
G01Y491647D02*
X103556Y491230D01*
X103056Y490980D01*
X102472Y490897D01*
X101806Y491064D01*
X101306Y491480D01*
X100972Y491980D01*
X100889Y492564D01*
X100972Y493147D01*
X101306Y493647D01*
X101806Y494064D01*
X102472Y494230D01*
X103056Y494147D01*
X103472Y493980D01*
X103889Y493647D01*
G01X114256Y493564D02*
X114589Y493814D01*
X114839Y494230D01*
X115006Y494814D01*
X114839Y495314D01*
X114506Y495647D01*
X113922Y495897D01*
X111672D01*
Y490897D01*
X114422D01*
X115006Y491230D01*
X115339Y491730D01*
X115506Y492314D01*
X115339Y492897D01*
X114839Y493397D01*
X114256Y493564D01*
X111672D01*
G01X119189Y490897D02*
X118689Y490980D01*
X118189Y491314D01*
X117856Y491897D01*
X117689Y492564D01*
X117856Y493230D01*
X118189Y493814D01*
X118689Y494147D01*
X119189Y494230D01*
X119689Y494147D01*
X120189Y493814D01*
X120522Y493230D01*
X120606Y492564D01*
X120522Y491897D01*
X120189Y491314D01*
X119689Y490980D01*
X119189Y490897D01*
G01X126289D02*
Y494230D01*
G01Y493647D02*
X125956Y493980D01*
X125456Y494147D01*
X124872Y494230D01*
X124289Y494064D01*
X123789Y493730D01*
X123456Y493230D01*
X123289Y492564D01*
X123456Y491897D01*
X123789Y491397D01*
X124289Y491064D01*
X124872Y490897D01*
X125456Y490980D01*
X125956Y491230D01*
X126289Y491564D01*
G01X129222Y490897D02*
Y494230D01*
G01Y493564D02*
X129639Y493897D01*
X130056Y494147D01*
X130639Y494230D01*
X131056Y494147D01*
X131556Y493897D01*
G01X137489Y495897D02*
Y490897D01*
G01Y491647D02*
X137156Y491230D01*
X136656Y490980D01*
X136072Y490897D01*
X135406Y491064D01*
X134906Y491480D01*
X134572Y491980D01*
X134489Y492564D01*
X134572Y493147D01*
X134906Y493647D01*
X135406Y494064D01*
X136072Y494230D01*
X136656Y494147D01*
X137072Y493980D01*
X137489Y493647D01*
G01X140339Y491480D02*
X140756Y491147D01*
X141339Y490897D01*
X141839D01*
X142339Y491064D01*
X142672Y491314D01*
X142839Y491647D01*
X142756Y492147D01*
X142422Y492397D01*
X140922Y492897D01*
X140589Y493480D01*
X140756Y493897D01*
X141089Y494147D01*
X141589Y494230D01*
X142089Y494147D01*
X142589Y493897D01*
G01X-367411Y491730D02*
X-367578Y491814D01*
Y491980D01*
X-367411Y492064D01*
X-367244Y491980D01*
Y491814D01*
X-367411Y491730D01*
G01Y500730D02*
X-367578Y500814D01*
Y500980D01*
X-367411Y501064D01*
X-367244Y500980D01*
Y500814D01*
X-367411Y500730D01*
G01Y509730D02*
X-367578Y509814D01*
Y509980D01*
X-367411Y510064D01*
X-367244Y509980D01*
Y509814D01*
X-367411Y509730D01*
G01X-363411Y504897D02*
X-361411D01*
G01X-362411D02*
Y499897D01*
G01X-363411D02*
X-361411D01*
G01X-358478D02*
Y504897D01*
X-356478D01*
X-355811Y504647D01*
X-355311Y504064D01*
X-355144Y503397D01*
X-355311Y502730D01*
X-355728Y502230D01*
X-356478Y501980D01*
X-358478D01*
G01X-349378Y504480D02*
X-349878Y504730D01*
X-350461Y504897D01*
X-351128D01*
X-351878Y504647D01*
X-352461Y504230D01*
X-352878Y503730D01*
X-353211Y502897D01*
X-353294Y502147D01*
X-353128Y501397D01*
X-352878Y500897D01*
X-352378Y500397D01*
X-351794Y500064D01*
X-351211Y499897D01*
X-350628D01*
X-350044Y500064D01*
X-349544Y500314D01*
X-349128Y500647D01*
G01X-346694Y501564D02*
X-344528D01*
G01X-342178Y499897D02*
Y504897D01*
X-340011Y500730D01*
X-337844Y504897D01*
Y499897D01*
G01X-335994D02*
Y504897D01*
X-332828D01*
G01X-333994Y502480D02*
X-335994D01*
G01X-329894Y501564D02*
X-327728D01*
G01X-323211Y499897D02*
Y504897D01*
X-324211Y503897D01*
G01Y499897D02*
X-322211D01*
G01X-319444Y500647D02*
X-318944Y500230D01*
X-318361Y499980D01*
X-317611Y499897D01*
X-316861Y500064D01*
X-316278Y500397D01*
X-315861Y500980D01*
X-315778Y501647D01*
X-315944Y502314D01*
X-316361Y502730D01*
X-316944Y503064D01*
X-317528Y503147D01*
X-318111Y503064D01*
X-318861Y502730D01*
X-318611Y504897D01*
X-316361D01*
G01X-312011D02*
X-312678Y504730D01*
X-313178Y504314D01*
X-313511Y503814D01*
X-313761Y503147D01*
X-313844Y502397D01*
X-313761Y501647D01*
X-313511Y500980D01*
X-313178Y500480D01*
X-312678Y500064D01*
X-312011Y499897D01*
X-311344Y500064D01*
X-310844Y500480D01*
X-310511Y500980D01*
X-310261Y501647D01*
X-310178Y502397D01*
X-310261Y503147D01*
X-310511Y503814D01*
X-310844Y504314D01*
X-311344Y504730D01*
X-312011Y504897D01*
G01X-302978Y499897D02*
Y504897D01*
X-300811Y500730D01*
X-298644Y504897D01*
Y499897D01*
G01X-296461Y502147D02*
X-293794D01*
X-294044Y502730D01*
X-294461Y503064D01*
X-295044Y503230D01*
X-295628Y503147D01*
X-296128Y502897D01*
X-296461Y502314D01*
X-296628Y501814D01*
Y501314D01*
X-296461Y500814D01*
X-296044Y500314D01*
X-295544Y499980D01*
X-294961Y499897D01*
X-294378Y500064D01*
X-293794Y500564D01*
G01X-289611Y504897D02*
Y499897D01*
G01X-290778Y503230D02*
X-288444D01*
G01X-282511Y499897D02*
Y503230D01*
G01Y502647D02*
X-282844Y502980D01*
X-283344Y503147D01*
X-283928Y503230D01*
X-284511Y503064D01*
X-285011Y502730D01*
X-285344Y502230D01*
X-285511Y501564D01*
X-285344Y500897D01*
X-285011Y500397D01*
X-284511Y500064D01*
X-283928Y499897D01*
X-283344Y499980D01*
X-282844Y500230D01*
X-282511Y500564D01*
G01X-278411Y499897D02*
Y504897D01*
G01X-268794Y499897D02*
Y504897D01*
X-265628D01*
G01X-266794Y502480D02*
X-268794D01*
G01X-261611Y499897D02*
X-262111Y499980D01*
X-262611Y500314D01*
X-262944Y500897D01*
X-263111Y501564D01*
X-262944Y502230D01*
X-262611Y502814D01*
X-262111Y503147D01*
X-261611Y503230D01*
X-261111Y503147D01*
X-260611Y502814D01*
X-260278Y502230D01*
X-260194Y501564D01*
X-260278Y500897D01*
X-260611Y500314D01*
X-261111Y499980D01*
X-261611Y499897D01*
G01X-256011Y503230D02*
Y499897D01*
G01Y504564D02*
X-256178Y504647D01*
Y504814D01*
X-256011Y504897D01*
X-255844Y504814D01*
Y504647D01*
X-256011Y504564D01*
G01X-250411Y499897D02*
Y504897D01*
G01X-239711Y499897D02*
Y504147D01*
X-239544Y504564D01*
X-239211Y504814D01*
X-238711Y504897D01*
X-238211Y504730D01*
X-237961Y504314D01*
G01X-238961Y502897D02*
X-240628D01*
G01X-233611Y499897D02*
X-234111Y499980D01*
X-234611Y500314D01*
X-234944Y500897D01*
X-235111Y501564D01*
X-234944Y502230D01*
X-234611Y502814D01*
X-234111Y503147D01*
X-233611Y503230D01*
X-233111Y503147D01*
X-232611Y502814D01*
X-232278Y502230D01*
X-232194Y501564D01*
X-232278Y500897D01*
X-232611Y500314D01*
X-233111Y499980D01*
X-233611Y499897D01*
G01X-229178D02*
Y503230D01*
G01Y502564D02*
X-228761Y502897D01*
X-228344Y503147D01*
X-227761Y503230D01*
X-227344Y503147D01*
X-226844Y502897D01*
G01X-218478Y499897D02*
Y504897D01*
X-216478D01*
X-215811Y504647D01*
X-215311Y504064D01*
X-215144Y503397D01*
X-215311Y502730D01*
X-215728Y502230D01*
X-216478Y501980D01*
X-218478D01*
G01X-212378Y499897D02*
Y503230D01*
G01Y502564D02*
X-211961Y502897D01*
X-211544Y503147D01*
X-210961Y503230D01*
X-210544Y503147D01*
X-210044Y502897D01*
G01X-205611Y503230D02*
Y499897D01*
G01Y504564D02*
X-205778Y504647D01*
Y504814D01*
X-205611Y504897D01*
X-205444Y504814D01*
Y504647D01*
X-205611Y504564D01*
G01X-201428Y499897D02*
Y503230D01*
G01Y502397D02*
X-201094Y502814D01*
X-200594Y503147D01*
X-199928Y503230D01*
X-199344Y503147D01*
X-198844Y502814D01*
X-198594Y502230D01*
Y499897D01*
G01X-194411Y504897D02*
Y499897D01*
G01X-195578Y503230D02*
X-193244D01*
G01X-190061Y502147D02*
X-187394D01*
X-187644Y502730D01*
X-188061Y503064D01*
X-188644Y503230D01*
X-189228Y503147D01*
X-189728Y502897D01*
X-190061Y502314D01*
X-190228Y501814D01*
Y501314D01*
X-190061Y500814D01*
X-189644Y500314D01*
X-189144Y499980D01*
X-188561Y499897D01*
X-187978Y500064D01*
X-187394Y500564D01*
G01X-181711Y504897D02*
Y499897D01*
G01Y500647D02*
X-182044Y500230D01*
X-182544Y499980D01*
X-183128Y499897D01*
X-183794Y500064D01*
X-184294Y500480D01*
X-184628Y500980D01*
X-184711Y501564D01*
X-184628Y502147D01*
X-184294Y502647D01*
X-183794Y503064D01*
X-183128Y503230D01*
X-182544Y503147D01*
X-182128Y502980D01*
X-181711Y502647D01*
G01X-174511Y504897D02*
X-173344Y499897D01*
X-172011Y504897D01*
X-170678Y499897D01*
X-169511Y504897D01*
G01X-166411Y503230D02*
Y499897D01*
G01Y504564D02*
X-166578Y504647D01*
Y504814D01*
X-166411Y504897D01*
X-166244Y504814D01*
Y504647D01*
X-166411Y504564D01*
G01X-161978Y499897D02*
Y503230D01*
G01Y502564D02*
X-161561Y502897D01*
X-161144Y503147D01*
X-160561Y503230D01*
X-160144Y503147D01*
X-159644Y502897D01*
G01X-155211Y503230D02*
Y499897D01*
G01Y504564D02*
X-155378Y504647D01*
Y504814D01*
X-155211Y504897D01*
X-155044Y504814D01*
Y504647D01*
X-155211Y504564D01*
G01X-151028Y499897D02*
Y503230D01*
G01Y502397D02*
X-150694Y502814D01*
X-150194Y503147D01*
X-149528Y503230D01*
X-148944Y503147D01*
X-148444Y502814D01*
X-148194Y502230D01*
Y499897D01*
G01X-145178Y498647D02*
X-144594Y498314D01*
X-143928Y498230D01*
X-143344Y498314D01*
X-142844Y498730D01*
X-142511Y499314D01*
Y503230D01*
G01Y502564D02*
X-142844Y502897D01*
X-143344Y503147D01*
X-143928Y503230D01*
X-144594Y503064D01*
X-145011Y502730D01*
X-145344Y502147D01*
X-145511Y501564D01*
X-145428Y501064D01*
X-145094Y500480D01*
X-144594Y500064D01*
X-143928Y499897D01*
X-143428Y499980D01*
X-142844Y500314D01*
X-142511Y500647D01*
G01X-134894Y499897D02*
X-132811Y504897D01*
X-130728Y499897D01*
G01X-131478Y501647D02*
X-134144D01*
G01X-128711Y498230D02*
Y503230D01*
G01Y502480D02*
X-128294Y502897D01*
X-127878Y503147D01*
X-127211Y503230D01*
X-126628Y503147D01*
X-126044Y502730D01*
X-125794Y502147D01*
X-125711Y501564D01*
X-125794Y500980D01*
X-126044Y500397D01*
X-126544Y500064D01*
X-127211Y499897D01*
X-127794Y499980D01*
X-128378Y500230D01*
X-128711Y500564D01*
G01X-123111Y498230D02*
Y503230D01*
G01Y502480D02*
X-122694Y502897D01*
X-122278Y503147D01*
X-121611Y503230D01*
X-121028Y503147D01*
X-120444Y502730D01*
X-120194Y502147D01*
X-120111Y501564D01*
X-120194Y500980D01*
X-120444Y500397D01*
X-120944Y500064D01*
X-121611Y499897D01*
X-122194Y499980D01*
X-122778Y500230D01*
X-123111Y500564D01*
G01X-116011Y499897D02*
Y504897D01*
G01X-110411Y503230D02*
Y499897D01*
G01Y504564D02*
X-110578Y504647D01*
Y504814D01*
X-110411Y504897D01*
X-110244Y504814D01*
Y504647D01*
X-110411Y504564D01*
G01X-103478Y502814D02*
X-104061Y503147D01*
X-104561Y503230D01*
X-105228Y503064D01*
X-105728Y502730D01*
X-106061Y502147D01*
X-106144Y501564D01*
X-106061Y500980D01*
X-105728Y500480D01*
X-105228Y500064D01*
X-104561Y499897D01*
X-103978Y500064D01*
X-103478Y500397D01*
G01X-97711Y499897D02*
Y503230D01*
G01Y502647D02*
X-98044Y502980D01*
X-98544Y503147D01*
X-99128Y503230D01*
X-99711Y503064D01*
X-100211Y502730D01*
X-100544Y502230D01*
X-100711Y501564D01*
X-100544Y500897D01*
X-100211Y500397D01*
X-99711Y500064D01*
X-99128Y499897D01*
X-98544Y499980D01*
X-98044Y500230D01*
X-97711Y500564D01*
G01X-93611Y504897D02*
Y499897D01*
G01X-94778Y503230D02*
X-92444D01*
G01X-88011D02*
Y499897D01*
G01Y504564D02*
X-88178Y504647D01*
Y504814D01*
X-88011Y504897D01*
X-87844Y504814D01*
Y504647D01*
X-88011Y504564D01*
G01X-82411Y499897D02*
X-82911Y499980D01*
X-83411Y500314D01*
X-83744Y500897D01*
X-83911Y501564D01*
X-83744Y502230D01*
X-83411Y502814D01*
X-82911Y503147D01*
X-82411Y503230D01*
X-81911Y503147D01*
X-81411Y502814D01*
X-81078Y502230D01*
X-80994Y501564D01*
X-81078Y500897D01*
X-81411Y500314D01*
X-81911Y499980D01*
X-82411Y499897D01*
G01X-78228D02*
Y503230D01*
G01Y502397D02*
X-77894Y502814D01*
X-77394Y503147D01*
X-76728Y503230D01*
X-76144Y503147D01*
X-75644Y502814D01*
X-75394Y502230D01*
Y499897D01*
G01X-72461Y500480D02*
X-72044Y500147D01*
X-71461Y499897D01*
X-70961D01*
X-70461Y500064D01*
X-70128Y500314D01*
X-69961Y500647D01*
X-70044Y501147D01*
X-70378Y501397D01*
X-71878Y501897D01*
X-72211Y502480D01*
X-72044Y502897D01*
X-71711Y503147D01*
X-71211Y503230D01*
X-70711Y503147D01*
X-70211Y502897D01*
G01X-363411Y513897D02*
X-361411D01*
G01X-362411D02*
Y508897D01*
G01X-363411D02*
X-361411D01*
G01X-358478D02*
Y513897D01*
X-356478D01*
X-355811Y513647D01*
X-355311Y513064D01*
X-355144Y512397D01*
X-355311Y511730D01*
X-355728Y511230D01*
X-356478Y510980D01*
X-358478D01*
G01X-349378Y513480D02*
X-349878Y513730D01*
X-350461Y513897D01*
X-351128D01*
X-351878Y513647D01*
X-352461Y513230D01*
X-352878Y512730D01*
X-353211Y511897D01*
X-353294Y511147D01*
X-353128Y510397D01*
X-352878Y509897D01*
X-352378Y509397D01*
X-351794Y509064D01*
X-351211Y508897D01*
X-350628D01*
X-350044Y509064D01*
X-349544Y509314D01*
X-349128Y509647D01*
G01X-346694Y510564D02*
X-344528D01*
G01X-339011Y508897D02*
Y513897D01*
X-342094Y510314D01*
X-337928D01*
G01X-334411Y508897D02*
Y513897D01*
X-335411Y512897D01*
G01Y508897D02*
X-333411D01*
G01X-328811Y513897D02*
X-329478Y513730D01*
X-329978Y513314D01*
X-330311Y512814D01*
X-330561Y512147D01*
X-330644Y511397D01*
X-330561Y510647D01*
X-330311Y509980D01*
X-329978Y509480D01*
X-329478Y509064D01*
X-328811Y508897D01*
X-328144Y509064D01*
X-327644Y509480D01*
X-327311Y509980D01*
X-327061Y510647D01*
X-326978Y511397D01*
X-327061Y512147D01*
X-327311Y512814D01*
X-327644Y513314D01*
X-328144Y513730D01*
X-328811Y513897D01*
G01X-323211Y508897D02*
Y513897D01*
X-324211Y512897D01*
G01Y508897D02*
X-322211D01*
G01X-313761Y509564D02*
X-313094Y509147D01*
X-312344Y508897D01*
X-311678D01*
X-311011Y509147D01*
X-310511Y509564D01*
X-310261Y510147D01*
X-310428Y510730D01*
X-310844Y511230D01*
X-311594Y511564D01*
X-312594Y511730D01*
X-313178Y512064D01*
X-313428Y512647D01*
X-313261Y513230D01*
X-312844Y513647D01*
X-312261Y513897D01*
X-311678D01*
X-311094Y513730D01*
X-310594Y513314D01*
G01X-307911Y507230D02*
Y512230D01*
G01Y511480D02*
X-307494Y511897D01*
X-307078Y512147D01*
X-306411Y512230D01*
X-305828Y512147D01*
X-305244Y511730D01*
X-304994Y511147D01*
X-304911Y510564D01*
X-304994Y509980D01*
X-305244Y509397D01*
X-305744Y509064D01*
X-306411Y508897D01*
X-306994Y508980D01*
X-307578Y509230D01*
X-307911Y509564D01*
G01X-302061Y511147D02*
X-299394D01*
X-299644Y511730D01*
X-300061Y512064D01*
X-300644Y512230D01*
X-301228Y512147D01*
X-301728Y511897D01*
X-302061Y511314D01*
X-302228Y510814D01*
Y510314D01*
X-302061Y509814D01*
X-301644Y509314D01*
X-301144Y508980D01*
X-300561Y508897D01*
X-299978Y509064D01*
X-299394Y509564D01*
G01X-293878Y511814D02*
X-294461Y512147D01*
X-294961Y512230D01*
X-295628Y512064D01*
X-296128Y511730D01*
X-296461Y511147D01*
X-296544Y510564D01*
X-296461Y509980D01*
X-296128Y509480D01*
X-295628Y509064D01*
X-294961Y508897D01*
X-294378Y509064D01*
X-293878Y509397D01*
G01X-289611Y512230D02*
Y508897D01*
G01Y513564D02*
X-289778Y513647D01*
Y513814D01*
X-289611Y513897D01*
X-289444Y513814D01*
Y513647D01*
X-289611Y513564D01*
G01X-284511Y508897D02*
Y513147D01*
X-284344Y513564D01*
X-284011Y513814D01*
X-283511Y513897D01*
X-283011Y513730D01*
X-282761Y513314D01*
G01X-283761Y511897D02*
X-285428D01*
G01X-278411Y512230D02*
Y508897D01*
G01Y513564D02*
X-278578Y513647D01*
Y513814D01*
X-278411Y513897D01*
X-278244Y513814D01*
Y513647D01*
X-278411Y513564D01*
G01X-271478Y511814D02*
X-272061Y512147D01*
X-272561Y512230D01*
X-273228Y512064D01*
X-273728Y511730D01*
X-274061Y511147D01*
X-274144Y510564D01*
X-274061Y509980D01*
X-273728Y509480D01*
X-273228Y509064D01*
X-272561Y508897D01*
X-271978Y509064D01*
X-271478Y509397D01*
G01X-265711Y508897D02*
Y512230D01*
G01Y511647D02*
X-266044Y511980D01*
X-266544Y512147D01*
X-267128Y512230D01*
X-267711Y512064D01*
X-268211Y511730D01*
X-268544Y511230D01*
X-268711Y510564D01*
X-268544Y509897D01*
X-268211Y509397D01*
X-267711Y509064D01*
X-267128Y508897D01*
X-266544Y508980D01*
X-266044Y509230D01*
X-265711Y509564D01*
G01X-261611Y513897D02*
Y508897D01*
G01X-262778Y512230D02*
X-260444D01*
G01X-256011D02*
Y508897D01*
G01Y513564D02*
X-256178Y513647D01*
Y513814D01*
X-256011Y513897D01*
X-255844Y513814D01*
Y513647D01*
X-256011Y513564D01*
G01X-250411Y508897D02*
X-250911Y508980D01*
X-251411Y509314D01*
X-251744Y509897D01*
X-251911Y510564D01*
X-251744Y511230D01*
X-251411Y511814D01*
X-250911Y512147D01*
X-250411Y512230D01*
X-249911Y512147D01*
X-249411Y511814D01*
X-249078Y511230D01*
X-248994Y510564D01*
X-249078Y509897D01*
X-249411Y509314D01*
X-249911Y508980D01*
X-250411Y508897D01*
G01X-246228D02*
Y512230D01*
G01Y511397D02*
X-245894Y511814D01*
X-245394Y512147D01*
X-244728Y512230D01*
X-244144Y512147D01*
X-243644Y511814D01*
X-243394Y511230D01*
Y508897D01*
G01X-234111D02*
Y513147D01*
X-233944Y513564D01*
X-233611Y513814D01*
X-233111Y513897D01*
X-232611Y513730D01*
X-232361Y513314D01*
G01X-233361Y511897D02*
X-235028D01*
G01X-228011Y508897D02*
X-228511Y508980D01*
X-229011Y509314D01*
X-229344Y509897D01*
X-229511Y510564D01*
X-229344Y511230D01*
X-229011Y511814D01*
X-228511Y512147D01*
X-228011Y512230D01*
X-227511Y512147D01*
X-227011Y511814D01*
X-226678Y511230D01*
X-226594Y510564D01*
X-226678Y509897D01*
X-227011Y509314D01*
X-227511Y508980D01*
X-228011Y508897D01*
G01X-223578D02*
Y512230D01*
G01Y511564D02*
X-223161Y511897D01*
X-222744Y512147D01*
X-222161Y512230D01*
X-221744Y512147D01*
X-221244Y511897D01*
G01X-210544Y511564D02*
X-210211Y511814D01*
X-209961Y512230D01*
X-209794Y512814D01*
X-209961Y513314D01*
X-210294Y513647D01*
X-210878Y513897D01*
X-213128D01*
Y508897D01*
X-210378D01*
X-209794Y509230D01*
X-209461Y509730D01*
X-209294Y510314D01*
X-209461Y510897D01*
X-209961Y511397D01*
X-210544Y511564D01*
X-213128D01*
G01X-204111Y508897D02*
Y512230D01*
G01Y511647D02*
X-204444Y511980D01*
X-204944Y512147D01*
X-205528Y512230D01*
X-206111Y512064D01*
X-206611Y511730D01*
X-206944Y511230D01*
X-207111Y510564D01*
X-206944Y509897D01*
X-206611Y509397D01*
X-206111Y509064D01*
X-205528Y508897D01*
X-204944Y508980D01*
X-204444Y509230D01*
X-204111Y509564D01*
G01X-201261Y509480D02*
X-200844Y509147D01*
X-200261Y508897D01*
X-199761D01*
X-199261Y509064D01*
X-198928Y509314D01*
X-198761Y509647D01*
X-198844Y510147D01*
X-199178Y510397D01*
X-200678Y510897D01*
X-201011Y511480D01*
X-200844Y511897D01*
X-200511Y512147D01*
X-200011Y512230D01*
X-199511Y512147D01*
X-199011Y511897D01*
G01X-195661Y511147D02*
X-192994D01*
X-193244Y511730D01*
X-193661Y512064D01*
X-194244Y512230D01*
X-194828Y512147D01*
X-195328Y511897D01*
X-195661Y511314D01*
X-195828Y510814D01*
Y510314D01*
X-195661Y509814D01*
X-195244Y509314D01*
X-194744Y508980D01*
X-194161Y508897D01*
X-193578Y509064D01*
X-192994Y509564D01*
G01X-185378Y508897D02*
Y513897D01*
X-183211Y509730D01*
X-181044Y513897D01*
Y508897D01*
G01X-176111D02*
Y512230D01*
G01Y511647D02*
X-176444Y511980D01*
X-176944Y512147D01*
X-177528Y512230D01*
X-178111Y512064D01*
X-178611Y511730D01*
X-178944Y511230D01*
X-179111Y510564D01*
X-178944Y509897D01*
X-178611Y509397D01*
X-178111Y509064D01*
X-177528Y508897D01*
X-176944Y508980D01*
X-176444Y509230D01*
X-176111Y509564D01*
G01X-172011Y513897D02*
Y508897D01*
G01X-173178Y512230D02*
X-170844D01*
G01X-167661Y511147D02*
X-164994D01*
X-165244Y511730D01*
X-165661Y512064D01*
X-166244Y512230D01*
X-166828Y512147D01*
X-167328Y511897D01*
X-167661Y511314D01*
X-167828Y510814D01*
Y510314D01*
X-167661Y509814D01*
X-167244Y509314D01*
X-166744Y508980D01*
X-166161Y508897D01*
X-165578Y509064D01*
X-164994Y509564D01*
G01X-161978Y508897D02*
Y512230D01*
G01Y511564D02*
X-161561Y511897D01*
X-161144Y512147D01*
X-160561Y512230D01*
X-160144Y512147D01*
X-159644Y511897D01*
G01X-155211Y512230D02*
Y508897D01*
G01Y513564D02*
X-155378Y513647D01*
Y513814D01*
X-155211Y513897D01*
X-155044Y513814D01*
Y513647D01*
X-155211Y513564D01*
G01X-148111Y508897D02*
Y512230D01*
G01Y511647D02*
X-148444Y511980D01*
X-148944Y512147D01*
X-149528Y512230D01*
X-150111Y512064D01*
X-150611Y511730D01*
X-150944Y511230D01*
X-151111Y510564D01*
X-150944Y509897D01*
X-150611Y509397D01*
X-150111Y509064D01*
X-149528Y508897D01*
X-148944Y508980D01*
X-148444Y509230D01*
X-148111Y509564D01*
G01X-144011Y508897D02*
Y513897D01*
G01X-139661Y509480D02*
X-139244Y509147D01*
X-138661Y508897D01*
X-138161D01*
X-137661Y509064D01*
X-137328Y509314D01*
X-137161Y509647D01*
X-137244Y510147D01*
X-137578Y510397D01*
X-139078Y510897D01*
X-139411Y511480D01*
X-139244Y511897D01*
X-138911Y512147D01*
X-138411Y512230D01*
X-137911Y512147D01*
X-137411Y511897D01*
G01X-127711Y508897D02*
Y513147D01*
X-127544Y513564D01*
X-127211Y513814D01*
X-126711Y513897D01*
X-126211Y513730D01*
X-125961Y513314D01*
G01X-126961Y511897D02*
X-128628D01*
G01X-121611Y508897D02*
X-122111Y508980D01*
X-122611Y509314D01*
X-122944Y509897D01*
X-123111Y510564D01*
X-122944Y511230D01*
X-122611Y511814D01*
X-122111Y512147D01*
X-121611Y512230D01*
X-121111Y512147D01*
X-120611Y511814D01*
X-120278Y511230D01*
X-120194Y510564D01*
X-120278Y509897D01*
X-120611Y509314D01*
X-121111Y508980D01*
X-121611Y508897D01*
G01X-117178D02*
Y512230D01*
G01Y511564D02*
X-116761Y511897D01*
X-116344Y512147D01*
X-115761Y512230D01*
X-115344Y512147D01*
X-114844Y511897D01*
G01X-106478Y508897D02*
Y513897D01*
X-104394D01*
X-103728Y513647D01*
X-103311Y513314D01*
X-103144Y512647D01*
X-103311Y511980D01*
X-103811Y511564D01*
X-104394Y511314D01*
X-106478D01*
G01X-104394D02*
X-103144Y508897D01*
G01X-99211Y512230D02*
Y508897D01*
G01Y513564D02*
X-99378Y513647D01*
Y513814D01*
X-99211Y513897D01*
X-99044Y513814D01*
Y513647D01*
X-99211Y513564D01*
G01X-94778Y507647D02*
X-94194Y507314D01*
X-93528Y507230D01*
X-92944Y507314D01*
X-92444Y507730D01*
X-92111Y508314D01*
Y512230D01*
G01Y511564D02*
X-92444Y511897D01*
X-92944Y512147D01*
X-93528Y512230D01*
X-94194Y512064D01*
X-94611Y511730D01*
X-94944Y511147D01*
X-95111Y510564D01*
X-95028Y510064D01*
X-94694Y509480D01*
X-94194Y509064D01*
X-93528Y508897D01*
X-93028Y508980D01*
X-92444Y509314D01*
X-92111Y509647D01*
G01X-88011Y512230D02*
Y508897D01*
G01Y513564D02*
X-88178Y513647D01*
Y513814D01*
X-88011Y513897D01*
X-87844Y513814D01*
Y513647D01*
X-88011Y513564D01*
G01X-80911Y513897D02*
Y508897D01*
G01Y509647D02*
X-81244Y509230D01*
X-81744Y508980D01*
X-82328Y508897D01*
X-82994Y509064D01*
X-83494Y509480D01*
X-83828Y509980D01*
X-83911Y510564D01*
X-83828Y511147D01*
X-83494Y511647D01*
X-82994Y512064D01*
X-82328Y512230D01*
X-81744Y512147D01*
X-81328Y511980D01*
X-80911Y511647D01*
G01X-69711Y508897D02*
Y512230D01*
G01Y511647D02*
X-70044Y511980D01*
X-70544Y512147D01*
X-71128Y512230D01*
X-71711Y512064D01*
X-72211Y511730D01*
X-72544Y511230D01*
X-72711Y510564D01*
X-72544Y509897D01*
X-72211Y509397D01*
X-71711Y509064D01*
X-71128Y508897D01*
X-70544Y508980D01*
X-70044Y509230D01*
X-69711Y509564D01*
G01X-67028Y508897D02*
Y512230D01*
G01Y511397D02*
X-66694Y511814D01*
X-66194Y512147D01*
X-65528Y512230D01*
X-64944Y512147D01*
X-64444Y511814D01*
X-64194Y511230D01*
Y508897D01*
G01X-58511Y513897D02*
Y508897D01*
G01Y509647D02*
X-58844Y509230D01*
X-59344Y508980D01*
X-59928Y508897D01*
X-60594Y509064D01*
X-61094Y509480D01*
X-61428Y509980D01*
X-61511Y510564D01*
X-61428Y511147D01*
X-61094Y511647D01*
X-60594Y512064D01*
X-59928Y512230D01*
X-59344Y512147D01*
X-58928Y511980D01*
X-58511Y511647D01*
G01X-50978Y508897D02*
Y513897D01*
X-48811Y509730D01*
X-46644Y513897D01*
Y508897D01*
G01X-44628Y512230D02*
Y509897D01*
X-44294Y509314D01*
X-43794Y508980D01*
X-43211Y508897D01*
X-42628Y508980D01*
X-42128Y509314D01*
X-41794Y509897D01*
G01Y508897D02*
Y512230D01*
G01X-37611Y508897D02*
Y513897D01*
G01X-32011D02*
Y508897D01*
G01X-33178Y512230D02*
X-30844D01*
G01X-26411D02*
Y508897D01*
G01Y513564D02*
X-26578Y513647D01*
Y513814D01*
X-26411Y513897D01*
X-26244Y513814D01*
Y513647D01*
X-26411Y513564D01*
G01X-20811Y508897D02*
Y513897D01*
G01X-13711Y508897D02*
Y512230D01*
G01Y511647D02*
X-14044Y511980D01*
X-14544Y512147D01*
X-15128Y512230D01*
X-15711Y512064D01*
X-16211Y511730D01*
X-16544Y511230D01*
X-16711Y510564D01*
X-16544Y509897D01*
X-16211Y509397D01*
X-15711Y509064D01*
X-15128Y508897D01*
X-14544Y508980D01*
X-14044Y509230D01*
X-13711Y509564D01*
G01X-11361Y507397D02*
X-10861Y507230D01*
X-10194Y507397D01*
X-9778Y507730D01*
X-9444Y508147D01*
X-8944Y509480D01*
X-7861Y512230D01*
G01X-10528D02*
X-8944Y509480D01*
G01X-5261Y511147D02*
X-2594D01*
X-2844Y511730D01*
X-3261Y512064D01*
X-3844Y512230D01*
X-4428Y512147D01*
X-4928Y511897D01*
X-5261Y511314D01*
X-5428Y510814D01*
Y510314D01*
X-5261Y509814D01*
X-4844Y509314D01*
X-4344Y508980D01*
X-3761Y508897D01*
X-3178Y509064D01*
X-2594Y509564D01*
G01X422Y508897D02*
Y512230D01*
G01Y511564D02*
X839Y511897D01*
X1256Y512147D01*
X1839Y512230D01*
X2256Y512147D01*
X2756Y511897D01*
G01X11122Y508897D02*
Y513897D01*
X13122D01*
X13789Y513647D01*
X14289Y513064D01*
X14456Y512397D01*
X14289Y511730D01*
X13872Y511230D01*
X13122Y510980D01*
X11122D01*
G01X17222Y508897D02*
Y512230D01*
G01Y511564D02*
X17639Y511897D01*
X18056Y512147D01*
X18639Y512230D01*
X19056Y512147D01*
X19556Y511897D01*
G01X23989Y512230D02*
Y508897D01*
G01Y513564D02*
X23822Y513647D01*
Y513814D01*
X23989Y513897D01*
X24156Y513814D01*
Y513647D01*
X23989Y513564D01*
G01X28172Y508897D02*
Y512230D01*
G01Y511397D02*
X28506Y511814D01*
X29006Y512147D01*
X29672Y512230D01*
X30256Y512147D01*
X30756Y511814D01*
X31006Y511230D01*
Y508897D01*
G01X35189Y513897D02*
Y508897D01*
G01X34022Y512230D02*
X36356D01*
G01X39539Y511147D02*
X42206D01*
X41956Y511730D01*
X41539Y512064D01*
X40956Y512230D01*
X40372Y512147D01*
X39872Y511897D01*
X39539Y511314D01*
X39372Y510814D01*
Y510314D01*
X39539Y509814D01*
X39956Y509314D01*
X40456Y508980D01*
X41039Y508897D01*
X41622Y509064D01*
X42206Y509564D01*
G01X47889Y513897D02*
Y508897D01*
G01Y509647D02*
X47556Y509230D01*
X47056Y508980D01*
X46472Y508897D01*
X45806Y509064D01*
X45306Y509480D01*
X44972Y509980D01*
X44889Y510564D01*
X44972Y511147D01*
X45306Y511647D01*
X45806Y512064D01*
X46472Y512230D01*
X47056Y512147D01*
X47472Y511980D01*
X47889Y511647D01*
G01X58256Y511564D02*
X58589Y511814D01*
X58839Y512230D01*
X59006Y512814D01*
X58839Y513314D01*
X58506Y513647D01*
X57922Y513897D01*
X55672D01*
Y508897D01*
X58422D01*
X59006Y509230D01*
X59339Y509730D01*
X59506Y510314D01*
X59339Y510897D01*
X58839Y511397D01*
X58256Y511564D01*
X55672D01*
G01X63189Y508897D02*
X62689Y508980D01*
X62189Y509314D01*
X61856Y509897D01*
X61689Y510564D01*
X61856Y511230D01*
X62189Y511814D01*
X62689Y512147D01*
X63189Y512230D01*
X63689Y512147D01*
X64189Y511814D01*
X64522Y511230D01*
X64606Y510564D01*
X64522Y509897D01*
X64189Y509314D01*
X63689Y508980D01*
X63189Y508897D01*
G01X70289D02*
Y512230D01*
G01Y511647D02*
X69956Y511980D01*
X69456Y512147D01*
X68872Y512230D01*
X68289Y512064D01*
X67789Y511730D01*
X67456Y511230D01*
X67289Y510564D01*
X67456Y509897D01*
X67789Y509397D01*
X68289Y509064D01*
X68872Y508897D01*
X69456Y508980D01*
X69956Y509230D01*
X70289Y509564D01*
G01X73222Y508897D02*
Y512230D01*
G01Y511564D02*
X73639Y511897D01*
X74056Y512147D01*
X74639Y512230D01*
X75056Y512147D01*
X75556Y511897D01*
G01X81489Y513897D02*
Y508897D01*
G01Y509647D02*
X81156Y509230D01*
X80656Y508980D01*
X80072Y508897D01*
X79406Y509064D01*
X78906Y509480D01*
X78572Y509980D01*
X78489Y510564D01*
X78572Y511147D01*
X78906Y511647D01*
X79406Y512064D01*
X80072Y512230D01*
X80656Y512147D01*
X81072Y511980D01*
X81489Y511647D01*
G01X84339Y509480D02*
X84756Y509147D01*
X85339Y508897D01*
X85839D01*
X86339Y509064D01*
X86672Y509314D01*
X86839Y509647D01*
X86756Y510147D01*
X86422Y510397D01*
X84922Y510897D01*
X84589Y511480D01*
X84756Y511897D01*
X85089Y512147D01*
X85589Y512230D01*
X86089Y512147D01*
X86589Y511897D01*
G01X-367411Y518730D02*
X-367578Y518814D01*
Y518980D01*
X-367411Y519064D01*
X-367244Y518980D01*
Y518814D01*
X-367411Y518730D01*
G01Y527730D02*
X-367578Y527814D01*
Y527980D01*
X-367411Y528064D01*
X-367244Y527980D01*
Y527814D01*
X-367411Y527730D01*
G01X-363411Y522897D02*
X-361411D01*
G01X-362411D02*
Y517897D01*
G01X-363411D02*
X-361411D01*
G01X-358478D02*
Y522897D01*
X-356478D01*
X-355811Y522647D01*
X-355311Y522064D01*
X-355144Y521397D01*
X-355311Y520730D01*
X-355728Y520230D01*
X-356478Y519980D01*
X-358478D01*
G01X-349378Y522480D02*
X-349878Y522730D01*
X-350461Y522897D01*
X-351128D01*
X-351878Y522647D01*
X-352461Y522230D01*
X-352878Y521730D01*
X-353211Y520897D01*
X-353294Y520147D01*
X-353128Y519397D01*
X-352878Y518897D01*
X-352378Y518397D01*
X-351794Y518064D01*
X-351211Y517897D01*
X-350628D01*
X-350044Y518064D01*
X-349544Y518314D01*
X-349128Y518647D01*
G01X-346694Y519564D02*
X-344528D01*
G01X-340011Y522897D02*
Y517897D01*
G01X-341928Y522897D02*
X-338094D01*
G01X-336578Y517897D02*
Y522897D01*
X-334411Y518730D01*
X-332244Y522897D01*
Y517897D01*
G01X-329894Y519564D02*
X-327728D01*
G01X-324794Y519980D02*
X-324211Y520564D01*
X-323711Y520897D01*
X-323044Y521064D01*
X-322461Y520897D01*
X-322044Y520564D01*
X-321711Y520064D01*
X-321628Y519480D01*
X-321711Y518980D01*
X-322044Y518480D01*
X-322544Y518064D01*
X-323128Y517897D01*
X-323794Y518064D01*
X-324378Y518564D01*
X-324711Y519314D01*
X-324794Y520147D01*
X-324628Y521230D01*
X-324378Y521814D01*
X-323961Y522397D01*
X-323378Y522814D01*
X-322794Y522897D01*
X-322211Y522730D01*
X-321794Y522314D01*
G01X-319444Y518647D02*
X-318944Y518230D01*
X-318361Y517980D01*
X-317611Y517897D01*
X-316861Y518064D01*
X-316278Y518397D01*
X-315861Y518980D01*
X-315778Y519647D01*
X-315944Y520314D01*
X-316361Y520730D01*
X-316944Y521064D01*
X-317528Y521147D01*
X-318111Y521064D01*
X-318861Y520730D01*
X-318611Y522897D01*
X-316361D01*
G01X-312011D02*
X-312678Y522730D01*
X-313178Y522314D01*
X-313511Y521814D01*
X-313761Y521147D01*
X-313844Y520397D01*
X-313761Y519647D01*
X-313511Y518980D01*
X-313178Y518480D01*
X-312678Y518064D01*
X-312011Y517897D01*
X-311344Y518064D01*
X-310844Y518480D01*
X-310511Y518980D01*
X-310261Y519647D01*
X-310178Y520397D01*
X-310261Y521147D01*
X-310511Y521814D01*
X-310844Y522314D01*
X-311344Y522730D01*
X-312011Y522897D01*
G01X-300811D02*
Y517897D01*
G01X-302728Y522897D02*
X-298894D01*
G01X-296461Y520147D02*
X-293794D01*
X-294044Y520730D01*
X-294461Y521064D01*
X-295044Y521230D01*
X-295628Y521147D01*
X-296128Y520897D01*
X-296461Y520314D01*
X-296628Y519814D01*
Y519314D01*
X-296461Y518814D01*
X-296044Y518314D01*
X-295544Y517980D01*
X-294961Y517897D01*
X-294378Y518064D01*
X-293794Y518564D01*
G01X-290861Y518480D02*
X-290444Y518147D01*
X-289861Y517897D01*
X-289361D01*
X-288861Y518064D01*
X-288528Y518314D01*
X-288361Y518647D01*
X-288444Y519147D01*
X-288778Y519397D01*
X-290278Y519897D01*
X-290611Y520480D01*
X-290444Y520897D01*
X-290111Y521147D01*
X-289611Y521230D01*
X-289111Y521147D01*
X-288611Y520897D01*
G01X-284011Y522897D02*
Y517897D01*
G01X-285178Y521230D02*
X-282844D01*
G01X-274978Y517897D02*
Y522897D01*
X-272811Y518730D01*
X-270644Y522897D01*
Y517897D01*
G01X-268461Y520147D02*
X-265794D01*
X-266044Y520730D01*
X-266461Y521064D01*
X-267044Y521230D01*
X-267628Y521147D01*
X-268128Y520897D01*
X-268461Y520314D01*
X-268628Y519814D01*
Y519314D01*
X-268461Y518814D01*
X-268044Y518314D01*
X-267544Y517980D01*
X-266961Y517897D01*
X-266378Y518064D01*
X-265794Y518564D01*
G01X-261611Y522897D02*
Y517897D01*
G01X-262778Y521230D02*
X-260444D01*
G01X-257428Y517897D02*
Y522897D01*
G01Y520480D02*
X-257011Y520897D01*
X-256594Y521147D01*
X-255928Y521230D01*
X-255428Y521147D01*
X-254844Y520814D01*
X-254594Y520314D01*
Y517897D01*
G01X-250411D02*
X-250911Y517980D01*
X-251411Y518314D01*
X-251744Y518897D01*
X-251911Y519564D01*
X-251744Y520230D01*
X-251411Y520814D01*
X-250911Y521147D01*
X-250411Y521230D01*
X-249911Y521147D01*
X-249411Y520814D01*
X-249078Y520230D01*
X-248994Y519564D01*
X-249078Y518897D01*
X-249411Y518314D01*
X-249911Y517980D01*
X-250411Y517897D01*
G01X-243311Y522897D02*
Y517897D01*
G01Y518647D02*
X-243644Y518230D01*
X-244144Y517980D01*
X-244728Y517897D01*
X-245394Y518064D01*
X-245894Y518480D01*
X-246228Y518980D01*
X-246311Y519564D01*
X-246228Y520147D01*
X-245894Y520647D01*
X-245394Y521064D01*
X-244728Y521230D01*
X-244144Y521147D01*
X-243728Y520980D01*
X-243311Y520647D01*
G01X-240461Y518480D02*
X-240044Y518147D01*
X-239461Y517897D01*
X-238961D01*
X-238461Y518064D01*
X-238128Y518314D01*
X-237961Y518647D01*
X-238044Y519147D01*
X-238378Y519397D01*
X-239878Y519897D01*
X-240211Y520480D01*
X-240044Y520897D01*
X-239711Y521147D01*
X-239211Y521230D01*
X-238711Y521147D01*
X-238211Y520897D01*
G01X-230178Y517897D02*
Y522897D01*
X-228011Y518730D01*
X-225844Y522897D01*
Y517897D01*
G01X-220911D02*
Y521230D01*
G01Y520647D02*
X-221244Y520980D01*
X-221744Y521147D01*
X-222328Y521230D01*
X-222911Y521064D01*
X-223411Y520730D01*
X-223744Y520230D01*
X-223911Y519564D01*
X-223744Y518897D01*
X-223411Y518397D01*
X-222911Y518064D01*
X-222328Y517897D01*
X-221744Y517980D01*
X-221244Y518230D01*
X-220911Y518564D01*
G01X-218228Y517897D02*
Y521230D01*
G01Y520397D02*
X-217894Y520814D01*
X-217394Y521147D01*
X-216728Y521230D01*
X-216144Y521147D01*
X-215644Y520814D01*
X-215394Y520230D01*
Y517897D01*
G01X-212628Y521230D02*
Y518897D01*
X-212294Y518314D01*
X-211794Y517980D01*
X-211211Y517897D01*
X-210628Y517980D01*
X-210128Y518314D01*
X-209794Y518897D01*
G01Y517897D02*
Y521230D01*
G01X-204111Y517897D02*
Y521230D01*
G01Y520647D02*
X-204444Y520980D01*
X-204944Y521147D01*
X-205528Y521230D01*
X-206111Y521064D01*
X-206611Y520730D01*
X-206944Y520230D01*
X-207111Y519564D01*
X-206944Y518897D01*
X-206611Y518397D01*
X-206111Y518064D01*
X-205528Y517897D01*
X-204944Y517980D01*
X-204444Y518230D01*
X-204111Y518564D01*
G01X-200011Y517897D02*
Y522897D01*
G01X-363411Y531897D02*
X-361411D01*
G01X-362411D02*
Y526897D01*
G01X-363411D02*
X-361411D01*
G01X-358478D02*
Y531897D01*
X-356478D01*
X-355811Y531647D01*
X-355311Y531064D01*
X-355144Y530397D01*
X-355311Y529730D01*
X-355728Y529230D01*
X-356478Y528980D01*
X-358478D01*
G01X-349378Y531480D02*
X-349878Y531730D01*
X-350461Y531897D01*
X-351128D01*
X-351878Y531647D01*
X-352461Y531230D01*
X-352878Y530730D01*
X-353211Y529897D01*
X-353294Y529147D01*
X-353128Y528397D01*
X-352878Y527897D01*
X-352378Y527397D01*
X-351794Y527064D01*
X-351211Y526897D01*
X-350628D01*
X-350044Y527064D01*
X-349544Y527314D01*
X-349128Y527647D01*
G01X-346694Y528564D02*
X-344528D01*
G01X-341594Y528980D02*
X-341011Y529564D01*
X-340511Y529897D01*
X-339844Y530064D01*
X-339261Y529897D01*
X-338844Y529564D01*
X-338511Y529064D01*
X-338428Y528480D01*
X-338511Y527980D01*
X-338844Y527480D01*
X-339344Y527064D01*
X-339928Y526897D01*
X-340594Y527064D01*
X-341178Y527564D01*
X-341511Y528314D01*
X-341594Y529147D01*
X-341428Y530230D01*
X-341178Y530814D01*
X-340761Y531397D01*
X-340178Y531814D01*
X-339594Y531897D01*
X-339011Y531730D01*
X-338594Y531314D01*
G01X-334411Y531897D02*
X-335078Y531730D01*
X-335578Y531314D01*
X-335911Y530814D01*
X-336161Y530147D01*
X-336244Y529397D01*
X-336161Y528647D01*
X-335911Y527980D01*
X-335578Y527480D01*
X-335078Y527064D01*
X-334411Y526897D01*
X-333744Y527064D01*
X-333244Y527480D01*
X-332911Y527980D01*
X-332661Y528647D01*
X-332578Y529397D01*
X-332661Y530147D01*
X-332911Y530814D01*
X-333244Y531314D01*
X-333744Y531730D01*
X-334411Y531897D01*
G01X-328811Y526897D02*
Y531897D01*
X-329811Y530897D01*
G01Y526897D02*
X-327811D01*
G01X-324794Y528980D02*
X-324211Y529564D01*
X-323711Y529897D01*
X-323044Y530064D01*
X-322461Y529897D01*
X-322044Y529564D01*
X-321711Y529064D01*
X-321628Y528480D01*
X-321711Y527980D01*
X-322044Y527480D01*
X-322544Y527064D01*
X-323128Y526897D01*
X-323794Y527064D01*
X-324378Y527564D01*
X-324711Y528314D01*
X-324794Y529147D01*
X-324628Y530230D01*
X-324378Y530814D01*
X-323961Y531397D01*
X-323378Y531814D01*
X-322794Y531897D01*
X-322211Y531730D01*
X-321794Y531314D01*
G01X-312011Y526897D02*
X-312678Y526980D01*
X-313261Y527314D01*
X-313761Y527814D01*
X-314094Y528397D01*
X-314261Y529064D01*
Y529730D01*
X-314094Y530397D01*
X-313761Y530980D01*
X-313261Y531480D01*
X-312678Y531814D01*
X-312011Y531897D01*
X-311344Y531814D01*
X-310761Y531480D01*
X-310261Y530980D01*
X-309928Y530397D01*
X-309761Y529730D01*
Y529064D01*
X-309928Y528397D01*
X-310261Y527814D01*
X-310761Y527314D01*
X-311344Y526980D01*
X-312011Y526897D01*
G01X-311344Y528230D02*
X-310344Y526897D01*
G01X-307828Y530230D02*
Y527897D01*
X-307494Y527314D01*
X-306994Y526980D01*
X-306411Y526897D01*
X-305828Y526980D01*
X-305328Y527314D01*
X-304994Y527897D01*
G01Y526897D02*
Y530230D01*
G01X-299311Y526897D02*
Y530230D01*
G01Y529647D02*
X-299644Y529980D01*
X-300144Y530147D01*
X-300728Y530230D01*
X-301311Y530064D01*
X-301811Y529730D01*
X-302144Y529230D01*
X-302311Y528564D01*
X-302144Y527897D01*
X-301811Y527397D01*
X-301311Y527064D01*
X-300728Y526897D01*
X-300144Y526980D01*
X-299644Y527230D01*
X-299311Y527564D01*
G01X-295211Y526897D02*
Y531897D01*
G01X-289611Y530230D02*
Y526897D01*
G01Y531564D02*
X-289778Y531647D01*
Y531814D01*
X-289611Y531897D01*
X-289444Y531814D01*
Y531647D01*
X-289611Y531564D01*
G01X-284511Y526897D02*
Y531147D01*
X-284344Y531564D01*
X-284011Y531814D01*
X-283511Y531897D01*
X-283011Y531730D01*
X-282761Y531314D01*
G01X-283761Y529897D02*
X-285428D01*
G01X-278411Y530230D02*
Y526897D01*
G01Y531564D02*
X-278578Y531647D01*
Y531814D01*
X-278411Y531897D01*
X-278244Y531814D01*
Y531647D01*
X-278411Y531564D01*
G01X-271478Y529814D02*
X-272061Y530147D01*
X-272561Y530230D01*
X-273228Y530064D01*
X-273728Y529730D01*
X-274061Y529147D01*
X-274144Y528564D01*
X-274061Y527980D01*
X-273728Y527480D01*
X-273228Y527064D01*
X-272561Y526897D01*
X-271978Y527064D01*
X-271478Y527397D01*
G01X-265711Y526897D02*
Y530230D01*
G01Y529647D02*
X-266044Y529980D01*
X-266544Y530147D01*
X-267128Y530230D01*
X-267711Y530064D01*
X-268211Y529730D01*
X-268544Y529230D01*
X-268711Y528564D01*
X-268544Y527897D01*
X-268211Y527397D01*
X-267711Y527064D01*
X-267128Y526897D01*
X-266544Y526980D01*
X-266044Y527230D01*
X-265711Y527564D01*
G01X-261611Y531897D02*
Y526897D01*
G01X-262778Y530230D02*
X-260444D01*
G01X-256011D02*
Y526897D01*
G01Y531564D02*
X-256178Y531647D01*
Y531814D01*
X-256011Y531897D01*
X-255844Y531814D01*
Y531647D01*
X-256011Y531564D01*
G01X-250411Y526897D02*
X-250911Y526980D01*
X-251411Y527314D01*
X-251744Y527897D01*
X-251911Y528564D01*
X-251744Y529230D01*
X-251411Y529814D01*
X-250911Y530147D01*
X-250411Y530230D01*
X-249911Y530147D01*
X-249411Y529814D01*
X-249078Y529230D01*
X-248994Y528564D01*
X-249078Y527897D01*
X-249411Y527314D01*
X-249911Y526980D01*
X-250411Y526897D01*
G01X-246228D02*
Y530230D01*
G01Y529397D02*
X-245894Y529814D01*
X-245394Y530147D01*
X-244728Y530230D01*
X-244144Y530147D01*
X-243644Y529814D01*
X-243394Y529230D01*
Y526897D01*
G01X-231111Y525230D02*
X-235278Y530230D01*
Y531064D01*
X-234444Y531897D01*
X-233611D01*
X-232778Y531064D01*
Y530230D01*
X-233611Y529397D01*
X-235278Y528564D01*
X-236111Y527730D01*
Y526064D01*
X-235278Y525230D01*
X-232778D01*
X-231111Y526897D01*
G01X-224078D02*
Y531897D01*
X-222078D01*
X-221411Y531647D01*
X-220911Y531064D01*
X-220744Y530397D01*
X-220911Y529730D01*
X-221328Y529230D01*
X-222078Y528980D01*
X-224078D01*
G01X-218061Y529147D02*
X-215394D01*
X-215644Y529730D01*
X-216061Y530064D01*
X-216644Y530230D01*
X-217228Y530147D01*
X-217728Y529897D01*
X-218061Y529314D01*
X-218228Y528814D01*
Y528314D01*
X-218061Y527814D01*
X-217644Y527314D01*
X-217144Y526980D01*
X-216561Y526897D01*
X-215978Y527064D01*
X-215394Y527564D01*
G01X-212378Y526897D02*
Y530230D01*
G01Y529564D02*
X-211961Y529897D01*
X-211544Y530147D01*
X-210961Y530230D01*
X-210544Y530147D01*
X-210044Y529897D01*
G01X-206111Y526897D02*
Y531147D01*
X-205944Y531564D01*
X-205611Y531814D01*
X-205111Y531897D01*
X-204611Y531730D01*
X-204361Y531314D01*
G01X-205361Y529897D02*
X-207028D01*
G01X-200011Y526897D02*
X-200511Y526980D01*
X-201011Y527314D01*
X-201344Y527897D01*
X-201511Y528564D01*
X-201344Y529230D01*
X-201011Y529814D01*
X-200511Y530147D01*
X-200011Y530230D01*
X-199511Y530147D01*
X-199011Y529814D01*
X-198678Y529230D01*
X-198594Y528564D01*
X-198678Y527897D01*
X-199011Y527314D01*
X-199511Y526980D01*
X-200011Y526897D01*
G01X-195578D02*
Y530230D01*
G01Y529564D02*
X-195161Y529897D01*
X-194744Y530147D01*
X-194161Y530230D01*
X-193744Y530147D01*
X-193244Y529897D01*
G01X-191311Y526897D02*
Y530230D01*
G01Y529314D02*
X-191061Y529730D01*
X-190644Y530064D01*
X-190061Y530230D01*
X-189478Y530064D01*
X-189061Y529730D01*
X-188811Y529314D01*
Y526897D01*
G01Y529314D02*
X-188561Y529730D01*
X-188144Y530064D01*
X-187561Y530230D01*
X-186978Y530064D01*
X-186561Y529730D01*
X-186311Y529230D01*
Y526897D01*
G01X-181711D02*
Y530230D01*
G01Y529647D02*
X-182044Y529980D01*
X-182544Y530147D01*
X-183128Y530230D01*
X-183711Y530064D01*
X-184211Y529730D01*
X-184544Y529230D01*
X-184711Y528564D01*
X-184544Y527897D01*
X-184211Y527397D01*
X-183711Y527064D01*
X-183128Y526897D01*
X-182544Y526980D01*
X-182044Y527230D01*
X-181711Y527564D01*
G01X-179028Y526897D02*
Y530230D01*
G01Y529397D02*
X-178694Y529814D01*
X-178194Y530147D01*
X-177528Y530230D01*
X-176944Y530147D01*
X-176444Y529814D01*
X-176194Y529230D01*
Y526897D01*
G01X-170678Y529814D02*
X-171261Y530147D01*
X-171761Y530230D01*
X-172428Y530064D01*
X-172928Y529730D01*
X-173261Y529147D01*
X-173344Y528564D01*
X-173261Y527980D01*
X-172928Y527480D01*
X-172428Y527064D01*
X-171761Y526897D01*
X-171178Y527064D01*
X-170678Y527397D01*
G01X-167661Y529147D02*
X-164994D01*
X-165244Y529730D01*
X-165661Y530064D01*
X-166244Y530230D01*
X-166828Y530147D01*
X-167328Y529897D01*
X-167661Y529314D01*
X-167828Y528814D01*
Y528314D01*
X-167661Y527814D01*
X-167244Y527314D01*
X-166744Y526980D01*
X-166161Y526897D01*
X-165578Y527064D01*
X-164994Y527564D01*
G01X-156961D02*
X-156294Y527147D01*
X-155544Y526897D01*
X-154878D01*
X-154211Y527147D01*
X-153711Y527564D01*
X-153461Y528147D01*
X-153628Y528730D01*
X-154044Y529230D01*
X-154794Y529564D01*
X-155794Y529730D01*
X-156378Y530064D01*
X-156628Y530647D01*
X-156461Y531230D01*
X-156044Y531647D01*
X-155461Y531897D01*
X-154878D01*
X-154294Y531730D01*
X-153794Y531314D01*
G01X-151111Y525230D02*
Y530230D01*
G01Y529480D02*
X-150694Y529897D01*
X-150278Y530147D01*
X-149611Y530230D01*
X-149028Y530147D01*
X-148444Y529730D01*
X-148194Y529147D01*
X-148111Y528564D01*
X-148194Y527980D01*
X-148444Y527397D01*
X-148944Y527064D01*
X-149611Y526897D01*
X-150194Y526980D01*
X-150778Y527230D01*
X-151111Y527564D01*
G01X-145261Y529147D02*
X-142594D01*
X-142844Y529730D01*
X-143261Y530064D01*
X-143844Y530230D01*
X-144428Y530147D01*
X-144928Y529897D01*
X-145261Y529314D01*
X-145428Y528814D01*
Y528314D01*
X-145261Y527814D01*
X-144844Y527314D01*
X-144344Y526980D01*
X-143761Y526897D01*
X-143178Y527064D01*
X-142594Y527564D01*
G01X-137078Y529814D02*
X-137661Y530147D01*
X-138161Y530230D01*
X-138828Y530064D01*
X-139328Y529730D01*
X-139661Y529147D01*
X-139744Y528564D01*
X-139661Y527980D01*
X-139328Y527480D01*
X-138828Y527064D01*
X-138161Y526897D01*
X-137578Y527064D01*
X-137078Y527397D01*
G01X-132811Y530230D02*
Y526897D01*
G01Y531564D02*
X-132978Y531647D01*
Y531814D01*
X-132811Y531897D01*
X-132644Y531814D01*
Y531647D01*
X-132811Y531564D01*
G01X-127711Y526897D02*
Y531147D01*
X-127544Y531564D01*
X-127211Y531814D01*
X-126711Y531897D01*
X-126211Y531730D01*
X-125961Y531314D01*
G01X-126961Y529897D02*
X-128628D01*
G01X-121611Y530230D02*
Y526897D01*
G01Y531564D02*
X-121778Y531647D01*
Y531814D01*
X-121611Y531897D01*
X-121444Y531814D01*
Y531647D01*
X-121611Y531564D01*
G01X-114678Y529814D02*
X-115261Y530147D01*
X-115761Y530230D01*
X-116428Y530064D01*
X-116928Y529730D01*
X-117261Y529147D01*
X-117344Y528564D01*
X-117261Y527980D01*
X-116928Y527480D01*
X-116428Y527064D01*
X-115761Y526897D01*
X-115178Y527064D01*
X-114678Y527397D01*
G01X-108911Y526897D02*
Y530230D01*
G01Y529647D02*
X-109244Y529980D01*
X-109744Y530147D01*
X-110328Y530230D01*
X-110911Y530064D01*
X-111411Y529730D01*
X-111744Y529230D01*
X-111911Y528564D01*
X-111744Y527897D01*
X-111411Y527397D01*
X-110911Y527064D01*
X-110328Y526897D01*
X-109744Y526980D01*
X-109244Y527230D01*
X-108911Y527564D01*
G01X-104811Y531897D02*
Y526897D01*
G01X-105978Y530230D02*
X-103644D01*
G01X-99211D02*
Y526897D01*
G01Y531564D02*
X-99378Y531647D01*
Y531814D01*
X-99211Y531897D01*
X-99044Y531814D01*
Y531647D01*
X-99211Y531564D01*
G01X-93611Y526897D02*
X-94111Y526980D01*
X-94611Y527314D01*
X-94944Y527897D01*
X-95111Y528564D01*
X-94944Y529230D01*
X-94611Y529814D01*
X-94111Y530147D01*
X-93611Y530230D01*
X-93111Y530147D01*
X-92611Y529814D01*
X-92278Y529230D01*
X-92194Y528564D01*
X-92278Y527897D01*
X-92611Y527314D01*
X-93111Y526980D01*
X-93611Y526897D01*
G01X-89428D02*
Y530230D01*
G01Y529397D02*
X-89094Y529814D01*
X-88594Y530147D01*
X-87928Y530230D01*
X-87344Y530147D01*
X-86844Y529814D01*
X-86594Y529230D01*
Y526897D01*
G01X-77311D02*
Y531147D01*
X-77144Y531564D01*
X-76811Y531814D01*
X-76311Y531897D01*
X-75811Y531730D01*
X-75561Y531314D01*
G01X-76561Y529897D02*
X-78228D01*
G01X-71211Y526897D02*
X-71711Y526980D01*
X-72211Y527314D01*
X-72544Y527897D01*
X-72711Y528564D01*
X-72544Y529230D01*
X-72211Y529814D01*
X-71711Y530147D01*
X-71211Y530230D01*
X-70711Y530147D01*
X-70211Y529814D01*
X-69878Y529230D01*
X-69794Y528564D01*
X-69878Y527897D01*
X-70211Y527314D01*
X-70711Y526980D01*
X-71211Y526897D01*
G01X-66778D02*
Y530230D01*
G01Y529564D02*
X-66361Y529897D01*
X-65944Y530147D01*
X-65361Y530230D01*
X-64944Y530147D01*
X-64444Y529897D01*
G01X-56161Y526897D02*
Y531897D01*
G01X-52661D02*
Y526897D01*
G01Y529397D02*
X-56161D01*
G01X-48811Y530230D02*
Y526897D01*
G01Y531564D02*
X-48978Y531647D01*
Y531814D01*
X-48811Y531897D01*
X-48644Y531814D01*
Y531647D01*
X-48811Y531564D01*
G01X-44378Y525647D02*
X-43794Y525314D01*
X-43128Y525230D01*
X-42544Y525314D01*
X-42044Y525730D01*
X-41711Y526314D01*
Y530230D01*
G01Y529564D02*
X-42044Y529897D01*
X-42544Y530147D01*
X-43128Y530230D01*
X-43794Y530064D01*
X-44211Y529730D01*
X-44544Y529147D01*
X-44711Y528564D01*
X-44628Y528064D01*
X-44294Y527480D01*
X-43794Y527064D01*
X-43128Y526897D01*
X-42628Y526980D01*
X-42044Y527314D01*
X-41711Y527647D01*
G01X-39028Y526897D02*
Y531897D01*
G01Y529480D02*
X-38611Y529897D01*
X-38194Y530147D01*
X-37528Y530230D01*
X-37028Y530147D01*
X-36444Y529814D01*
X-36194Y529314D01*
Y526897D01*
G01X-28244D02*
Y531897D01*
X-26578D01*
X-25911Y531647D01*
X-25411Y531314D01*
X-24994Y530814D01*
X-24661Y530230D01*
X-24578Y529397D01*
X-24661Y528564D01*
X-24994Y527980D01*
X-25411Y527480D01*
X-25911Y527147D01*
X-26578Y526897D01*
X-28244D01*
G01X-22061Y529147D02*
X-19394D01*
X-19644Y529730D01*
X-20061Y530064D01*
X-20644Y530230D01*
X-21228Y530147D01*
X-21728Y529897D01*
X-22061Y529314D01*
X-22228Y528814D01*
Y528314D01*
X-22061Y527814D01*
X-21644Y527314D01*
X-21144Y526980D01*
X-20561Y526897D01*
X-19978Y527064D01*
X-19394Y527564D01*
G01X-16628Y526897D02*
Y530230D01*
G01Y529397D02*
X-16294Y529814D01*
X-15794Y530147D01*
X-15128Y530230D01*
X-14544Y530147D01*
X-14044Y529814D01*
X-13794Y529230D01*
Y526897D01*
G01X-10861Y527480D02*
X-10444Y527147D01*
X-9861Y526897D01*
X-9361D01*
X-8861Y527064D01*
X-8528Y527314D01*
X-8361Y527647D01*
X-8444Y528147D01*
X-8778Y528397D01*
X-10278Y528897D01*
X-10611Y529480D01*
X-10444Y529897D01*
X-10111Y530147D01*
X-9611Y530230D01*
X-9111Y530147D01*
X-8611Y529897D01*
G01X-4011Y530230D02*
Y526897D01*
G01Y531564D02*
X-4178Y531647D01*
Y531814D01*
X-4011Y531897D01*
X-3844Y531814D01*
Y531647D01*
X-4011Y531564D01*
G01X1589Y531897D02*
Y526897D01*
G01X422Y530230D02*
X2756D01*
G01X5439Y525397D02*
X5939Y525230D01*
X6606Y525397D01*
X7022Y525730D01*
X7356Y526147D01*
X7856Y527480D01*
X8939Y530230D01*
G01X6272D02*
X7856Y527480D01*
G01X17389Y531897D02*
X19389D01*
G01X18389D02*
Y526897D01*
G01X17389D02*
X19389D01*
G01X22572D02*
Y530230D01*
G01Y529397D02*
X22906Y529814D01*
X23406Y530147D01*
X24072Y530230D01*
X24656Y530147D01*
X25156Y529814D01*
X25406Y529230D01*
Y526897D01*
G01X29589Y531897D02*
Y526897D01*
G01X28422Y530230D02*
X30756D01*
G01X33939Y529147D02*
X36606D01*
X36356Y529730D01*
X35939Y530064D01*
X35356Y530230D01*
X34772Y530147D01*
X34272Y529897D01*
X33939Y529314D01*
X33772Y528814D01*
Y528314D01*
X33939Y527814D01*
X34356Y527314D01*
X34856Y526980D01*
X35439Y526897D01*
X36022Y527064D01*
X36606Y527564D01*
G01X39622Y526897D02*
Y530230D01*
G01Y529564D02*
X40039Y529897D01*
X40456Y530147D01*
X41039Y530230D01*
X41456Y530147D01*
X41956Y529897D01*
G01X47722Y529814D02*
X47139Y530147D01*
X46639Y530230D01*
X45972Y530064D01*
X45472Y529730D01*
X45139Y529147D01*
X45056Y528564D01*
X45139Y527980D01*
X45472Y527480D01*
X45972Y527064D01*
X46639Y526897D01*
X47222Y527064D01*
X47722Y527397D01*
G01X51989Y526897D02*
X51489Y526980D01*
X50989Y527314D01*
X50656Y527897D01*
X50489Y528564D01*
X50656Y529230D01*
X50989Y529814D01*
X51489Y530147D01*
X51989Y530230D01*
X52489Y530147D01*
X52989Y529814D01*
X53322Y529230D01*
X53406Y528564D01*
X53322Y527897D01*
X52989Y527314D01*
X52489Y526980D01*
X51989Y526897D01*
G01X56172D02*
Y530230D01*
G01Y529397D02*
X56506Y529814D01*
X57006Y530147D01*
X57672Y530230D01*
X58256Y530147D01*
X58756Y529814D01*
X59006Y529230D01*
Y526897D01*
G01X61772D02*
Y530230D01*
G01Y529397D02*
X62106Y529814D01*
X62606Y530147D01*
X63272Y530230D01*
X63856Y530147D01*
X64356Y529814D01*
X64606Y529230D01*
Y526897D01*
G01X67539Y529147D02*
X70206D01*
X69956Y529730D01*
X69539Y530064D01*
X68956Y530230D01*
X68372Y530147D01*
X67872Y529897D01*
X67539Y529314D01*
X67372Y528814D01*
Y528314D01*
X67539Y527814D01*
X67956Y527314D01*
X68456Y526980D01*
X69039Y526897D01*
X69622Y527064D01*
X70206Y527564D01*
G01X75722Y529814D02*
X75139Y530147D01*
X74639Y530230D01*
X73972Y530064D01*
X73472Y529730D01*
X73139Y529147D01*
X73056Y528564D01*
X73139Y527980D01*
X73472Y527480D01*
X73972Y527064D01*
X74639Y526897D01*
X75222Y527064D01*
X75722Y527397D01*
G01X79989Y531897D02*
Y526897D01*
G01X78822Y530230D02*
X81156D01*
G01X85172Y525230D02*
X84339Y526064D01*
X83922Y526897D01*
Y530230D01*
X84339Y531064D01*
X85172Y531897D01*
G01X89439Y526897D02*
Y531897D01*
G01X92939D02*
Y526897D01*
G01Y529397D02*
X89439D01*
G01X94956Y526897D02*
Y531897D01*
X96622D01*
X97289Y531647D01*
X97789Y531314D01*
X98206Y530814D01*
X98539Y530230D01*
X98622Y529397D01*
X98539Y528564D01*
X98206Y527980D01*
X97789Y527480D01*
X97289Y527147D01*
X96622Y526897D01*
X94956D01*
G01X101389Y531897D02*
X103389D01*
G01X102389D02*
Y526897D01*
G01X101389D02*
X103389D01*
G01X108406Y525230D02*
X109239Y526064D01*
X109656Y526897D01*
Y530230D01*
X109239Y531064D01*
X108406Y531897D01*
G01X117522D02*
Y526897D01*
X120856D01*
G01X126289D02*
Y530230D01*
G01Y529647D02*
X125956Y529980D01*
X125456Y530147D01*
X124872Y530230D01*
X124289Y530064D01*
X123789Y529730D01*
X123456Y529230D01*
X123289Y528564D01*
X123456Y527897D01*
X123789Y527397D01*
X124289Y527064D01*
X124872Y526897D01*
X125456Y526980D01*
X125956Y527230D01*
X126289Y527564D01*
G01X128639Y525397D02*
X129139Y525230D01*
X129806Y525397D01*
X130222Y525730D01*
X130556Y526147D01*
X131056Y527480D01*
X132139Y530230D01*
G01X129472D02*
X131056Y527480D01*
G01X134739Y529147D02*
X137406D01*
X137156Y529730D01*
X136739Y530064D01*
X136156Y530230D01*
X135572Y530147D01*
X135072Y529897D01*
X134739Y529314D01*
X134572Y528814D01*
Y528314D01*
X134739Y527814D01*
X135156Y527314D01*
X135656Y526980D01*
X136239Y526897D01*
X136822Y527064D01*
X137406Y527564D01*
G01X140422Y526897D02*
Y530230D01*
G01Y529564D02*
X140839Y529897D01*
X141256Y530147D01*
X141839Y530230D01*
X142256Y530147D01*
X142756Y529897D01*
G01X145939Y527480D02*
X146356Y527147D01*
X146939Y526897D01*
X147439D01*
X147939Y527064D01*
X148272Y527314D01*
X148439Y527647D01*
X148356Y528147D01*
X148022Y528397D01*
X146522Y528897D01*
X146189Y529480D01*
X146356Y529897D01*
X146689Y530147D01*
X147189Y530230D01*
X147689Y530147D01*
X148189Y529897D01*
G01X158389Y526897D02*
X157889Y526980D01*
X157389Y527314D01*
X157056Y527897D01*
X156889Y528564D01*
X157056Y529230D01*
X157389Y529814D01*
X157889Y530147D01*
X158389Y530230D01*
X158889Y530147D01*
X159389Y529814D01*
X159722Y529230D01*
X159806Y528564D01*
X159722Y527897D01*
X159389Y527314D01*
X158889Y526980D01*
X158389Y526897D01*
G01X162822D02*
Y530230D01*
G01Y529564D02*
X163239Y529897D01*
X163656Y530147D01*
X164239Y530230D01*
X164656Y530147D01*
X165156Y529897D01*
G01X175856Y529564D02*
X176189Y529814D01*
X176439Y530230D01*
X176606Y530814D01*
X176439Y531314D01*
X176106Y531647D01*
X175522Y531897D01*
X173272D01*
Y526897D01*
X176022D01*
X176606Y527230D01*
X176939Y527730D01*
X177106Y528314D01*
X176939Y528897D01*
X176439Y529397D01*
X175856Y529564D01*
X173272D01*
G01X180789Y526897D02*
X180289Y526980D01*
X179789Y527314D01*
X179456Y527897D01*
X179289Y528564D01*
X179456Y529230D01*
X179789Y529814D01*
X180289Y530147D01*
X180789Y530230D01*
X181289Y530147D01*
X181789Y529814D01*
X182122Y529230D01*
X182206Y528564D01*
X182122Y527897D01*
X181789Y527314D01*
X181289Y526980D01*
X180789Y526897D01*
G01X187889D02*
Y530230D01*
G01Y529647D02*
X187556Y529980D01*
X187056Y530147D01*
X186472Y530230D01*
X185889Y530064D01*
X185389Y529730D01*
X185056Y529230D01*
X184889Y528564D01*
X185056Y527897D01*
X185389Y527397D01*
X185889Y527064D01*
X186472Y526897D01*
X187056Y526980D01*
X187556Y527230D01*
X187889Y527564D01*
G01X190822Y526897D02*
Y530230D01*
G01Y529564D02*
X191239Y529897D01*
X191656Y530147D01*
X192239Y530230D01*
X192656Y530147D01*
X193156Y529897D01*
G01X199089Y531897D02*
Y526897D01*
G01Y527647D02*
X198756Y527230D01*
X198256Y526980D01*
X197672Y526897D01*
X197006Y527064D01*
X196506Y527480D01*
X196172Y527980D01*
X196089Y528564D01*
X196172Y529147D01*
X196506Y529647D01*
X197006Y530064D01*
X197672Y530230D01*
X198256Y530147D01*
X198672Y529980D01*
X199089Y529647D01*
G01X201939Y527480D02*
X202356Y527147D01*
X202939Y526897D01*
X203439D01*
X203939Y527064D01*
X204272Y527314D01*
X204439Y527647D01*
X204356Y528147D01*
X204022Y528397D01*
X202522Y528897D01*
X202189Y529480D01*
X202356Y529897D01*
X202689Y530147D01*
X203189Y530230D01*
X203689Y530147D01*
X204189Y529897D01*
G01X209206Y525230D02*
X210039Y526064D01*
X210456Y526897D01*
Y530230D01*
X210039Y531064D01*
X209206Y531897D01*
G01X-363411Y540897D02*
X-361411D01*
G01X-362411D02*
Y535897D01*
G01X-363411D02*
X-361411D01*
G01X-358478D02*
Y540897D01*
X-356478D01*
X-355811Y540647D01*
X-355311Y540064D01*
X-355144Y539397D01*
X-355311Y538730D01*
X-355728Y538230D01*
X-356478Y537980D01*
X-358478D01*
G01X-349378Y540480D02*
X-349878Y540730D01*
X-350461Y540897D01*
X-351128D01*
X-351878Y540647D01*
X-352461Y540230D01*
X-352878Y539730D01*
X-353211Y538897D01*
X-353294Y538147D01*
X-353128Y537397D01*
X-352878Y536897D01*
X-352378Y536397D01*
X-351794Y536064D01*
X-351211Y535897D01*
X-350628D01*
X-350044Y536064D01*
X-349544Y536314D01*
X-349128Y536647D01*
G01X-346694Y537564D02*
X-344528D01*
G01X-341594Y537980D02*
X-341011Y538564D01*
X-340511Y538897D01*
X-339844Y539064D01*
X-339261Y538897D01*
X-338844Y538564D01*
X-338511Y538064D01*
X-338428Y537480D01*
X-338511Y536980D01*
X-338844Y536480D01*
X-339344Y536064D01*
X-339928Y535897D01*
X-340594Y536064D01*
X-341178Y536564D01*
X-341511Y537314D01*
X-341594Y538147D01*
X-341428Y539230D01*
X-341178Y539814D01*
X-340761Y540397D01*
X-340178Y540814D01*
X-339594Y540897D01*
X-339011Y540730D01*
X-338594Y540314D01*
G01X-334411Y540897D02*
X-335078Y540730D01*
X-335578Y540314D01*
X-335911Y539814D01*
X-336161Y539147D01*
X-336244Y538397D01*
X-336161Y537647D01*
X-335911Y536980D01*
X-335578Y536480D01*
X-335078Y536064D01*
X-334411Y535897D01*
X-333744Y536064D01*
X-333244Y536480D01*
X-332911Y536980D01*
X-332661Y537647D01*
X-332578Y538397D01*
X-332661Y539147D01*
X-332911Y539814D01*
X-333244Y540314D01*
X-333744Y540730D01*
X-334411Y540897D01*
G01X-328811Y535897D02*
Y540897D01*
X-329811Y539897D01*
G01Y535897D02*
X-327811D01*
G01X-324794Y540064D02*
X-324294Y540564D01*
X-323711Y540814D01*
X-323044Y540897D01*
X-322211Y540730D01*
X-321628Y540314D01*
X-321461Y539814D01*
X-321544Y539314D01*
X-321878Y538897D01*
X-323544Y538064D01*
X-324294Y537480D01*
X-324794Y536647D01*
X-324961Y535897D01*
X-321461D01*
G01X-312011D02*
X-312678Y535980D01*
X-313261Y536314D01*
X-313761Y536814D01*
X-314094Y537397D01*
X-314261Y538064D01*
Y538730D01*
X-314094Y539397D01*
X-313761Y539980D01*
X-313261Y540480D01*
X-312678Y540814D01*
X-312011Y540897D01*
X-311344Y540814D01*
X-310761Y540480D01*
X-310261Y539980D01*
X-309928Y539397D01*
X-309761Y538730D01*
Y538064D01*
X-309928Y537397D01*
X-310261Y536814D01*
X-310761Y536314D01*
X-311344Y535980D01*
X-312011Y535897D01*
G01X-311344Y537230D02*
X-310344Y535897D01*
G01X-307828Y539230D02*
Y536897D01*
X-307494Y536314D01*
X-306994Y535980D01*
X-306411Y535897D01*
X-305828Y535980D01*
X-305328Y536314D01*
X-304994Y536897D01*
G01Y535897D02*
Y539230D01*
G01X-299311Y535897D02*
Y539230D01*
G01Y538647D02*
X-299644Y538980D01*
X-300144Y539147D01*
X-300728Y539230D01*
X-301311Y539064D01*
X-301811Y538730D01*
X-302144Y538230D01*
X-302311Y537564D01*
X-302144Y536897D01*
X-301811Y536397D01*
X-301311Y536064D01*
X-300728Y535897D01*
X-300144Y535980D01*
X-299644Y536230D01*
X-299311Y536564D01*
G01X-295211Y535897D02*
Y540897D01*
G01X-289611Y539230D02*
Y535897D01*
G01Y540564D02*
X-289778Y540647D01*
Y540814D01*
X-289611Y540897D01*
X-289444Y540814D01*
Y540647D01*
X-289611Y540564D01*
G01X-284511Y535897D02*
Y540147D01*
X-284344Y540564D01*
X-284011Y540814D01*
X-283511Y540897D01*
X-283011Y540730D01*
X-282761Y540314D01*
G01X-283761Y538897D02*
X-285428D01*
G01X-278411Y539230D02*
Y535897D01*
G01Y540564D02*
X-278578Y540647D01*
Y540814D01*
X-278411Y540897D01*
X-278244Y540814D01*
Y540647D01*
X-278411Y540564D01*
G01X-271478Y538814D02*
X-272061Y539147D01*
X-272561Y539230D01*
X-273228Y539064D01*
X-273728Y538730D01*
X-274061Y538147D01*
X-274144Y537564D01*
X-274061Y536980D01*
X-273728Y536480D01*
X-273228Y536064D01*
X-272561Y535897D01*
X-271978Y536064D01*
X-271478Y536397D01*
G01X-265711Y535897D02*
Y539230D01*
G01Y538647D02*
X-266044Y538980D01*
X-266544Y539147D01*
X-267128Y539230D01*
X-267711Y539064D01*
X-268211Y538730D01*
X-268544Y538230D01*
X-268711Y537564D01*
X-268544Y536897D01*
X-268211Y536397D01*
X-267711Y536064D01*
X-267128Y535897D01*
X-266544Y535980D01*
X-266044Y536230D01*
X-265711Y536564D01*
G01X-261611Y540897D02*
Y535897D01*
G01X-262778Y539230D02*
X-260444D01*
G01X-256011D02*
Y535897D01*
G01Y540564D02*
X-256178Y540647D01*
Y540814D01*
X-256011Y540897D01*
X-255844Y540814D01*
Y540647D01*
X-256011Y540564D01*
G01X-250411Y535897D02*
X-250911Y535980D01*
X-251411Y536314D01*
X-251744Y536897D01*
X-251911Y537564D01*
X-251744Y538230D01*
X-251411Y538814D01*
X-250911Y539147D01*
X-250411Y539230D01*
X-249911Y539147D01*
X-249411Y538814D01*
X-249078Y538230D01*
X-248994Y537564D01*
X-249078Y536897D01*
X-249411Y536314D01*
X-249911Y535980D01*
X-250411Y535897D01*
G01X-246228D02*
Y539230D01*
G01Y538397D02*
X-245894Y538814D01*
X-245394Y539147D01*
X-244728Y539230D01*
X-244144Y539147D01*
X-243644Y538814D01*
X-243394Y538230D01*
Y535897D01*
G01X-232111D02*
Y539230D01*
G01Y538647D02*
X-232444Y538980D01*
X-232944Y539147D01*
X-233528Y539230D01*
X-234111Y539064D01*
X-234611Y538730D01*
X-234944Y538230D01*
X-235111Y537564D01*
X-234944Y536897D01*
X-234611Y536397D01*
X-234111Y536064D01*
X-233528Y535897D01*
X-232944Y535980D01*
X-232444Y536230D01*
X-232111Y536564D01*
G01X-229428Y535897D02*
Y539230D01*
G01Y538397D02*
X-229094Y538814D01*
X-228594Y539147D01*
X-227928Y539230D01*
X-227344Y539147D01*
X-226844Y538814D01*
X-226594Y538230D01*
Y535897D01*
G01X-220911Y540897D02*
Y535897D01*
G01Y536647D02*
X-221244Y536230D01*
X-221744Y535980D01*
X-222328Y535897D01*
X-222994Y536064D01*
X-223494Y536480D01*
X-223828Y536980D01*
X-223911Y537564D01*
X-223828Y538147D01*
X-223494Y538647D01*
X-222994Y539064D01*
X-222328Y539230D01*
X-221744Y539147D01*
X-221328Y538980D01*
X-220911Y538647D01*
G01X-212878Y535897D02*
Y540897D01*
X-210878D01*
X-210211Y540647D01*
X-209711Y540064D01*
X-209544Y539397D01*
X-209711Y538730D01*
X-210128Y538230D01*
X-210878Y537980D01*
X-212878D01*
G01X-206861Y538147D02*
X-204194D01*
X-204444Y538730D01*
X-204861Y539064D01*
X-205444Y539230D01*
X-206028Y539147D01*
X-206528Y538897D01*
X-206861Y538314D01*
X-207028Y537814D01*
Y537314D01*
X-206861Y536814D01*
X-206444Y536314D01*
X-205944Y535980D01*
X-205361Y535897D01*
X-204778Y536064D01*
X-204194Y536564D01*
G01X-201178Y535897D02*
Y539230D01*
G01Y538564D02*
X-200761Y538897D01*
X-200344Y539147D01*
X-199761Y539230D01*
X-199344Y539147D01*
X-198844Y538897D01*
G01X-194911Y535897D02*
Y540147D01*
X-194744Y540564D01*
X-194411Y540814D01*
X-193911Y540897D01*
X-193411Y540730D01*
X-193161Y540314D01*
G01X-194161Y538897D02*
X-195828D01*
G01X-188811Y535897D02*
X-189311Y535980D01*
X-189811Y536314D01*
X-190144Y536897D01*
X-190311Y537564D01*
X-190144Y538230D01*
X-189811Y538814D01*
X-189311Y539147D01*
X-188811Y539230D01*
X-188311Y539147D01*
X-187811Y538814D01*
X-187478Y538230D01*
X-187394Y537564D01*
X-187478Y536897D01*
X-187811Y536314D01*
X-188311Y535980D01*
X-188811Y535897D01*
G01X-184378D02*
Y539230D01*
G01Y538564D02*
X-183961Y538897D01*
X-183544Y539147D01*
X-182961Y539230D01*
X-182544Y539147D01*
X-182044Y538897D01*
G01X-180111Y535897D02*
Y539230D01*
G01Y538314D02*
X-179861Y538730D01*
X-179444Y539064D01*
X-178861Y539230D01*
X-178278Y539064D01*
X-177861Y538730D01*
X-177611Y538314D01*
Y535897D01*
G01Y538314D02*
X-177361Y538730D01*
X-176944Y539064D01*
X-176361Y539230D01*
X-175778Y539064D01*
X-175361Y538730D01*
X-175111Y538230D01*
Y535897D01*
G01X-170511D02*
Y539230D01*
G01Y538647D02*
X-170844Y538980D01*
X-171344Y539147D01*
X-171928Y539230D01*
X-172511Y539064D01*
X-173011Y538730D01*
X-173344Y538230D01*
X-173511Y537564D01*
X-173344Y536897D01*
X-173011Y536397D01*
X-172511Y536064D01*
X-171928Y535897D01*
X-171344Y535980D01*
X-170844Y536230D01*
X-170511Y536564D01*
G01X-167828Y535897D02*
Y539230D01*
G01Y538397D02*
X-167494Y538814D01*
X-166994Y539147D01*
X-166328Y539230D01*
X-165744Y539147D01*
X-165244Y538814D01*
X-164994Y538230D01*
Y535897D01*
G01X-159478Y538814D02*
X-160061Y539147D01*
X-160561Y539230D01*
X-161228Y539064D01*
X-161728Y538730D01*
X-162061Y538147D01*
X-162144Y537564D01*
X-162061Y536980D01*
X-161728Y536480D01*
X-161228Y536064D01*
X-160561Y535897D01*
X-159978Y536064D01*
X-159478Y536397D01*
G01X-156461Y538147D02*
X-153794D01*
X-154044Y538730D01*
X-154461Y539064D01*
X-155044Y539230D01*
X-155628Y539147D01*
X-156128Y538897D01*
X-156461Y538314D01*
X-156628Y537814D01*
Y537314D01*
X-156461Y536814D01*
X-156044Y536314D01*
X-155544Y535980D01*
X-154961Y535897D01*
X-154378Y536064D01*
X-153794Y536564D01*
G01X-145761D02*
X-145094Y536147D01*
X-144344Y535897D01*
X-143678D01*
X-143011Y536147D01*
X-142511Y536564D01*
X-142261Y537147D01*
X-142428Y537730D01*
X-142844Y538230D01*
X-143594Y538564D01*
X-144594Y538730D01*
X-145178Y539064D01*
X-145428Y539647D01*
X-145261Y540230D01*
X-144844Y540647D01*
X-144261Y540897D01*
X-143678D01*
X-143094Y540730D01*
X-142594Y540314D01*
G01X-139911Y534230D02*
Y539230D01*
G01Y538480D02*
X-139494Y538897D01*
X-139078Y539147D01*
X-138411Y539230D01*
X-137828Y539147D01*
X-137244Y538730D01*
X-136994Y538147D01*
X-136911Y537564D01*
X-136994Y536980D01*
X-137244Y536397D01*
X-137744Y536064D01*
X-138411Y535897D01*
X-138994Y535980D01*
X-139578Y536230D01*
X-139911Y536564D01*
G01X-134061Y538147D02*
X-131394D01*
X-131644Y538730D01*
X-132061Y539064D01*
X-132644Y539230D01*
X-133228Y539147D01*
X-133728Y538897D01*
X-134061Y538314D01*
X-134228Y537814D01*
Y537314D01*
X-134061Y536814D01*
X-133644Y536314D01*
X-133144Y535980D01*
X-132561Y535897D01*
X-131978Y536064D01*
X-131394Y536564D01*
G01X-125878Y538814D02*
X-126461Y539147D01*
X-126961Y539230D01*
X-127628Y539064D01*
X-128128Y538730D01*
X-128461Y538147D01*
X-128544Y537564D01*
X-128461Y536980D01*
X-128128Y536480D01*
X-127628Y536064D01*
X-126961Y535897D01*
X-126378Y536064D01*
X-125878Y536397D01*
G01X-121611Y539230D02*
Y535897D01*
G01Y540564D02*
X-121778Y540647D01*
Y540814D01*
X-121611Y540897D01*
X-121444Y540814D01*
Y540647D01*
X-121611Y540564D01*
G01X-116511Y535897D02*
Y540147D01*
X-116344Y540564D01*
X-116011Y540814D01*
X-115511Y540897D01*
X-115011Y540730D01*
X-114761Y540314D01*
G01X-115761Y538897D02*
X-117428D01*
G01X-110411Y539230D02*
Y535897D01*
G01Y540564D02*
X-110578Y540647D01*
Y540814D01*
X-110411Y540897D01*
X-110244Y540814D01*
Y540647D01*
X-110411Y540564D01*
G01X-103478Y538814D02*
X-104061Y539147D01*
X-104561Y539230D01*
X-105228Y539064D01*
X-105728Y538730D01*
X-106061Y538147D01*
X-106144Y537564D01*
X-106061Y536980D01*
X-105728Y536480D01*
X-105228Y536064D01*
X-104561Y535897D01*
X-103978Y536064D01*
X-103478Y536397D01*
G01X-97711Y535897D02*
Y539230D01*
G01Y538647D02*
X-98044Y538980D01*
X-98544Y539147D01*
X-99128Y539230D01*
X-99711Y539064D01*
X-100211Y538730D01*
X-100544Y538230D01*
X-100711Y537564D01*
X-100544Y536897D01*
X-100211Y536397D01*
X-99711Y536064D01*
X-99128Y535897D01*
X-98544Y535980D01*
X-98044Y536230D01*
X-97711Y536564D01*
G01X-93611Y540897D02*
Y535897D01*
G01X-94778Y539230D02*
X-92444D01*
G01X-88011D02*
Y535897D01*
G01Y540564D02*
X-88178Y540647D01*
Y540814D01*
X-88011Y540897D01*
X-87844Y540814D01*
Y540647D01*
X-88011Y540564D01*
G01X-82411Y535897D02*
X-82911Y535980D01*
X-83411Y536314D01*
X-83744Y536897D01*
X-83911Y537564D01*
X-83744Y538230D01*
X-83411Y538814D01*
X-82911Y539147D01*
X-82411Y539230D01*
X-81911Y539147D01*
X-81411Y538814D01*
X-81078Y538230D01*
X-80994Y537564D01*
X-81078Y536897D01*
X-81411Y536314D01*
X-81911Y535980D01*
X-82411Y535897D01*
G01X-78228D02*
Y539230D01*
G01Y538397D02*
X-77894Y538814D01*
X-77394Y539147D01*
X-76728Y539230D01*
X-76144Y539147D01*
X-75644Y538814D01*
X-75394Y538230D01*
Y535897D01*
G01X-66111D02*
Y540147D01*
X-65944Y540564D01*
X-65611Y540814D01*
X-65111Y540897D01*
X-64611Y540730D01*
X-64361Y540314D01*
G01X-65361Y538897D02*
X-67028D01*
G01X-60011Y535897D02*
X-60511Y535980D01*
X-61011Y536314D01*
X-61344Y536897D01*
X-61511Y537564D01*
X-61344Y538230D01*
X-61011Y538814D01*
X-60511Y539147D01*
X-60011Y539230D01*
X-59511Y539147D01*
X-59011Y538814D01*
X-58678Y538230D01*
X-58594Y537564D01*
X-58678Y536897D01*
X-59011Y536314D01*
X-59511Y535980D01*
X-60011Y535897D01*
G01X-55578D02*
Y539230D01*
G01Y538564D02*
X-55161Y538897D01*
X-54744Y539147D01*
X-54161Y539230D01*
X-53744Y539147D01*
X-53244Y538897D01*
G01X-44878Y535897D02*
Y540897D01*
X-42794D01*
X-42128Y540647D01*
X-41711Y540314D01*
X-41544Y539647D01*
X-41711Y538980D01*
X-42211Y538564D01*
X-42794Y538314D01*
X-44878D01*
G01X-42794D02*
X-41544Y535897D01*
G01X-37611Y539230D02*
Y535897D01*
G01Y540564D02*
X-37778Y540647D01*
Y540814D01*
X-37611Y540897D01*
X-37444Y540814D01*
Y540647D01*
X-37611Y540564D01*
G01X-33178Y534647D02*
X-32594Y534314D01*
X-31928Y534230D01*
X-31344Y534314D01*
X-30844Y534730D01*
X-30511Y535314D01*
Y539230D01*
G01Y538564D02*
X-30844Y538897D01*
X-31344Y539147D01*
X-31928Y539230D01*
X-32594Y539064D01*
X-33011Y538730D01*
X-33344Y538147D01*
X-33511Y537564D01*
X-33428Y537064D01*
X-33094Y536480D01*
X-32594Y536064D01*
X-31928Y535897D01*
X-31428Y535980D01*
X-30844Y536314D01*
X-30511Y536647D01*
G01X-26411Y539230D02*
Y535897D01*
G01Y540564D02*
X-26578Y540647D01*
Y540814D01*
X-26411Y540897D01*
X-26244Y540814D01*
Y540647D01*
X-26411Y540564D01*
G01X-19311Y540897D02*
Y535897D01*
G01Y536647D02*
X-19644Y536230D01*
X-20144Y535980D01*
X-20728Y535897D01*
X-21394Y536064D01*
X-21894Y536480D01*
X-22228Y536980D01*
X-22311Y537564D01*
X-22228Y538147D01*
X-21894Y538647D01*
X-21394Y539064D01*
X-20728Y539230D01*
X-20144Y539147D01*
X-19728Y538980D01*
X-19311Y538647D01*
G01X-11278Y535897D02*
Y540897D01*
X-9278D01*
X-8611Y540647D01*
X-8111Y540064D01*
X-7944Y539397D01*
X-8111Y538730D01*
X-8528Y538230D01*
X-9278Y537980D01*
X-11278D01*
G01X-5178Y535897D02*
Y539230D01*
G01Y538564D02*
X-4761Y538897D01*
X-4344Y539147D01*
X-3761Y539230D01*
X-3344Y539147D01*
X-2844Y538897D01*
G01X1589Y539230D02*
Y535897D01*
G01Y540564D02*
X1422Y540647D01*
Y540814D01*
X1589Y540897D01*
X1756Y540814D01*
Y540647D01*
X1589Y540564D01*
G01X5772Y535897D02*
Y539230D01*
G01Y538397D02*
X6106Y538814D01*
X6606Y539147D01*
X7272Y539230D01*
X7856Y539147D01*
X8356Y538814D01*
X8606Y538230D01*
Y535897D01*
G01X12789Y540897D02*
Y535897D01*
G01X11622Y539230D02*
X13956D01*
G01X17139Y538147D02*
X19806D01*
X19556Y538730D01*
X19139Y539064D01*
X18556Y539230D01*
X17972Y539147D01*
X17472Y538897D01*
X17139Y538314D01*
X16972Y537814D01*
Y537314D01*
X17139Y536814D01*
X17556Y536314D01*
X18056Y535980D01*
X18639Y535897D01*
X19222Y536064D01*
X19806Y536564D01*
G01X25489Y540897D02*
Y535897D01*
G01Y536647D02*
X25156Y536230D01*
X24656Y535980D01*
X24072Y535897D01*
X23406Y536064D01*
X22906Y536480D01*
X22572Y536980D01*
X22489Y537564D01*
X22572Y538147D01*
X22906Y538647D01*
X23406Y539064D01*
X24072Y539230D01*
X24656Y539147D01*
X25072Y538980D01*
X25489Y538647D01*
G01X35856Y538564D02*
X36189Y538814D01*
X36439Y539230D01*
X36606Y539814D01*
X36439Y540314D01*
X36106Y540647D01*
X35522Y540897D01*
X33272D01*
Y535897D01*
X36022D01*
X36606Y536230D01*
X36939Y536730D01*
X37106Y537314D01*
X36939Y537897D01*
X36439Y538397D01*
X35856Y538564D01*
X33272D01*
G01X40789Y535897D02*
X40289Y535980D01*
X39789Y536314D01*
X39456Y536897D01*
X39289Y537564D01*
X39456Y538230D01*
X39789Y538814D01*
X40289Y539147D01*
X40789Y539230D01*
X41289Y539147D01*
X41789Y538814D01*
X42122Y538230D01*
X42206Y537564D01*
X42122Y536897D01*
X41789Y536314D01*
X41289Y535980D01*
X40789Y535897D01*
G01X47889D02*
Y539230D01*
G01Y538647D02*
X47556Y538980D01*
X47056Y539147D01*
X46472Y539230D01*
X45889Y539064D01*
X45389Y538730D01*
X45056Y538230D01*
X44889Y537564D01*
X45056Y536897D01*
X45389Y536397D01*
X45889Y536064D01*
X46472Y535897D01*
X47056Y535980D01*
X47556Y536230D01*
X47889Y536564D01*
G01X50822Y535897D02*
Y539230D01*
G01Y538564D02*
X51239Y538897D01*
X51656Y539147D01*
X52239Y539230D01*
X52656Y539147D01*
X53156Y538897D01*
G01X59089Y540897D02*
Y535897D01*
G01Y536647D02*
X58756Y536230D01*
X58256Y535980D01*
X57672Y535897D01*
X57006Y536064D01*
X56506Y536480D01*
X56172Y536980D01*
X56089Y537564D01*
X56172Y538147D01*
X56506Y538647D01*
X57006Y539064D01*
X57672Y539230D01*
X58256Y539147D01*
X58672Y538980D01*
X59089Y538647D01*
G01X61939Y536480D02*
X62356Y536147D01*
X62939Y535897D01*
X63439D01*
X63939Y536064D01*
X64272Y536314D01*
X64439Y536647D01*
X64356Y537147D01*
X64022Y537397D01*
X62522Y537897D01*
X62189Y538480D01*
X62356Y538897D01*
X62689Y539147D01*
X63189Y539230D01*
X63689Y539147D01*
X64189Y538897D01*
G01X-367411Y536730D02*
X-367578Y536814D01*
Y536980D01*
X-367411Y537064D01*
X-367244Y536980D01*
Y536814D01*
X-367411Y536730D01*
G01Y545730D02*
X-367578Y545814D01*
Y545980D01*
X-367411Y546064D01*
X-367244Y545980D01*
Y545814D01*
X-367411Y545730D01*
G01Y552630D02*
X-367578Y552714D01*
Y552880D01*
X-367411Y552964D01*
X-367244Y552880D01*
Y552714D01*
X-367411Y552630D01*
G01X-363411Y549897D02*
X-361411D01*
G01X-362411D02*
Y544897D01*
G01X-363411D02*
X-361411D01*
G01X-358478D02*
Y549897D01*
X-356478D01*
X-355811Y549647D01*
X-355311Y549064D01*
X-355144Y548397D01*
X-355311Y547730D01*
X-355728Y547230D01*
X-356478Y546980D01*
X-358478D01*
G01X-349378Y549480D02*
X-349878Y549730D01*
X-350461Y549897D01*
X-351128D01*
X-351878Y549647D01*
X-352461Y549230D01*
X-352878Y548730D01*
X-353211Y547897D01*
X-353294Y547147D01*
X-353128Y546397D01*
X-352878Y545897D01*
X-352378Y545397D01*
X-351794Y545064D01*
X-351211Y544897D01*
X-350628D01*
X-350044Y545064D01*
X-349544Y545314D01*
X-349128Y545647D01*
G01X-346694Y546564D02*
X-344528D01*
G01X-341594Y546980D02*
X-341011Y547564D01*
X-340511Y547897D01*
X-339844Y548064D01*
X-339261Y547897D01*
X-338844Y547564D01*
X-338511Y547064D01*
X-338428Y546480D01*
X-338511Y545980D01*
X-338844Y545480D01*
X-339344Y545064D01*
X-339928Y544897D01*
X-340594Y545064D01*
X-341178Y545564D01*
X-341511Y546314D01*
X-341594Y547147D01*
X-341428Y548230D01*
X-341178Y548814D01*
X-340761Y549397D01*
X-340178Y549814D01*
X-339594Y549897D01*
X-339011Y549730D01*
X-338594Y549314D01*
G01X-334411Y549897D02*
X-335078Y549730D01*
X-335578Y549314D01*
X-335911Y548814D01*
X-336161Y548147D01*
X-336244Y547397D01*
X-336161Y546647D01*
X-335911Y545980D01*
X-335578Y545480D01*
X-335078Y545064D01*
X-334411Y544897D01*
X-333744Y545064D01*
X-333244Y545480D01*
X-332911Y545980D01*
X-332661Y546647D01*
X-332578Y547397D01*
X-332661Y548147D01*
X-332911Y548814D01*
X-333244Y549314D01*
X-333744Y549730D01*
X-334411Y549897D01*
G01X-328811Y544897D02*
Y549897D01*
X-329811Y548897D01*
G01Y544897D02*
X-327811D01*
G01X-323211D02*
Y549897D01*
X-324211Y548897D01*
G01Y544897D02*
X-322211D01*
G01X-311511Y547397D02*
X-309844D01*
Y545897D01*
X-310344Y545397D01*
X-310928Y545064D01*
X-311761Y544897D01*
X-312594Y545064D01*
X-313178Y545397D01*
X-313678Y545897D01*
X-314011Y546480D01*
X-314178Y547147D01*
Y547730D01*
X-314011Y548230D01*
X-313678Y548814D01*
X-313178Y549314D01*
X-312678Y549647D01*
X-312011Y549897D01*
X-311428D01*
X-310761Y549730D01*
X-310261Y549397D01*
G01X-307661Y547147D02*
X-304994D01*
X-305244Y547730D01*
X-305661Y548064D01*
X-306244Y548230D01*
X-306828Y548147D01*
X-307328Y547897D01*
X-307661Y547314D01*
X-307828Y546814D01*
Y546314D01*
X-307661Y545814D01*
X-307244Y545314D01*
X-306744Y544980D01*
X-306161Y544897D01*
X-305578Y545064D01*
X-304994Y545564D01*
G01X-302228Y544897D02*
Y548230D01*
G01Y547397D02*
X-301894Y547814D01*
X-301394Y548147D01*
X-300728Y548230D01*
X-300144Y548147D01*
X-299644Y547814D01*
X-299394Y547230D01*
Y544897D01*
G01X-296461Y547147D02*
X-293794D01*
X-294044Y547730D01*
X-294461Y548064D01*
X-295044Y548230D01*
X-295628Y548147D01*
X-296128Y547897D01*
X-296461Y547314D01*
X-296628Y546814D01*
Y546314D01*
X-296461Y545814D01*
X-296044Y545314D01*
X-295544Y544980D01*
X-294961Y544897D01*
X-294378Y545064D01*
X-293794Y545564D01*
G01X-290778Y544897D02*
Y548230D01*
G01Y547564D02*
X-290361Y547897D01*
X-289944Y548147D01*
X-289361Y548230D01*
X-288944Y548147D01*
X-288444Y547897D01*
G01X-284011Y548230D02*
Y544897D01*
G01Y549564D02*
X-284178Y549647D01*
Y549814D01*
X-284011Y549897D01*
X-283844Y549814D01*
Y549647D01*
X-284011Y549564D01*
G01X-277078Y547814D02*
X-277661Y548147D01*
X-278161Y548230D01*
X-278828Y548064D01*
X-279328Y547730D01*
X-279661Y547147D01*
X-279744Y546564D01*
X-279661Y545980D01*
X-279328Y545480D01*
X-278828Y545064D01*
X-278161Y544897D01*
X-277578Y545064D01*
X-277078Y545397D01*
G01X-268878Y544897D02*
Y549897D01*
X-266878D01*
X-266211Y549647D01*
X-265711Y549064D01*
X-265544Y548397D01*
X-265711Y547730D01*
X-266128Y547230D01*
X-266878Y546980D01*
X-268878D01*
G01X-262861Y547147D02*
X-260194D01*
X-260444Y547730D01*
X-260861Y548064D01*
X-261444Y548230D01*
X-262028Y548147D01*
X-262528Y547897D01*
X-262861Y547314D01*
X-263028Y546814D01*
Y546314D01*
X-262861Y545814D01*
X-262444Y545314D01*
X-261944Y544980D01*
X-261361Y544897D01*
X-260778Y545064D01*
X-260194Y545564D01*
G01X-257178Y544897D02*
Y548230D01*
G01Y547564D02*
X-256761Y547897D01*
X-256344Y548147D01*
X-255761Y548230D01*
X-255344Y548147D01*
X-254844Y547897D01*
G01X-250911Y544897D02*
Y549147D01*
X-250744Y549564D01*
X-250411Y549814D01*
X-249911Y549897D01*
X-249411Y549730D01*
X-249161Y549314D01*
G01X-250161Y547897D02*
X-251828D01*
G01X-244811Y544897D02*
X-245311Y544980D01*
X-245811Y545314D01*
X-246144Y545897D01*
X-246311Y546564D01*
X-246144Y547230D01*
X-245811Y547814D01*
X-245311Y548147D01*
X-244811Y548230D01*
X-244311Y548147D01*
X-243811Y547814D01*
X-243478Y547230D01*
X-243394Y546564D01*
X-243478Y545897D01*
X-243811Y545314D01*
X-244311Y544980D01*
X-244811Y544897D01*
G01X-240378D02*
Y548230D01*
G01Y547564D02*
X-239961Y547897D01*
X-239544Y548147D01*
X-238961Y548230D01*
X-238544Y548147D01*
X-238044Y547897D01*
G01X-236111Y544897D02*
Y548230D01*
G01Y547314D02*
X-235861Y547730D01*
X-235444Y548064D01*
X-234861Y548230D01*
X-234278Y548064D01*
X-233861Y547730D01*
X-233611Y547314D01*
Y544897D01*
G01Y547314D02*
X-233361Y547730D01*
X-232944Y548064D01*
X-232361Y548230D01*
X-231778Y548064D01*
X-231361Y547730D01*
X-231111Y547230D01*
Y544897D01*
G01X-226511D02*
Y548230D01*
G01Y547647D02*
X-226844Y547980D01*
X-227344Y548147D01*
X-227928Y548230D01*
X-228511Y548064D01*
X-229011Y547730D01*
X-229344Y547230D01*
X-229511Y546564D01*
X-229344Y545897D01*
X-229011Y545397D01*
X-228511Y545064D01*
X-227928Y544897D01*
X-227344Y544980D01*
X-226844Y545230D01*
X-226511Y545564D01*
G01X-223828Y544897D02*
Y548230D01*
G01Y547397D02*
X-223494Y547814D01*
X-222994Y548147D01*
X-222328Y548230D01*
X-221744Y548147D01*
X-221244Y547814D01*
X-220994Y547230D01*
Y544897D01*
G01X-215478Y547814D02*
X-216061Y548147D01*
X-216561Y548230D01*
X-217228Y548064D01*
X-217728Y547730D01*
X-218061Y547147D01*
X-218144Y546564D01*
X-218061Y545980D01*
X-217728Y545480D01*
X-217228Y545064D01*
X-216561Y544897D01*
X-215978Y545064D01*
X-215478Y545397D01*
G01X-212461Y547147D02*
X-209794D01*
X-210044Y547730D01*
X-210461Y548064D01*
X-211044Y548230D01*
X-211628Y548147D01*
X-212128Y547897D01*
X-212461Y547314D01*
X-212628Y546814D01*
Y546314D01*
X-212461Y545814D01*
X-212044Y545314D01*
X-211544Y544980D01*
X-210961Y544897D01*
X-210378Y545064D01*
X-209794Y545564D01*
G01X-201761D02*
X-201094Y545147D01*
X-200344Y544897D01*
X-199678D01*
X-199011Y545147D01*
X-198511Y545564D01*
X-198261Y546147D01*
X-198428Y546730D01*
X-198844Y547230D01*
X-199594Y547564D01*
X-200594Y547730D01*
X-201178Y548064D01*
X-201428Y548647D01*
X-201261Y549230D01*
X-200844Y549647D01*
X-200261Y549897D01*
X-199678D01*
X-199094Y549730D01*
X-198594Y549314D01*
G01X-195911Y543230D02*
Y548230D01*
G01Y547480D02*
X-195494Y547897D01*
X-195078Y548147D01*
X-194411Y548230D01*
X-193828Y548147D01*
X-193244Y547730D01*
X-192994Y547147D01*
X-192911Y546564D01*
X-192994Y545980D01*
X-193244Y545397D01*
X-193744Y545064D01*
X-194411Y544897D01*
X-194994Y544980D01*
X-195578Y545230D01*
X-195911Y545564D01*
G01X-190061Y547147D02*
X-187394D01*
X-187644Y547730D01*
X-188061Y548064D01*
X-188644Y548230D01*
X-189228Y548147D01*
X-189728Y547897D01*
X-190061Y547314D01*
X-190228Y546814D01*
Y546314D01*
X-190061Y545814D01*
X-189644Y545314D01*
X-189144Y544980D01*
X-188561Y544897D01*
X-187978Y545064D01*
X-187394Y545564D01*
G01X-181878Y547814D02*
X-182461Y548147D01*
X-182961Y548230D01*
X-183628Y548064D01*
X-184128Y547730D01*
X-184461Y547147D01*
X-184544Y546564D01*
X-184461Y545980D01*
X-184128Y545480D01*
X-183628Y545064D01*
X-182961Y544897D01*
X-182378Y545064D01*
X-181878Y545397D01*
G01X-177611Y548230D02*
Y544897D01*
G01Y549564D02*
X-177778Y549647D01*
Y549814D01*
X-177611Y549897D01*
X-177444Y549814D01*
Y549647D01*
X-177611Y549564D01*
G01X-172511Y544897D02*
Y549147D01*
X-172344Y549564D01*
X-172011Y549814D01*
X-171511Y549897D01*
X-171011Y549730D01*
X-170761Y549314D01*
G01X-171761Y547897D02*
X-173428D01*
G01X-166411Y548230D02*
Y544897D01*
G01Y549564D02*
X-166578Y549647D01*
Y549814D01*
X-166411Y549897D01*
X-166244Y549814D01*
Y549647D01*
X-166411Y549564D01*
G01X-159478Y547814D02*
X-160061Y548147D01*
X-160561Y548230D01*
X-161228Y548064D01*
X-161728Y547730D01*
X-162061Y547147D01*
X-162144Y546564D01*
X-162061Y545980D01*
X-161728Y545480D01*
X-161228Y545064D01*
X-160561Y544897D01*
X-159978Y545064D01*
X-159478Y545397D01*
G01X-153711Y544897D02*
Y548230D01*
G01Y547647D02*
X-154044Y547980D01*
X-154544Y548147D01*
X-155128Y548230D01*
X-155711Y548064D01*
X-156211Y547730D01*
X-156544Y547230D01*
X-156711Y546564D01*
X-156544Y545897D01*
X-156211Y545397D01*
X-155711Y545064D01*
X-155128Y544897D01*
X-154544Y544980D01*
X-154044Y545230D01*
X-153711Y545564D01*
G01X-149611Y549897D02*
Y544897D01*
G01X-150778Y548230D02*
X-148444D01*
G01X-144011D02*
Y544897D01*
G01Y549564D02*
X-144178Y549647D01*
Y549814D01*
X-144011Y549897D01*
X-143844Y549814D01*
Y549647D01*
X-144011Y549564D01*
G01X-138411Y544897D02*
X-138911Y544980D01*
X-139411Y545314D01*
X-139744Y545897D01*
X-139911Y546564D01*
X-139744Y547230D01*
X-139411Y547814D01*
X-138911Y548147D01*
X-138411Y548230D01*
X-137911Y548147D01*
X-137411Y547814D01*
X-137078Y547230D01*
X-136994Y546564D01*
X-137078Y545897D01*
X-137411Y545314D01*
X-137911Y544980D01*
X-138411Y544897D01*
G01X-134228D02*
Y548230D01*
G01Y547397D02*
X-133894Y547814D01*
X-133394Y548147D01*
X-132728Y548230D01*
X-132144Y548147D01*
X-131644Y547814D01*
X-131394Y547230D01*
Y544897D01*
G01X-122111D02*
Y549147D01*
X-121944Y549564D01*
X-121611Y549814D01*
X-121111Y549897D01*
X-120611Y549730D01*
X-120361Y549314D01*
G01X-121361Y547897D02*
X-123028D01*
G01X-116011Y544897D02*
X-116511Y544980D01*
X-117011Y545314D01*
X-117344Y545897D01*
X-117511Y546564D01*
X-117344Y547230D01*
X-117011Y547814D01*
X-116511Y548147D01*
X-116011Y548230D01*
X-115511Y548147D01*
X-115011Y547814D01*
X-114678Y547230D01*
X-114594Y546564D01*
X-114678Y545897D01*
X-115011Y545314D01*
X-115511Y544980D01*
X-116011Y544897D01*
G01X-111578D02*
Y548230D01*
G01Y547564D02*
X-111161Y547897D01*
X-110744Y548147D01*
X-110161Y548230D01*
X-109744Y548147D01*
X-109244Y547897D01*
G01X-100878Y544897D02*
Y549897D01*
X-98878D01*
X-98211Y549647D01*
X-97711Y549064D01*
X-97544Y548397D01*
X-97711Y547730D01*
X-98128Y547230D01*
X-98878Y546980D01*
X-100878D01*
G01X-94778Y544897D02*
Y548230D01*
G01Y547564D02*
X-94361Y547897D01*
X-93944Y548147D01*
X-93361Y548230D01*
X-92944Y548147D01*
X-92444Y547897D01*
G01X-88011Y548230D02*
Y544897D01*
G01Y549564D02*
X-88178Y549647D01*
Y549814D01*
X-88011Y549897D01*
X-87844Y549814D01*
Y549647D01*
X-88011Y549564D01*
G01X-83828Y544897D02*
Y548230D01*
G01Y547397D02*
X-83494Y547814D01*
X-82994Y548147D01*
X-82328Y548230D01*
X-81744Y548147D01*
X-81244Y547814D01*
X-80994Y547230D01*
Y544897D01*
G01X-76811Y549897D02*
Y544897D01*
G01X-77978Y548230D02*
X-75644D01*
G01X-72461Y547147D02*
X-69794D01*
X-70044Y547730D01*
X-70461Y548064D01*
X-71044Y548230D01*
X-71628Y548147D01*
X-72128Y547897D01*
X-72461Y547314D01*
X-72628Y546814D01*
Y546314D01*
X-72461Y545814D01*
X-72044Y545314D01*
X-71544Y544980D01*
X-70961Y544897D01*
X-70378Y545064D01*
X-69794Y545564D01*
G01X-64111Y549897D02*
Y544897D01*
G01Y545647D02*
X-64444Y545230D01*
X-64944Y544980D01*
X-65528Y544897D01*
X-66194Y545064D01*
X-66694Y545480D01*
X-67028Y545980D01*
X-67111Y546564D01*
X-67028Y547147D01*
X-66694Y547647D01*
X-66194Y548064D01*
X-65528Y548230D01*
X-64944Y548147D01*
X-64528Y547980D01*
X-64111Y547647D01*
G01X-53744Y547564D02*
X-53411Y547814D01*
X-53161Y548230D01*
X-52994Y548814D01*
X-53161Y549314D01*
X-53494Y549647D01*
X-54078Y549897D01*
X-56328D01*
Y544897D01*
X-53578D01*
X-52994Y545230D01*
X-52661Y545730D01*
X-52494Y546314D01*
X-52661Y546897D01*
X-53161Y547397D01*
X-53744Y547564D01*
X-56328D01*
G01X-48811Y544897D02*
X-49311Y544980D01*
X-49811Y545314D01*
X-50144Y545897D01*
X-50311Y546564D01*
X-50144Y547230D01*
X-49811Y547814D01*
X-49311Y548147D01*
X-48811Y548230D01*
X-48311Y548147D01*
X-47811Y547814D01*
X-47478Y547230D01*
X-47394Y546564D01*
X-47478Y545897D01*
X-47811Y545314D01*
X-48311Y544980D01*
X-48811Y544897D01*
G01X-41711D02*
Y548230D01*
G01Y547647D02*
X-42044Y547980D01*
X-42544Y548147D01*
X-43128Y548230D01*
X-43711Y548064D01*
X-44211Y547730D01*
X-44544Y547230D01*
X-44711Y546564D01*
X-44544Y545897D01*
X-44211Y545397D01*
X-43711Y545064D01*
X-43128Y544897D01*
X-42544Y544980D01*
X-42044Y545230D01*
X-41711Y545564D01*
G01X-38778Y544897D02*
Y548230D01*
G01Y547564D02*
X-38361Y547897D01*
X-37944Y548147D01*
X-37361Y548230D01*
X-36944Y548147D01*
X-36444Y547897D01*
G01X-30511Y549897D02*
Y544897D01*
G01Y545647D02*
X-30844Y545230D01*
X-31344Y544980D01*
X-31928Y544897D01*
X-32594Y545064D01*
X-33094Y545480D01*
X-33428Y545980D01*
X-33511Y546564D01*
X-33428Y547147D01*
X-33094Y547647D01*
X-32594Y548064D01*
X-31928Y548230D01*
X-31344Y548147D01*
X-30928Y547980D01*
X-30511Y547647D01*
G01X-27661Y545480D02*
X-27244Y545147D01*
X-26661Y544897D01*
X-26161D01*
X-25661Y545064D01*
X-25328Y545314D01*
X-25161Y545647D01*
X-25244Y546147D01*
X-25578Y546397D01*
X-27078Y546897D01*
X-27411Y547480D01*
X-27244Y547897D01*
X-26911Y548147D01*
X-26411Y548230D01*
X-25911Y548147D01*
X-25411Y547897D01*
G01X-363411Y557797D02*
X-361411D01*
G01X-362411D02*
Y552797D01*
G01X-363411D02*
X-361411D01*
G01X-358478D02*
Y557797D01*
X-356478D01*
X-355811Y557547D01*
X-355311Y556964D01*
X-355144Y556297D01*
X-355311Y555630D01*
X-355728Y555130D01*
X-356478Y554880D01*
X-358478D01*
G01X-349378Y557380D02*
X-349878Y557630D01*
X-350461Y557797D01*
X-351128D01*
X-351878Y557547D01*
X-352461Y557130D01*
X-352878Y556630D01*
X-353211Y555797D01*
X-353294Y555047D01*
X-353128Y554297D01*
X-352878Y553797D01*
X-352378Y553297D01*
X-351794Y552964D01*
X-351211Y552797D01*
X-350628D01*
X-350044Y552964D01*
X-349544Y553214D01*
X-349128Y553547D01*
G01X-346694Y554464D02*
X-344528D01*
G01X-342094Y552797D02*
X-340011Y557797D01*
X-337928Y552797D01*
G01X-338678Y554547D02*
X-341344D01*
G01X-335494Y554464D02*
X-333328D01*
G01X-330394Y554880D02*
X-329811Y555464D01*
X-329311Y555797D01*
X-328644Y555964D01*
X-328061Y555797D01*
X-327644Y555464D01*
X-327311Y554964D01*
X-327228Y554380D01*
X-327311Y553880D01*
X-327644Y553380D01*
X-328144Y552964D01*
X-328728Y552797D01*
X-329394Y552964D01*
X-329978Y553464D01*
X-330311Y554214D01*
X-330394Y555047D01*
X-330228Y556130D01*
X-329978Y556714D01*
X-329561Y557297D01*
X-328978Y557714D01*
X-328394Y557797D01*
X-327811Y557630D01*
X-327394Y557214D01*
G01X-323211Y557797D02*
X-323878Y557630D01*
X-324378Y557214D01*
X-324711Y556714D01*
X-324961Y556047D01*
X-325044Y555297D01*
X-324961Y554547D01*
X-324711Y553880D01*
X-324378Y553380D01*
X-323878Y552964D01*
X-323211Y552797D01*
X-322544Y552964D01*
X-322044Y553380D01*
X-321711Y553880D01*
X-321461Y554547D01*
X-321378Y555297D01*
X-321461Y556047D01*
X-321711Y556714D01*
X-322044Y557214D01*
X-322544Y557630D01*
X-323211Y557797D01*
G01X-317611D02*
X-318278Y557630D01*
X-318778Y557214D01*
X-319111Y556714D01*
X-319361Y556047D01*
X-319444Y555297D01*
X-319361Y554547D01*
X-319111Y553880D01*
X-318778Y553380D01*
X-318278Y552964D01*
X-317611Y552797D01*
X-316944Y552964D01*
X-316444Y553380D01*
X-316111Y553880D01*
X-315861Y554547D01*
X-315778Y555297D01*
X-315861Y556047D01*
X-316111Y556714D01*
X-316444Y557214D01*
X-316944Y557630D01*
X-317611Y557797D01*
G01X-308494Y552797D02*
X-306411Y557797D01*
X-304328Y552797D01*
G01X-305078Y554547D02*
X-307744D01*
G01X-299478Y555714D02*
X-300061Y556047D01*
X-300561Y556130D01*
X-301228Y555964D01*
X-301728Y555630D01*
X-302061Y555047D01*
X-302144Y554464D01*
X-302061Y553880D01*
X-301728Y553380D01*
X-301228Y552964D01*
X-300561Y552797D01*
X-299978Y552964D01*
X-299478Y553297D01*
G01X-293878Y555714D02*
X-294461Y556047D01*
X-294961Y556130D01*
X-295628Y555964D01*
X-296128Y555630D01*
X-296461Y555047D01*
X-296544Y554464D01*
X-296461Y553880D01*
X-296128Y553380D01*
X-295628Y552964D01*
X-294961Y552797D01*
X-294378Y552964D01*
X-293878Y553297D01*
G01X-290861Y555047D02*
X-288194D01*
X-288444Y555630D01*
X-288861Y555964D01*
X-289444Y556130D01*
X-290028Y556047D01*
X-290528Y555797D01*
X-290861Y555214D01*
X-291028Y554714D01*
Y554214D01*
X-290861Y553714D01*
X-290444Y553214D01*
X-289944Y552880D01*
X-289361Y552797D01*
X-288778Y552964D01*
X-288194Y553464D01*
G01X-285511Y551130D02*
Y556130D01*
G01Y555380D02*
X-285094Y555797D01*
X-284678Y556047D01*
X-284011Y556130D01*
X-283428Y556047D01*
X-282844Y555630D01*
X-282594Y555047D01*
X-282511Y554464D01*
X-282594Y553880D01*
X-282844Y553297D01*
X-283344Y552964D01*
X-284011Y552797D01*
X-284594Y552880D01*
X-285178Y553130D01*
X-285511Y553464D01*
G01X-278411Y557797D02*
Y552797D01*
G01X-279578Y556130D02*
X-277244D01*
G01X-271311Y552797D02*
Y556130D01*
G01Y555547D02*
X-271644Y555880D01*
X-272144Y556047D01*
X-272728Y556130D01*
X-273311Y555964D01*
X-273811Y555630D01*
X-274144Y555130D01*
X-274311Y554464D01*
X-274144Y553797D01*
X-273811Y553297D01*
X-273311Y552964D01*
X-272728Y552797D01*
X-272144Y552880D01*
X-271644Y553130D01*
X-271311Y553464D01*
G01X-268711Y552797D02*
Y557797D01*
G01Y555297D02*
X-268294Y555797D01*
X-267794Y556047D01*
X-267294Y556130D01*
X-266544Y555964D01*
X-266044Y555630D01*
X-265711Y555047D01*
Y554380D01*
X-265878Y553714D01*
X-266211Y553214D01*
X-266794Y552880D01*
X-267294Y552797D01*
X-267794Y552880D01*
X-268294Y553130D01*
X-268711Y553547D01*
G01X-261611Y556130D02*
Y552797D01*
G01Y557464D02*
X-261778Y557547D01*
Y557714D01*
X-261611Y557797D01*
X-261444Y557714D01*
Y557547D01*
X-261611Y557464D01*
G01X-256011Y552797D02*
Y557797D01*
G01X-250411Y556130D02*
Y552797D01*
G01Y557464D02*
X-250578Y557547D01*
Y557714D01*
X-250411Y557797D01*
X-250244Y557714D01*
Y557547D01*
X-250411Y557464D01*
G01X-244811Y557797D02*
Y552797D01*
G01X-245978Y556130D02*
X-243644D01*
G01X-240961Y551297D02*
X-240461Y551130D01*
X-239794Y551297D01*
X-239378Y551630D01*
X-239044Y552047D01*
X-238544Y553380D01*
X-237461Y556130D01*
G01X-240128D02*
X-238544Y553380D01*
G01X-228011Y552797D02*
X-228511Y552880D01*
X-229011Y553214D01*
X-229344Y553797D01*
X-229511Y554464D01*
X-229344Y555130D01*
X-229011Y555714D01*
X-228511Y556047D01*
X-228011Y556130D01*
X-227511Y556047D01*
X-227011Y555714D01*
X-226678Y555130D01*
X-226594Y554464D01*
X-226678Y553797D01*
X-227011Y553214D01*
X-227511Y552880D01*
X-228011Y552797D01*
G01X-222911D02*
Y557047D01*
X-222744Y557464D01*
X-222411Y557714D01*
X-221911Y557797D01*
X-221411Y557630D01*
X-221161Y557214D01*
G01X-222161Y555797D02*
X-223828D01*
G01X-212878Y552797D02*
Y557797D01*
X-210878D01*
X-210211Y557547D01*
X-209711Y556964D01*
X-209544Y556297D01*
X-209711Y555630D01*
X-210128Y555130D01*
X-210878Y554880D01*
X-212878D01*
G01X-206778Y552797D02*
Y556130D01*
G01Y555464D02*
X-206361Y555797D01*
X-205944Y556047D01*
X-205361Y556130D01*
X-204944Y556047D01*
X-204444Y555797D01*
G01X-200011Y556130D02*
Y552797D01*
G01Y557464D02*
X-200178Y557547D01*
Y557714D01*
X-200011Y557797D01*
X-199844Y557714D01*
Y557547D01*
X-200011Y557464D01*
G01X-195828Y552797D02*
Y556130D01*
G01Y555297D02*
X-195494Y555714D01*
X-194994Y556047D01*
X-194328Y556130D01*
X-193744Y556047D01*
X-193244Y555714D01*
X-192994Y555130D01*
Y552797D01*
G01X-188811Y557797D02*
Y552797D01*
G01X-189978Y556130D02*
X-187644D01*
G01X-184461Y555047D02*
X-181794D01*
X-182044Y555630D01*
X-182461Y555964D01*
X-183044Y556130D01*
X-183628Y556047D01*
X-184128Y555797D01*
X-184461Y555214D01*
X-184628Y554714D01*
Y554214D01*
X-184461Y553714D01*
X-184044Y553214D01*
X-183544Y552880D01*
X-182961Y552797D01*
X-182378Y552964D01*
X-181794Y553464D01*
G01X-176111Y557797D02*
Y552797D01*
G01Y553547D02*
X-176444Y553130D01*
X-176944Y552880D01*
X-177528Y552797D01*
X-178194Y552964D01*
X-178694Y553380D01*
X-179028Y553880D01*
X-179111Y554464D01*
X-179028Y555047D01*
X-178694Y555547D01*
X-178194Y555964D01*
X-177528Y556130D01*
X-176944Y556047D01*
X-176528Y555880D01*
X-176111Y555547D01*
G01X-165744Y555464D02*
X-165411Y555714D01*
X-165161Y556130D01*
X-164994Y556714D01*
X-165161Y557214D01*
X-165494Y557547D01*
X-166078Y557797D01*
X-168328D01*
Y552797D01*
X-165578D01*
X-164994Y553130D01*
X-164661Y553630D01*
X-164494Y554214D01*
X-164661Y554797D01*
X-165161Y555297D01*
X-165744Y555464D01*
X-168328D01*
G01X-160811Y552797D02*
X-161311Y552880D01*
X-161811Y553214D01*
X-162144Y553797D01*
X-162311Y554464D01*
X-162144Y555130D01*
X-161811Y555714D01*
X-161311Y556047D01*
X-160811Y556130D01*
X-160311Y556047D01*
X-159811Y555714D01*
X-159478Y555130D01*
X-159394Y554464D01*
X-159478Y553797D01*
X-159811Y553214D01*
X-160311Y552880D01*
X-160811Y552797D01*
G01X-153711D02*
Y556130D01*
G01Y555547D02*
X-154044Y555880D01*
X-154544Y556047D01*
X-155128Y556130D01*
X-155711Y555964D01*
X-156211Y555630D01*
X-156544Y555130D01*
X-156711Y554464D01*
X-156544Y553797D01*
X-156211Y553297D01*
X-155711Y552964D01*
X-155128Y552797D01*
X-154544Y552880D01*
X-154044Y553130D01*
X-153711Y553464D01*
G01X-150778Y552797D02*
Y556130D01*
G01Y555464D02*
X-150361Y555797D01*
X-149944Y556047D01*
X-149361Y556130D01*
X-148944Y556047D01*
X-148444Y555797D01*
G01X-142511Y557797D02*
Y552797D01*
G01Y553547D02*
X-142844Y553130D01*
X-143344Y552880D01*
X-143928Y552797D01*
X-144594Y552964D01*
X-145094Y553380D01*
X-145428Y553880D01*
X-145511Y554464D01*
X-145428Y555047D01*
X-145094Y555547D01*
X-144594Y555964D01*
X-143928Y556130D01*
X-143344Y556047D01*
X-142928Y555880D01*
X-142511Y555547D01*
G01X-139661Y553380D02*
X-139244Y553047D01*
X-138661Y552797D01*
X-138161D01*
X-137661Y552964D01*
X-137328Y553214D01*
X-137161Y553547D01*
X-137244Y554047D01*
X-137578Y554297D01*
X-139078Y554797D01*
X-139411Y555380D01*
X-139244Y555797D01*
X-138911Y556047D01*
X-138411Y556130D01*
X-137911Y556047D01*
X-137411Y555797D01*
G01X-377411Y568797D02*
X-375411D01*
G01X-376411D02*
Y563797D01*
G01X-377411D02*
X-375411D01*
G01X-371311D02*
Y568047D01*
X-371144Y568464D01*
X-370811Y568714D01*
X-370311Y568797D01*
X-369811Y568630D01*
X-369561Y568214D01*
G01X-370561Y566797D02*
X-372228D01*
G01X-359611Y568797D02*
Y563797D01*
G01X-360778Y567130D02*
X-358444D01*
G01X-355428Y563797D02*
Y568797D01*
G01Y566380D02*
X-355011Y566797D01*
X-354594Y567047D01*
X-353928Y567130D01*
X-353428Y567047D01*
X-352844Y566714D01*
X-352594Y566214D01*
Y563797D01*
G01X-349661Y566047D02*
X-346994D01*
X-347244Y566630D01*
X-347661Y566964D01*
X-348244Y567130D01*
X-348828Y567047D01*
X-349328Y566797D01*
X-349661Y566214D01*
X-349828Y565714D01*
Y565214D01*
X-349661Y564714D01*
X-349244Y564214D01*
X-348744Y563880D01*
X-348161Y563797D01*
X-347578Y563964D01*
X-346994Y564464D01*
G01X-335878Y566714D02*
X-336461Y567047D01*
X-336961Y567130D01*
X-337628Y566964D01*
X-338128Y566630D01*
X-338461Y566047D01*
X-338544Y565464D01*
X-338461Y564880D01*
X-338128Y564380D01*
X-337628Y563964D01*
X-336961Y563797D01*
X-336378Y563964D01*
X-335878Y564297D01*
G01X-332778Y563797D02*
Y567130D01*
G01Y566464D02*
X-332361Y566797D01*
X-331944Y567047D01*
X-331361Y567130D01*
X-330944Y567047D01*
X-330444Y566797D01*
G01X-326011Y567130D02*
Y563797D01*
G01Y568464D02*
X-326178Y568547D01*
Y568714D01*
X-326011Y568797D01*
X-325844Y568714D01*
Y568547D01*
X-326011Y568464D01*
G01X-320411Y568797D02*
Y563797D01*
G01X-321578Y567130D02*
X-319244D01*
G01X-316061Y566047D02*
X-313394D01*
X-313644Y566630D01*
X-314061Y566964D01*
X-314644Y567130D01*
X-315228Y567047D01*
X-315728Y566797D01*
X-316061Y566214D01*
X-316228Y565714D01*
Y565214D01*
X-316061Y564714D01*
X-315644Y564214D01*
X-315144Y563880D01*
X-314561Y563797D01*
X-313978Y563964D01*
X-313394Y564464D01*
G01X-310378Y563797D02*
Y567130D01*
G01Y566464D02*
X-309961Y566797D01*
X-309544Y567047D01*
X-308961Y567130D01*
X-308544Y567047D01*
X-308044Y566797D01*
G01X-303611Y567130D02*
Y563797D01*
G01Y568464D02*
X-303778Y568547D01*
Y568714D01*
X-303611Y568797D01*
X-303444Y568714D01*
Y568547D01*
X-303611Y568464D01*
G01X-296511Y563797D02*
Y567130D01*
G01Y566547D02*
X-296844Y566880D01*
X-297344Y567047D01*
X-297928Y567130D01*
X-298511Y566964D01*
X-299011Y566630D01*
X-299344Y566130D01*
X-299511Y565464D01*
X-299344Y564797D01*
X-299011Y564297D01*
X-298511Y563964D01*
X-297928Y563797D01*
X-297344Y563880D01*
X-296844Y564130D01*
X-296511Y564464D01*
G01X-286811Y567130D02*
Y563797D01*
G01Y568464D02*
X-286978Y568547D01*
Y568714D01*
X-286811Y568797D01*
X-286644Y568714D01*
Y568547D01*
X-286811Y568464D01*
G01X-282461Y564380D02*
X-282044Y564047D01*
X-281461Y563797D01*
X-280961D01*
X-280461Y563964D01*
X-280128Y564214D01*
X-279961Y564547D01*
X-280044Y565047D01*
X-280378Y565297D01*
X-281878Y565797D01*
X-282211Y566380D01*
X-282044Y566797D01*
X-281711Y567047D01*
X-281211Y567130D01*
X-280711Y567047D01*
X-280211Y566797D01*
G01X-271428Y563797D02*
Y567130D01*
G01Y566297D02*
X-271094Y566714D01*
X-270594Y567047D01*
X-269928Y567130D01*
X-269344Y567047D01*
X-268844Y566714D01*
X-268594Y566130D01*
Y563797D01*
G01X-264411D02*
X-264911Y563880D01*
X-265411Y564214D01*
X-265744Y564797D01*
X-265911Y565464D01*
X-265744Y566130D01*
X-265411Y566714D01*
X-264911Y567047D01*
X-264411Y567130D01*
X-263911Y567047D01*
X-263411Y566714D01*
X-263078Y566130D01*
X-262994Y565464D01*
X-263078Y564797D01*
X-263411Y564214D01*
X-263911Y563880D01*
X-264411Y563797D01*
G01X-258811Y568797D02*
Y563797D01*
G01X-259978Y567130D02*
X-257644D01*
G01X-248861Y564380D02*
X-248444Y564047D01*
X-247861Y563797D01*
X-247361D01*
X-246861Y563964D01*
X-246528Y564214D01*
X-246361Y564547D01*
X-246444Y565047D01*
X-246778Y565297D01*
X-248278Y565797D01*
X-248611Y566380D01*
X-248444Y566797D01*
X-248111Y567047D01*
X-247611Y567130D01*
X-247111Y567047D01*
X-246611Y566797D01*
G01X-243511Y562130D02*
Y567130D01*
G01Y566380D02*
X-243094Y566797D01*
X-242678Y567047D01*
X-242011Y567130D01*
X-241428Y567047D01*
X-240844Y566630D01*
X-240594Y566047D01*
X-240511Y565464D01*
X-240594Y564880D01*
X-240844Y564297D01*
X-241344Y563964D01*
X-242011Y563797D01*
X-242594Y563880D01*
X-243178Y564130D01*
X-243511Y564464D01*
G01X-237661Y566047D02*
X-234994D01*
X-235244Y566630D01*
X-235661Y566964D01*
X-236244Y567130D01*
X-236828Y567047D01*
X-237328Y566797D01*
X-237661Y566214D01*
X-237828Y565714D01*
Y565214D01*
X-237661Y564714D01*
X-237244Y564214D01*
X-236744Y563880D01*
X-236161Y563797D01*
X-235578Y563964D01*
X-234994Y564464D01*
G01X-229478Y566714D02*
X-230061Y567047D01*
X-230561Y567130D01*
X-231228Y566964D01*
X-231728Y566630D01*
X-232061Y566047D01*
X-232144Y565464D01*
X-232061Y564880D01*
X-231728Y564380D01*
X-231228Y563964D01*
X-230561Y563797D01*
X-229978Y563964D01*
X-229478Y564297D01*
G01X-225211Y567130D02*
Y563797D01*
G01Y568464D02*
X-225378Y568547D01*
Y568714D01*
X-225211Y568797D01*
X-225044Y568714D01*
Y568547D01*
X-225211Y568464D01*
G01X-220111Y563797D02*
Y568047D01*
X-219944Y568464D01*
X-219611Y568714D01*
X-219111Y568797D01*
X-218611Y568630D01*
X-218361Y568214D01*
G01X-219361Y566797D02*
X-221028D01*
G01X-214011Y567130D02*
Y563797D01*
G01Y568464D02*
X-214178Y568547D01*
Y568714D01*
X-214011Y568797D01*
X-213844Y568714D01*
Y568547D01*
X-214011Y568464D01*
G01X-209661Y566047D02*
X-206994D01*
X-207244Y566630D01*
X-207661Y566964D01*
X-208244Y567130D01*
X-208828Y567047D01*
X-209328Y566797D01*
X-209661Y566214D01*
X-209828Y565714D01*
Y565214D01*
X-209661Y564714D01*
X-209244Y564214D01*
X-208744Y563880D01*
X-208161Y563797D01*
X-207578Y563964D01*
X-206994Y564464D01*
G01X-201311Y568797D02*
Y563797D01*
G01Y564547D02*
X-201644Y564130D01*
X-202144Y563880D01*
X-202728Y563797D01*
X-203394Y563964D01*
X-203894Y564380D01*
X-204228Y564880D01*
X-204311Y565464D01*
X-204228Y566047D01*
X-203894Y566547D01*
X-203394Y566964D01*
X-202728Y567130D01*
X-202144Y567047D01*
X-201728Y566880D01*
X-201311Y566547D01*
G01X-191611Y567130D02*
Y563797D01*
G01Y568464D02*
X-191778Y568547D01*
Y568714D01*
X-191611Y568797D01*
X-191444Y568714D01*
Y568547D01*
X-191611Y568464D01*
G01X-187428Y563797D02*
Y567130D01*
G01Y566297D02*
X-187094Y566714D01*
X-186594Y567047D01*
X-185928Y567130D01*
X-185344Y567047D01*
X-184844Y566714D01*
X-184594Y566130D01*
Y563797D01*
G01X-174811Y568797D02*
Y563797D01*
G01X-175978Y567130D02*
X-173644D01*
G01X-170628Y563797D02*
Y568797D01*
G01Y566380D02*
X-170211Y566797D01*
X-169794Y567047D01*
X-169128Y567130D01*
X-168628Y567047D01*
X-168044Y566714D01*
X-167794Y566214D01*
Y563797D01*
G01X-164861Y566047D02*
X-162194D01*
X-162444Y566630D01*
X-162861Y566964D01*
X-163444Y567130D01*
X-164028Y567047D01*
X-164528Y566797D01*
X-164861Y566214D01*
X-165028Y565714D01*
Y565214D01*
X-164861Y564714D01*
X-164444Y564214D01*
X-163944Y563880D01*
X-163361Y563797D01*
X-162778Y563964D01*
X-162194Y564464D01*
G01X-152411Y568797D02*
Y563797D01*
G01X-153578Y567130D02*
X-151244D01*
G01X-145311Y563797D02*
Y567130D01*
G01Y566547D02*
X-145644Y566880D01*
X-146144Y567047D01*
X-146728Y567130D01*
X-147311Y566964D01*
X-147811Y566630D01*
X-148144Y566130D01*
X-148311Y565464D01*
X-148144Y564797D01*
X-147811Y564297D01*
X-147311Y563964D01*
X-146728Y563797D01*
X-146144Y563880D01*
X-145644Y564130D01*
X-145311Y564464D01*
G01X-142711Y563797D02*
Y568797D01*
G01Y566297D02*
X-142294Y566797D01*
X-141794Y567047D01*
X-141294Y567130D01*
X-140544Y566964D01*
X-140044Y566630D01*
X-139711Y566047D01*
Y565380D01*
X-139878Y564714D01*
X-140211Y564214D01*
X-140794Y563880D01*
X-141294Y563797D01*
X-141794Y563880D01*
X-142294Y564130D01*
X-142711Y564547D01*
G01X-135611Y563797D02*
Y568797D01*
G01X-131261Y566047D02*
X-128594D01*
X-128844Y566630D01*
X-129261Y566964D01*
X-129844Y567130D01*
X-130428Y567047D01*
X-130928Y566797D01*
X-131261Y566214D01*
X-131428Y565714D01*
Y565214D01*
X-131261Y564714D01*
X-130844Y564214D01*
X-130344Y563880D01*
X-129761Y563797D01*
X-129178Y563964D01*
X-128594Y564464D01*
G01X-124411Y563630D02*
X-124578Y563714D01*
Y563880D01*
X-124411Y563964D01*
X-124244Y563880D01*
Y563714D01*
X-124411Y563630D01*
G01Y565880D02*
X-124578Y565964D01*
Y566130D01*
X-124411Y566214D01*
X-124244Y566130D01*
Y565964D01*
X-124411Y565880D01*
G01X-376578Y572797D02*
Y577797D01*
X-374578D01*
X-373911Y577547D01*
X-373411Y576964D01*
X-373244Y576297D01*
X-373411Y575630D01*
X-373828Y575130D01*
X-374578Y574880D01*
X-376578D01*
G01X-369311Y572797D02*
Y577797D01*
G01X-364961Y575047D02*
X-362294D01*
X-362544Y575630D01*
X-362961Y575964D01*
X-363544Y576130D01*
X-364128Y576047D01*
X-364628Y575797D01*
X-364961Y575214D01*
X-365128Y574714D01*
Y574214D01*
X-364961Y573714D01*
X-364544Y573214D01*
X-364044Y572880D01*
X-363461Y572797D01*
X-362878Y572964D01*
X-362294Y573464D01*
G01X-356611Y572797D02*
Y576130D01*
G01Y575547D02*
X-356944Y575880D01*
X-357444Y576047D01*
X-358028Y576130D01*
X-358611Y575964D01*
X-359111Y575630D01*
X-359444Y575130D01*
X-359611Y574464D01*
X-359444Y573797D01*
X-359111Y573297D01*
X-358611Y572964D01*
X-358028Y572797D01*
X-357444Y572880D01*
X-356944Y573130D01*
X-356611Y573464D01*
G01X-353761Y573380D02*
X-353344Y573047D01*
X-352761Y572797D01*
X-352261D01*
X-351761Y572964D01*
X-351428Y573214D01*
X-351261Y573547D01*
X-351344Y574047D01*
X-351678Y574297D01*
X-353178Y574797D01*
X-353511Y575380D01*
X-353344Y575797D01*
X-353011Y576047D01*
X-352511Y576130D01*
X-352011Y576047D01*
X-351511Y575797D01*
G01X-348161Y575047D02*
X-345494D01*
X-345744Y575630D01*
X-346161Y575964D01*
X-346744Y576130D01*
X-347328Y576047D01*
X-347828Y575797D01*
X-348161Y575214D01*
X-348328Y574714D01*
Y574214D01*
X-348161Y573714D01*
X-347744Y573214D01*
X-347244Y572880D01*
X-346661Y572797D01*
X-346078Y572964D01*
X-345494Y573464D01*
G01X-336211Y572797D02*
Y577047D01*
X-336044Y577464D01*
X-335711Y577714D01*
X-335211Y577797D01*
X-334711Y577630D01*
X-334461Y577214D01*
G01X-335461Y575797D02*
X-337128D01*
G01X-330111Y572797D02*
X-330611Y572880D01*
X-331111Y573214D01*
X-331444Y573797D01*
X-331611Y574464D01*
X-331444Y575130D01*
X-331111Y575714D01*
X-330611Y576047D01*
X-330111Y576130D01*
X-329611Y576047D01*
X-329111Y575714D01*
X-328778Y575130D01*
X-328694Y574464D01*
X-328778Y573797D01*
X-329111Y573214D01*
X-329611Y572880D01*
X-330111Y572797D01*
G01X-324511D02*
Y577797D01*
G01X-318911Y572797D02*
Y577797D01*
G01X-313311Y572797D02*
X-313811Y572880D01*
X-314311Y573214D01*
X-314644Y573797D01*
X-314811Y574464D01*
X-314644Y575130D01*
X-314311Y575714D01*
X-313811Y576047D01*
X-313311Y576130D01*
X-312811Y576047D01*
X-312311Y575714D01*
X-311978Y575130D01*
X-311894Y574464D01*
X-311978Y573797D01*
X-312311Y573214D01*
X-312811Y572880D01*
X-313311Y572797D01*
G01X-309794Y576130D02*
X-308794Y572797D01*
X-307711Y576130D01*
X-306628Y572797D01*
X-305628Y576130D01*
G01X-296511Y577797D02*
Y572797D01*
G01X-297678Y576130D02*
X-295344D01*
G01X-292328Y572797D02*
Y577797D01*
G01Y575380D02*
X-291911Y575797D01*
X-291494Y576047D01*
X-290828Y576130D01*
X-290328Y576047D01*
X-289744Y575714D01*
X-289494Y575214D01*
Y572797D01*
G01X-286561Y575047D02*
X-283894D01*
X-284144Y575630D01*
X-284561Y575964D01*
X-285144Y576130D01*
X-285728Y576047D01*
X-286228Y575797D01*
X-286561Y575214D01*
X-286728Y574714D01*
Y574214D01*
X-286561Y573714D01*
X-286144Y573214D01*
X-285644Y572880D01*
X-285061Y572797D01*
X-284478Y572964D01*
X-283894Y573464D01*
G01X-275361Y573380D02*
X-274944Y573047D01*
X-274361Y572797D01*
X-273861D01*
X-273361Y572964D01*
X-273028Y573214D01*
X-272861Y573547D01*
X-272944Y574047D01*
X-273278Y574297D01*
X-274778Y574797D01*
X-275111Y575380D01*
X-274944Y575797D01*
X-274611Y576047D01*
X-274111Y576130D01*
X-273611Y576047D01*
X-273111Y575797D01*
G01X-270011Y571130D02*
Y576130D01*
G01Y575380D02*
X-269594Y575797D01*
X-269178Y576047D01*
X-268511Y576130D01*
X-267928Y576047D01*
X-267344Y575630D01*
X-267094Y575047D01*
X-267011Y574464D01*
X-267094Y573880D01*
X-267344Y573297D01*
X-267844Y572964D01*
X-268511Y572797D01*
X-269094Y572880D01*
X-269678Y573130D01*
X-270011Y573464D01*
G01X-264161Y575047D02*
X-261494D01*
X-261744Y575630D01*
X-262161Y575964D01*
X-262744Y576130D01*
X-263328Y576047D01*
X-263828Y575797D01*
X-264161Y575214D01*
X-264328Y574714D01*
Y574214D01*
X-264161Y573714D01*
X-263744Y573214D01*
X-263244Y572880D01*
X-262661Y572797D01*
X-262078Y572964D01*
X-261494Y573464D01*
G01X-255978Y575714D02*
X-256561Y576047D01*
X-257061Y576130D01*
X-257728Y575964D01*
X-258228Y575630D01*
X-258561Y575047D01*
X-258644Y574464D01*
X-258561Y573880D01*
X-258228Y573380D01*
X-257728Y572964D01*
X-257061Y572797D01*
X-256478Y572964D01*
X-255978Y573297D01*
G01X-251711Y576130D02*
Y572797D01*
G01Y577464D02*
X-251878Y577547D01*
Y577714D01*
X-251711Y577797D01*
X-251544Y577714D01*
Y577547D01*
X-251711Y577464D01*
G01X-246611Y572797D02*
Y577047D01*
X-246444Y577464D01*
X-246111Y577714D01*
X-245611Y577797D01*
X-245111Y577630D01*
X-244861Y577214D01*
G01X-245861Y575797D02*
X-247528D01*
G01X-240511Y576130D02*
Y572797D01*
G01Y577464D02*
X-240678Y577547D01*
Y577714D01*
X-240511Y577797D01*
X-240344Y577714D01*
Y577547D01*
X-240511Y577464D01*
G01X-233578Y575714D02*
X-234161Y576047D01*
X-234661Y576130D01*
X-235328Y575964D01*
X-235828Y575630D01*
X-236161Y575047D01*
X-236244Y574464D01*
X-236161Y573880D01*
X-235828Y573380D01*
X-235328Y572964D01*
X-234661Y572797D01*
X-234078Y572964D01*
X-233578Y573297D01*
G01X-227811Y572797D02*
Y576130D01*
G01Y575547D02*
X-228144Y575880D01*
X-228644Y576047D01*
X-229228Y576130D01*
X-229811Y575964D01*
X-230311Y575630D01*
X-230644Y575130D01*
X-230811Y574464D01*
X-230644Y573797D01*
X-230311Y573297D01*
X-229811Y572964D01*
X-229228Y572797D01*
X-228644Y572880D01*
X-228144Y573130D01*
X-227811Y573464D01*
G01X-223711Y577797D02*
Y572797D01*
G01X-224878Y576130D02*
X-222544D01*
G01X-218111D02*
Y572797D01*
G01Y577464D02*
X-218278Y577547D01*
Y577714D01*
X-218111Y577797D01*
X-217944Y577714D01*
Y577547D01*
X-218111Y577464D01*
G01X-212511Y572797D02*
X-213011Y572880D01*
X-213511Y573214D01*
X-213844Y573797D01*
X-214011Y574464D01*
X-213844Y575130D01*
X-213511Y575714D01*
X-213011Y576047D01*
X-212511Y576130D01*
X-212011Y576047D01*
X-211511Y575714D01*
X-211178Y575130D01*
X-211094Y574464D01*
X-211178Y573797D01*
X-211511Y573214D01*
X-212011Y572880D01*
X-212511Y572797D01*
G01X-208328D02*
Y576130D01*
G01Y575297D02*
X-207994Y575714D01*
X-207494Y576047D01*
X-206828Y576130D01*
X-206244Y576047D01*
X-205744Y575714D01*
X-205494Y575130D01*
Y572797D01*
G01X-194211Y577797D02*
Y572797D01*
G01Y573547D02*
X-194544Y573130D01*
X-195044Y572880D01*
X-195628Y572797D01*
X-196294Y572964D01*
X-196794Y573380D01*
X-197128Y573880D01*
X-197211Y574464D01*
X-197128Y575047D01*
X-196794Y575547D01*
X-196294Y575964D01*
X-195628Y576130D01*
X-195044Y576047D01*
X-194628Y575880D01*
X-194211Y575547D01*
G01X-190111Y572797D02*
X-190611Y572880D01*
X-191111Y573214D01*
X-191444Y573797D01*
X-191611Y574464D01*
X-191444Y575130D01*
X-191111Y575714D01*
X-190611Y576047D01*
X-190111Y576130D01*
X-189611Y576047D01*
X-189111Y575714D01*
X-188778Y575130D01*
X-188694Y574464D01*
X-188778Y573797D01*
X-189111Y573214D01*
X-189611Y572880D01*
X-190111Y572797D01*
G01X-183178Y575714D02*
X-183761Y576047D01*
X-184261Y576130D01*
X-184928Y575964D01*
X-185428Y575630D01*
X-185761Y575047D01*
X-185844Y574464D01*
X-185761Y573880D01*
X-185428Y573380D01*
X-184928Y572964D01*
X-184261Y572797D01*
X-183678Y572964D01*
X-183178Y573297D01*
G01X-180328Y576130D02*
Y573797D01*
X-179994Y573214D01*
X-179494Y572880D01*
X-178911Y572797D01*
X-178328Y572880D01*
X-177828Y573214D01*
X-177494Y573797D01*
G01Y572797D02*
Y576130D01*
G01X-175811Y572797D02*
Y576130D01*
G01Y575214D02*
X-175561Y575630D01*
X-175144Y575964D01*
X-174561Y576130D01*
X-173978Y575964D01*
X-173561Y575630D01*
X-173311Y575214D01*
Y572797D01*
G01Y575214D02*
X-173061Y575630D01*
X-172644Y575964D01*
X-172061Y576130D01*
X-171478Y575964D01*
X-171061Y575630D01*
X-170811Y575130D01*
Y572797D01*
G01X-168961Y575047D02*
X-166294D01*
X-166544Y575630D01*
X-166961Y575964D01*
X-167544Y576130D01*
X-168128Y576047D01*
X-168628Y575797D01*
X-168961Y575214D01*
X-169128Y574714D01*
Y574214D01*
X-168961Y573714D01*
X-168544Y573214D01*
X-168044Y572880D01*
X-167461Y572797D01*
X-166878Y572964D01*
X-166294Y573464D01*
G01X-163528Y572797D02*
Y576130D01*
G01Y575297D02*
X-163194Y575714D01*
X-162694Y576047D01*
X-162028Y576130D01*
X-161444Y576047D01*
X-160944Y575714D01*
X-160694Y575130D01*
Y572797D01*
G01X-156511Y577797D02*
Y572797D01*
G01X-157678Y576130D02*
X-155344D01*
G01X-152161Y573380D02*
X-151744Y573047D01*
X-151161Y572797D01*
X-150661D01*
X-150161Y572964D01*
X-149828Y573214D01*
X-149661Y573547D01*
X-149744Y574047D01*
X-150078Y574297D01*
X-151578Y574797D01*
X-151911Y575380D01*
X-151744Y575797D01*
X-151411Y576047D01*
X-150911Y576130D01*
X-150411Y576047D01*
X-149911Y575797D01*
G01X-139711Y576130D02*
Y572797D01*
G01Y577464D02*
X-139878Y577547D01*
Y577714D01*
X-139711Y577797D01*
X-139544Y577714D01*
Y577547D01*
X-139711Y577464D01*
G01X-135528Y572797D02*
Y576130D01*
G01Y575297D02*
X-135194Y575714D01*
X-134694Y576047D01*
X-134028Y576130D01*
X-133444Y576047D01*
X-132944Y575714D01*
X-132694Y575130D01*
Y572797D01*
G01X-121578Y575714D02*
X-122161Y576047D01*
X-122661Y576130D01*
X-123328Y575964D01*
X-123828Y575630D01*
X-124161Y575047D01*
X-124244Y574464D01*
X-124161Y573880D01*
X-123828Y573380D01*
X-123328Y572964D01*
X-122661Y572797D01*
X-122078Y572964D01*
X-121578Y573297D01*
G01X-117311Y572797D02*
Y577797D01*
G01X-110211Y572797D02*
Y576130D01*
G01Y575547D02*
X-110544Y575880D01*
X-111044Y576047D01*
X-111628Y576130D01*
X-112211Y575964D01*
X-112711Y575630D01*
X-113044Y575130D01*
X-113211Y574464D01*
X-113044Y573797D01*
X-112711Y573297D01*
X-112211Y572964D01*
X-111628Y572797D01*
X-111044Y572880D01*
X-110544Y573130D01*
X-110211Y573464D01*
G01X-107361Y573380D02*
X-106944Y573047D01*
X-106361Y572797D01*
X-105861D01*
X-105361Y572964D01*
X-105028Y573214D01*
X-104861Y573547D01*
X-104944Y574047D01*
X-105278Y574297D01*
X-106778Y574797D01*
X-107111Y575380D01*
X-106944Y575797D01*
X-106611Y576047D01*
X-106111Y576130D01*
X-105611Y576047D01*
X-105111Y575797D01*
G01X-101761Y573380D02*
X-101344Y573047D01*
X-100761Y572797D01*
X-100261D01*
X-99761Y572964D01*
X-99428Y573214D01*
X-99261Y573547D01*
X-99344Y574047D01*
X-99678Y574297D01*
X-101178Y574797D01*
X-101511Y575380D01*
X-101344Y575797D01*
X-101011Y576047D01*
X-100511Y576130D01*
X-100011Y576047D01*
X-99511Y575797D01*
G01X-90894Y576964D02*
X-90394Y577464D01*
X-89811Y577714D01*
X-89144Y577797D01*
X-88311Y577630D01*
X-87728Y577214D01*
X-87561Y576714D01*
X-87644Y576214D01*
X-87978Y575797D01*
X-89644Y574964D01*
X-90394Y574380D01*
X-90894Y573547D01*
X-91061Y572797D01*
X-87561D01*
G01X-76611D02*
Y576130D01*
G01Y575547D02*
X-76944Y575880D01*
X-77444Y576047D01*
X-78028Y576130D01*
X-78611Y575964D01*
X-79111Y575630D01*
X-79444Y575130D01*
X-79611Y574464D01*
X-79444Y573797D01*
X-79111Y573297D01*
X-78611Y572964D01*
X-78028Y572797D01*
X-77444Y572880D01*
X-76944Y573130D01*
X-76611Y573464D01*
G01X-73928Y572797D02*
Y576130D01*
G01Y575297D02*
X-73594Y575714D01*
X-73094Y576047D01*
X-72428Y576130D01*
X-71844Y576047D01*
X-71344Y575714D01*
X-71094Y575130D01*
Y572797D01*
G01X-65411Y577797D02*
Y572797D01*
G01Y573547D02*
X-65744Y573130D01*
X-66244Y572880D01*
X-66828Y572797D01*
X-67494Y572964D01*
X-67994Y573380D01*
X-68328Y573880D01*
X-68411Y574464D01*
X-68328Y575047D01*
X-67994Y575547D01*
X-67494Y575964D01*
X-66828Y576130D01*
X-66244Y576047D01*
X-65828Y575880D01*
X-65411Y575547D01*
G01X-55711Y577797D02*
Y572797D01*
G01X-56878Y576130D02*
X-54544D01*
G01X-51528Y572797D02*
Y577797D01*
G01Y575380D02*
X-51111Y575797D01*
X-50694Y576047D01*
X-50028Y576130D01*
X-49528Y576047D01*
X-48944Y575714D01*
X-48694Y575214D01*
Y572797D01*
G01X-45761Y575047D02*
X-43094D01*
X-43344Y575630D01*
X-43761Y575964D01*
X-44344Y576130D01*
X-44928Y576047D01*
X-45428Y575797D01*
X-45761Y575214D01*
X-45928Y574714D01*
Y574214D01*
X-45761Y573714D01*
X-45344Y573214D01*
X-44844Y572880D01*
X-44261Y572797D01*
X-43678Y572964D01*
X-43094Y573464D01*
G01X-33311Y572797D02*
Y577797D01*
G01X-26211Y572797D02*
Y576130D01*
G01Y575547D02*
X-26544Y575880D01*
X-27044Y576047D01*
X-27628Y576130D01*
X-28211Y575964D01*
X-28711Y575630D01*
X-29044Y575130D01*
X-29211Y574464D01*
X-29044Y573797D01*
X-28711Y573297D01*
X-28211Y572964D01*
X-27628Y572797D01*
X-27044Y572880D01*
X-26544Y573130D01*
X-26211Y573464D01*
G01X-22111Y577797D02*
Y572797D01*
G01X-23278Y576130D02*
X-20944D01*
G01X-17761Y575047D02*
X-15094D01*
X-15344Y575630D01*
X-15761Y575964D01*
X-16344Y576130D01*
X-16928Y576047D01*
X-17428Y575797D01*
X-17761Y575214D01*
X-17928Y574714D01*
Y574214D01*
X-17761Y573714D01*
X-17344Y573214D01*
X-16844Y572880D01*
X-16261Y572797D01*
X-15678Y572964D01*
X-15094Y573464D01*
G01X-12161Y573380D02*
X-11744Y573047D01*
X-11161Y572797D01*
X-10661D01*
X-10161Y572964D01*
X-9828Y573214D01*
X-9661Y573547D01*
X-9744Y574047D01*
X-10078Y574297D01*
X-11578Y574797D01*
X-11911Y575380D01*
X-11744Y575797D01*
X-11411Y576047D01*
X-10911Y576130D01*
X-10411Y576047D01*
X-9911Y575797D01*
G01X-5311Y577797D02*
Y572797D01*
G01X-6478Y576130D02*
X-4144D01*
G01X4389D02*
X5889Y572797D01*
X7389Y576130D01*
G01X10239Y575047D02*
X12906D01*
X12656Y575630D01*
X12239Y575964D01*
X11656Y576130D01*
X11072Y576047D01*
X10572Y575797D01*
X10239Y575214D01*
X10072Y574714D01*
Y574214D01*
X10239Y573714D01*
X10656Y573214D01*
X11156Y572880D01*
X11739Y572797D01*
X12322Y572964D01*
X12906Y573464D01*
G01X15922Y572797D02*
Y576130D01*
G01Y575464D02*
X16339Y575797D01*
X16756Y576047D01*
X17339Y576130D01*
X17756Y576047D01*
X18256Y575797D01*
G01X21439Y573380D02*
X21856Y573047D01*
X22439Y572797D01*
X22939D01*
X23439Y572964D01*
X23772Y573214D01*
X23939Y573547D01*
X23856Y574047D01*
X23522Y574297D01*
X22022Y574797D01*
X21689Y575380D01*
X21856Y575797D01*
X22189Y576047D01*
X22689Y576130D01*
X23189Y576047D01*
X23689Y575797D01*
G01X28289Y576130D02*
Y572797D01*
G01Y577464D02*
X28122Y577547D01*
Y577714D01*
X28289Y577797D01*
X28456Y577714D01*
Y577547D01*
X28289Y577464D01*
G01X33889Y572797D02*
X33389Y572880D01*
X32889Y573214D01*
X32556Y573797D01*
X32389Y574464D01*
X32556Y575130D01*
X32889Y575714D01*
X33389Y576047D01*
X33889Y576130D01*
X34389Y576047D01*
X34889Y575714D01*
X35222Y575130D01*
X35306Y574464D01*
X35222Y573797D01*
X34889Y573214D01*
X34389Y572880D01*
X33889Y572797D01*
G01X38072D02*
Y576130D01*
G01Y575297D02*
X38406Y575714D01*
X38906Y576047D01*
X39572Y576130D01*
X40156Y576047D01*
X40656Y575714D01*
X40906Y575130D01*
Y572797D01*
G01X50689Y576130D02*
Y572797D01*
G01Y577464D02*
X50522Y577547D01*
Y577714D01*
X50689Y577797D01*
X50856Y577714D01*
Y577547D01*
X50689Y577464D01*
G01X55039Y573380D02*
X55456Y573047D01*
X56039Y572797D01*
X56539D01*
X57039Y572964D01*
X57372Y573214D01*
X57539Y573547D01*
X57456Y574047D01*
X57122Y574297D01*
X55622Y574797D01*
X55289Y575380D01*
X55456Y575797D01*
X55789Y576047D01*
X56289Y576130D01*
X56789Y576047D01*
X57289Y575797D01*
G01X66322Y572797D02*
Y576130D01*
G01Y575464D02*
X66739Y575797D01*
X67156Y576047D01*
X67739Y576130D01*
X68156Y576047D01*
X68656Y575797D01*
G01X71839Y575047D02*
X74506D01*
X74256Y575630D01*
X73839Y575964D01*
X73256Y576130D01*
X72672Y576047D01*
X72172Y575797D01*
X71839Y575214D01*
X71672Y574714D01*
Y574214D01*
X71839Y573714D01*
X72256Y573214D01*
X72756Y572880D01*
X73339Y572797D01*
X73922Y572964D01*
X74506Y573464D01*
G01X80189Y571130D02*
Y576130D01*
G01Y575380D02*
X79772Y575797D01*
X79272Y576047D01*
X78689Y576130D01*
X78189Y576047D01*
X77606Y575630D01*
X77272Y575047D01*
X77189Y574464D01*
X77272Y573880D01*
X77606Y573297D01*
X78189Y572880D01*
X78689Y572797D01*
X79272Y572880D01*
X79772Y573130D01*
X80189Y573547D01*
G01X82872Y576130D02*
Y573797D01*
X83206Y573214D01*
X83706Y572880D01*
X84289Y572797D01*
X84872Y572880D01*
X85372Y573214D01*
X85706Y573797D01*
G01Y572797D02*
Y576130D01*
G01X89889D02*
Y572797D01*
G01Y577464D02*
X89722Y577547D01*
Y577714D01*
X89889Y577797D01*
X90056Y577714D01*
Y577547D01*
X89889Y577464D01*
G01X94322Y572797D02*
Y576130D01*
G01Y575464D02*
X94739Y575797D01*
X95156Y576047D01*
X95739Y576130D01*
X96156Y576047D01*
X96656Y575797D01*
G01X99839Y575047D02*
X102506D01*
X102256Y575630D01*
X101839Y575964D01*
X101256Y576130D01*
X100672Y576047D01*
X100172Y575797D01*
X99839Y575214D01*
X99672Y574714D01*
Y574214D01*
X99839Y573714D01*
X100256Y573214D01*
X100756Y572880D01*
X101339Y572797D01*
X101922Y572964D01*
X102506Y573464D01*
G01X108189Y577797D02*
Y572797D01*
G01Y573547D02*
X107856Y573130D01*
X107356Y572880D01*
X106772Y572797D01*
X106106Y572964D01*
X105606Y573380D01*
X105272Y573880D01*
X105189Y574464D01*
X105272Y575047D01*
X105606Y575547D01*
X106106Y575964D01*
X106772Y576130D01*
X107356Y576047D01*
X107772Y575880D01*
X108189Y575547D01*
G01X112122Y571880D02*
X112456Y572964D01*
G01X-322078Y-293703D02*
Y-298703D01*
X-318744D01*
G01X-314811D02*
X-315311Y-298620D01*
X-315811Y-298286D01*
X-316144Y-297703D01*
X-316311Y-297036D01*
X-316144Y-296370D01*
X-315811Y-295786D01*
X-315311Y-295453D01*
X-314811Y-295370D01*
X-314311Y-295453D01*
X-313811Y-295786D01*
X-313478Y-296370D01*
X-313394Y-297036D01*
X-313478Y-297703D01*
X-313811Y-298286D01*
X-314311Y-298620D01*
X-314811Y-298703D01*
G01X-310378Y-299953D02*
X-309794Y-300286D01*
X-309128Y-300370D01*
X-308544Y-300286D01*
X-308044Y-299870D01*
X-307711Y-299286D01*
Y-295370D01*
G01Y-296036D02*
X-308044Y-295703D01*
X-308544Y-295453D01*
X-309128Y-295370D01*
X-309794Y-295536D01*
X-310211Y-295870D01*
X-310544Y-296453D01*
X-310711Y-297036D01*
X-310628Y-297536D01*
X-310294Y-298120D01*
X-309794Y-298536D01*
X-309128Y-298703D01*
X-308628Y-298620D01*
X-308044Y-298286D01*
X-307711Y-297953D01*
G01X-303611Y-298703D02*
X-304111Y-298620D01*
X-304611Y-298286D01*
X-304944Y-297703D01*
X-305111Y-297036D01*
X-304944Y-296370D01*
X-304611Y-295786D01*
X-304111Y-295453D01*
X-303611Y-295370D01*
X-303111Y-295453D01*
X-302611Y-295786D01*
X-302278Y-296370D01*
X-302194Y-297036D01*
X-302278Y-297703D01*
X-302611Y-298286D01*
X-303111Y-298620D01*
X-303611Y-298703D01*
G01X-330911Y445297D02*
Y-303203D01*
G01Y-288203D02*
X260089D01*
G01X-320411Y-269703D02*
Y-274703D01*
G01X-321578Y-271370D02*
X-319244D01*
G01X-316228Y-274703D02*
Y-269703D01*
G01Y-272120D02*
X-315811Y-271703D01*
X-315394Y-271453D01*
X-314728Y-271370D01*
X-314228Y-271453D01*
X-313644Y-271786D01*
X-313394Y-272286D01*
Y-274703D01*
G01X-309211Y-271370D02*
Y-274703D01*
G01Y-270036D02*
X-309378Y-269953D01*
Y-269786D01*
X-309211Y-269703D01*
X-309044Y-269786D01*
Y-269953D01*
X-309211Y-270036D01*
G01X-302278Y-271786D02*
X-302861Y-271453D01*
X-303361Y-271370D01*
X-304028Y-271536D01*
X-304528Y-271870D01*
X-304861Y-272453D01*
X-304944Y-273036D01*
X-304861Y-273620D01*
X-304528Y-274120D01*
X-304028Y-274536D01*
X-303361Y-274703D01*
X-302778Y-274536D01*
X-302278Y-274203D01*
G01X-299428Y-274703D02*
Y-269703D01*
G01X-296761Y-271370D02*
X-299428Y-273286D01*
G01X-298344Y-272536D02*
X-296594Y-274703D01*
G01X-293828D02*
Y-271370D01*
G01Y-272203D02*
X-293494Y-271786D01*
X-292994Y-271453D01*
X-292328Y-271370D01*
X-291744Y-271453D01*
X-291244Y-271786D01*
X-290994Y-272370D01*
Y-274703D01*
G01X-288061Y-272453D02*
X-285394D01*
X-285644Y-271870D01*
X-286061Y-271536D01*
X-286644Y-271370D01*
X-287228Y-271453D01*
X-287728Y-271703D01*
X-288061Y-272286D01*
X-288228Y-272786D01*
Y-273286D01*
X-288061Y-273786D01*
X-287644Y-274286D01*
X-287144Y-274620D01*
X-286561Y-274703D01*
X-285978Y-274536D01*
X-285394Y-274036D01*
G01X-282461Y-274120D02*
X-282044Y-274453D01*
X-281461Y-274703D01*
X-280961D01*
X-280461Y-274536D01*
X-280128Y-274286D01*
X-279961Y-273953D01*
X-280044Y-273453D01*
X-280378Y-273203D01*
X-281878Y-272703D01*
X-282211Y-272120D01*
X-282044Y-271703D01*
X-281711Y-271453D01*
X-281211Y-271370D01*
X-280711Y-271453D01*
X-280211Y-271703D01*
G01X-276861Y-274120D02*
X-276444Y-274453D01*
X-275861Y-274703D01*
X-275361D01*
X-274861Y-274536D01*
X-274528Y-274286D01*
X-274361Y-273953D01*
X-274444Y-273453D01*
X-274778Y-273203D01*
X-276278Y-272703D01*
X-276611Y-272120D01*
X-276444Y-271703D01*
X-276111Y-271453D01*
X-275611Y-271370D01*
X-275111Y-271453D01*
X-274611Y-271703D01*
G01X-320411Y-248703D02*
Y-253703D01*
G01X-321578Y-250370D02*
X-319244D01*
G01X-316228Y-253703D02*
Y-248703D01*
G01Y-251120D02*
X-315811Y-250703D01*
X-315394Y-250453D01*
X-314728Y-250370D01*
X-314228Y-250453D01*
X-313644Y-250786D01*
X-313394Y-251286D01*
Y-253703D01*
G01X-309211Y-250370D02*
Y-253703D01*
G01Y-249036D02*
X-309378Y-248953D01*
Y-248786D01*
X-309211Y-248703D01*
X-309044Y-248786D01*
Y-248953D01*
X-309211Y-249036D01*
G01X-302278Y-250786D02*
X-302861Y-250453D01*
X-303361Y-250370D01*
X-304028Y-250536D01*
X-304528Y-250870D01*
X-304861Y-251453D01*
X-304944Y-252036D01*
X-304861Y-252620D01*
X-304528Y-253120D01*
X-304028Y-253536D01*
X-303361Y-253703D01*
X-302778Y-253536D01*
X-302278Y-253203D01*
G01X-299428Y-253703D02*
Y-248703D01*
G01X-296761Y-250370D02*
X-299428Y-252286D01*
G01X-298344Y-251536D02*
X-296594Y-253703D01*
G01X-293828D02*
Y-250370D01*
G01Y-251203D02*
X-293494Y-250786D01*
X-292994Y-250453D01*
X-292328Y-250370D01*
X-291744Y-250453D01*
X-291244Y-250786D01*
X-290994Y-251370D01*
Y-253703D01*
G01X-288061Y-251453D02*
X-285394D01*
X-285644Y-250870D01*
X-286061Y-250536D01*
X-286644Y-250370D01*
X-287228Y-250453D01*
X-287728Y-250703D01*
X-288061Y-251286D01*
X-288228Y-251786D01*
Y-252286D01*
X-288061Y-252786D01*
X-287644Y-253286D01*
X-287144Y-253620D01*
X-286561Y-253703D01*
X-285978Y-253536D01*
X-285394Y-253036D01*
G01X-282461Y-253120D02*
X-282044Y-253453D01*
X-281461Y-253703D01*
X-280961D01*
X-280461Y-253536D01*
X-280128Y-253286D01*
X-279961Y-252953D01*
X-280044Y-252453D01*
X-280378Y-252203D01*
X-281878Y-251703D01*
X-282211Y-251120D01*
X-282044Y-250703D01*
X-281711Y-250453D01*
X-281211Y-250370D01*
X-280711Y-250453D01*
X-280211Y-250703D01*
G01X-276861Y-253120D02*
X-276444Y-253453D01*
X-275861Y-253703D01*
X-275361D01*
X-274861Y-253536D01*
X-274528Y-253286D01*
X-274361Y-252953D01*
X-274444Y-252453D01*
X-274778Y-252203D01*
X-276278Y-251703D01*
X-276611Y-251120D01*
X-276444Y-250703D01*
X-276111Y-250453D01*
X-275611Y-250370D01*
X-275111Y-250453D01*
X-274611Y-250703D01*
G01X-330911Y-243203D02*
X260089D01*
G01X-315228Y-235870D02*
X-316061Y-235036D01*
X-316478Y-234203D01*
Y-230870D01*
X-316061Y-230036D01*
X-315228Y-229203D01*
G01X-310961Y-233536D02*
X-310294Y-233953D01*
X-309544Y-234203D01*
X-308878D01*
X-308211Y-233953D01*
X-307711Y-233536D01*
X-307461Y-232953D01*
X-307628Y-232370D01*
X-308044Y-231870D01*
X-308794Y-231536D01*
X-309794Y-231370D01*
X-310378Y-231036D01*
X-310628Y-230453D01*
X-310461Y-229870D01*
X-310044Y-229453D01*
X-309461Y-229203D01*
X-308878D01*
X-308294Y-229370D01*
X-307794Y-229786D01*
G01X-305778Y-234203D02*
Y-229203D01*
X-303611Y-233370D01*
X-301444Y-229203D01*
Y-234203D01*
G01X-299844D02*
Y-229203D01*
X-298178D01*
X-297511Y-229453D01*
X-297011Y-229786D01*
X-296594Y-230286D01*
X-296261Y-230870D01*
X-296178Y-231703D01*
X-296261Y-232536D01*
X-296594Y-233120D01*
X-297011Y-233620D01*
X-297511Y-233953D01*
X-298178Y-234203D01*
X-299844D01*
G01X-291994Y-235870D02*
X-291161Y-235036D01*
X-290744Y-234203D01*
Y-230870D01*
X-291161Y-230036D01*
X-291994Y-229203D01*
G01X-322161Y-221536D02*
X-321494Y-221953D01*
X-320744Y-222203D01*
X-320078D01*
X-319411Y-221953D01*
X-318911Y-221536D01*
X-318661Y-220953D01*
X-318828Y-220370D01*
X-319244Y-219870D01*
X-319994Y-219536D01*
X-320994Y-219370D01*
X-321578Y-219036D01*
X-321828Y-218453D01*
X-321661Y-217870D01*
X-321244Y-217453D01*
X-320661Y-217203D01*
X-320078D01*
X-319494Y-217370D01*
X-318994Y-217786D01*
G01X-314811Y-222203D02*
X-315311Y-222120D01*
X-315811Y-221786D01*
X-316144Y-221203D01*
X-316311Y-220536D01*
X-316144Y-219870D01*
X-315811Y-219286D01*
X-315311Y-218953D01*
X-314811Y-218870D01*
X-314311Y-218953D01*
X-313811Y-219286D01*
X-313478Y-219870D01*
X-313394Y-220536D01*
X-313478Y-221203D01*
X-313811Y-221786D01*
X-314311Y-222120D01*
X-314811Y-222203D01*
G01X-309211D02*
Y-217203D01*
G01X-302111D02*
Y-222203D01*
G01Y-221453D02*
X-302444Y-221870D01*
X-302944Y-222120D01*
X-303528Y-222203D01*
X-304194Y-222036D01*
X-304694Y-221620D01*
X-305028Y-221120D01*
X-305111Y-220536D01*
X-305028Y-219953D01*
X-304694Y-219453D01*
X-304194Y-219036D01*
X-303528Y-218870D01*
X-302944Y-218953D01*
X-302528Y-219120D01*
X-302111Y-219453D01*
G01X-299261Y-219953D02*
X-296594D01*
X-296844Y-219370D01*
X-297261Y-219036D01*
X-297844Y-218870D01*
X-298428Y-218953D01*
X-298928Y-219203D01*
X-299261Y-219786D01*
X-299428Y-220286D01*
Y-220786D01*
X-299261Y-221286D01*
X-298844Y-221786D01*
X-298344Y-222120D01*
X-297761Y-222203D01*
X-297178Y-222036D01*
X-296594Y-221536D01*
G01X-293578Y-222203D02*
Y-218870D01*
G01Y-219536D02*
X-293161Y-219203D01*
X-292744Y-218953D01*
X-292161Y-218870D01*
X-291744Y-218953D01*
X-291244Y-219203D01*
G01X-283711Y-222203D02*
Y-218870D01*
G01Y-219786D02*
X-283461Y-219370D01*
X-283044Y-219036D01*
X-282461Y-218870D01*
X-281878Y-219036D01*
X-281461Y-219370D01*
X-281211Y-219786D01*
Y-222203D01*
G01Y-219786D02*
X-280961Y-219370D01*
X-280544Y-219036D01*
X-279961Y-218870D01*
X-279378Y-219036D01*
X-278961Y-219370D01*
X-278711Y-219870D01*
Y-222203D01*
G01X-274111D02*
Y-218870D01*
G01Y-219453D02*
X-274444Y-219120D01*
X-274944Y-218953D01*
X-275528Y-218870D01*
X-276111Y-219036D01*
X-276611Y-219370D01*
X-276944Y-219870D01*
X-277111Y-220536D01*
X-276944Y-221203D01*
X-276611Y-221703D01*
X-276111Y-222036D01*
X-275528Y-222203D01*
X-274944Y-222120D01*
X-274444Y-221870D01*
X-274111Y-221536D01*
G01X-271261Y-221620D02*
X-270844Y-221953D01*
X-270261Y-222203D01*
X-269761D01*
X-269261Y-222036D01*
X-268928Y-221786D01*
X-268761Y-221453D01*
X-268844Y-220953D01*
X-269178Y-220703D01*
X-270678Y-220203D01*
X-271011Y-219620D01*
X-270844Y-219203D01*
X-270511Y-218953D01*
X-270011Y-218870D01*
X-269511Y-218953D01*
X-269011Y-219203D01*
G01X-265828Y-222203D02*
Y-217203D01*
G01X-263161Y-218870D02*
X-265828Y-220786D01*
G01X-264744Y-220036D02*
X-262994Y-222203D01*
G01X-251711Y-217203D02*
Y-222203D01*
G01Y-221453D02*
X-252044Y-221870D01*
X-252544Y-222120D01*
X-253128Y-222203D01*
X-253794Y-222036D01*
X-254294Y-221620D01*
X-254628Y-221120D01*
X-254711Y-220536D01*
X-254628Y-219953D01*
X-254294Y-219453D01*
X-253794Y-219036D01*
X-253128Y-218870D01*
X-252544Y-218953D01*
X-252128Y-219120D01*
X-251711Y-219453D01*
G01X-248861Y-219953D02*
X-246194D01*
X-246444Y-219370D01*
X-246861Y-219036D01*
X-247444Y-218870D01*
X-248028Y-218953D01*
X-248528Y-219203D01*
X-248861Y-219786D01*
X-249028Y-220286D01*
Y-220786D01*
X-248861Y-221286D01*
X-248444Y-221786D01*
X-247944Y-222120D01*
X-247361Y-222203D01*
X-246778Y-222036D01*
X-246194Y-221536D01*
G01X-242511Y-222203D02*
Y-217953D01*
X-242344Y-217536D01*
X-242011Y-217286D01*
X-241511Y-217203D01*
X-241011Y-217370D01*
X-240761Y-217786D01*
G01X-241761Y-219203D02*
X-243428D01*
G01X-236411Y-218870D02*
Y-222203D01*
G01Y-217536D02*
X-236578Y-217453D01*
Y-217286D01*
X-236411Y-217203D01*
X-236244Y-217286D01*
Y-217453D01*
X-236411Y-217536D01*
G01X-232228Y-222203D02*
Y-218870D01*
G01Y-219703D02*
X-231894Y-219286D01*
X-231394Y-218953D01*
X-230728Y-218870D01*
X-230144Y-218953D01*
X-229644Y-219286D01*
X-229394Y-219870D01*
Y-222203D01*
G01X-226461Y-219953D02*
X-223794D01*
X-224044Y-219370D01*
X-224461Y-219036D01*
X-225044Y-218870D01*
X-225628Y-218953D01*
X-226128Y-219203D01*
X-226461Y-219786D01*
X-226628Y-220286D01*
Y-220786D01*
X-226461Y-221286D01*
X-226044Y-221786D01*
X-225544Y-222120D01*
X-224961Y-222203D01*
X-224378Y-222036D01*
X-223794Y-221536D01*
G01X-215511Y-223870D02*
Y-218870D01*
G01Y-219620D02*
X-215094Y-219203D01*
X-214678Y-218953D01*
X-214011Y-218870D01*
X-213428Y-218953D01*
X-212844Y-219370D01*
X-212594Y-219953D01*
X-212511Y-220536D01*
X-212594Y-221120D01*
X-212844Y-221703D01*
X-213344Y-222036D01*
X-214011Y-222203D01*
X-214594Y-222120D01*
X-215178Y-221870D01*
X-215511Y-221536D01*
G01X-206911Y-222203D02*
Y-218870D01*
G01Y-219453D02*
X-207244Y-219120D01*
X-207744Y-218953D01*
X-208328Y-218870D01*
X-208911Y-219036D01*
X-209411Y-219370D01*
X-209744Y-219870D01*
X-209911Y-220536D01*
X-209744Y-221203D01*
X-209411Y-221703D01*
X-208911Y-222036D01*
X-208328Y-222203D01*
X-207744Y-222120D01*
X-207244Y-221870D01*
X-206911Y-221536D01*
G01X-201311Y-217203D02*
Y-222203D01*
G01Y-221453D02*
X-201644Y-221870D01*
X-202144Y-222120D01*
X-202728Y-222203D01*
X-203394Y-222036D01*
X-203894Y-221620D01*
X-204228Y-221120D01*
X-204311Y-220536D01*
X-204228Y-219953D01*
X-203894Y-219453D01*
X-203394Y-219036D01*
X-202728Y-218870D01*
X-202144Y-218953D01*
X-201728Y-219120D01*
X-201311Y-219453D01*
G01X-321928Y-209003D02*
Y-204003D01*
X-319761Y-208170D01*
X-317594Y-204003D01*
Y-209003D01*
G01X-312661D02*
Y-205670D01*
G01Y-206253D02*
X-312994Y-205920D01*
X-313494Y-205753D01*
X-314078Y-205670D01*
X-314661Y-205836D01*
X-315161Y-206170D01*
X-315494Y-206670D01*
X-315661Y-207336D01*
X-315494Y-208003D01*
X-315161Y-208503D01*
X-314661Y-208836D01*
X-314078Y-209003D01*
X-313494Y-208920D01*
X-312994Y-208670D01*
X-312661Y-208336D01*
G01X-309728Y-209003D02*
Y-205670D01*
G01Y-206336D02*
X-309311Y-206003D01*
X-308894Y-205753D01*
X-308311Y-205670D01*
X-307894Y-205753D01*
X-307394Y-206003D01*
G01X-304378Y-209003D02*
Y-204003D01*
G01X-301711Y-205670D02*
X-304378Y-207586D01*
G01X-303294Y-206836D02*
X-301544Y-209003D01*
G01X-296944Y-210670D02*
X-296111Y-209836D01*
X-295694Y-209003D01*
Y-205670D01*
X-296111Y-204836D01*
X-296944Y-204003D01*
G01X-321341Y-197573D02*
X-319674D01*
Y-199073D01*
X-320174Y-199573D01*
X-320758Y-199906D01*
X-321591Y-200073D01*
X-322424Y-199906D01*
X-323008Y-199573D01*
X-323508Y-199073D01*
X-323841Y-198490D01*
X-324008Y-197823D01*
Y-197240D01*
X-323841Y-196740D01*
X-323508Y-196156D01*
X-323008Y-195656D01*
X-322508Y-195323D01*
X-321841Y-195073D01*
X-321258D01*
X-320591Y-195240D01*
X-320091Y-195573D01*
G01X-316241Y-200073D02*
X-316741Y-199990D01*
X-317241Y-199656D01*
X-317574Y-199073D01*
X-317741Y-198406D01*
X-317574Y-197740D01*
X-317241Y-197156D01*
X-316741Y-196823D01*
X-316241Y-196740D01*
X-315741Y-196823D01*
X-315241Y-197156D01*
X-314908Y-197740D01*
X-314824Y-198406D01*
X-314908Y-199073D01*
X-315241Y-199656D01*
X-315741Y-199990D01*
X-316241Y-200073D01*
G01X-310641D02*
Y-195073D01*
G01X-303541D02*
Y-200073D01*
G01Y-199323D02*
X-303874Y-199740D01*
X-304374Y-199990D01*
X-304958Y-200073D01*
X-305624Y-199906D01*
X-306124Y-199490D01*
X-306458Y-198990D01*
X-306541Y-198406D01*
X-306458Y-197823D01*
X-306124Y-197323D01*
X-305624Y-196906D01*
X-304958Y-196740D01*
X-304374Y-196823D01*
X-303958Y-196990D01*
X-303541Y-197323D01*
G01X-300691Y-197823D02*
X-298024D01*
X-298274Y-197240D01*
X-298691Y-196906D01*
X-299274Y-196740D01*
X-299858Y-196823D01*
X-300358Y-197073D01*
X-300691Y-197656D01*
X-300858Y-198156D01*
Y-198656D01*
X-300691Y-199156D01*
X-300274Y-199656D01*
X-299774Y-199990D01*
X-299191Y-200073D01*
X-298608Y-199906D01*
X-298024Y-199406D01*
G01X-295258Y-200073D02*
Y-196740D01*
G01Y-197573D02*
X-294924Y-197156D01*
X-294424Y-196823D01*
X-293758Y-196740D01*
X-293174Y-196823D01*
X-292674Y-197156D01*
X-292424Y-197740D01*
Y-200073D01*
G01X-283141D02*
Y-195823D01*
X-282974Y-195406D01*
X-282641Y-195156D01*
X-282141Y-195073D01*
X-281641Y-195240D01*
X-281391Y-195656D01*
G01X-282391Y-197073D02*
X-284058D01*
G01X-277041Y-196740D02*
Y-200073D01*
G01Y-195406D02*
X-277208Y-195323D01*
Y-195156D01*
X-277041Y-195073D01*
X-276874Y-195156D01*
Y-195323D01*
X-277041Y-195406D01*
G01X-272858Y-200073D02*
Y-196740D01*
G01Y-197573D02*
X-272524Y-197156D01*
X-272024Y-196823D01*
X-271358Y-196740D01*
X-270774Y-196823D01*
X-270274Y-197156D01*
X-270024Y-197740D01*
Y-200073D01*
G01X-267008Y-201323D02*
X-266424Y-201656D01*
X-265758Y-201740D01*
X-265174Y-201656D01*
X-264674Y-201240D01*
X-264341Y-200656D01*
Y-196740D01*
G01Y-197406D02*
X-264674Y-197073D01*
X-265174Y-196823D01*
X-265758Y-196740D01*
X-266424Y-196906D01*
X-266841Y-197240D01*
X-267174Y-197823D01*
X-267341Y-198406D01*
X-267258Y-198906D01*
X-266924Y-199490D01*
X-266424Y-199906D01*
X-265758Y-200073D01*
X-265258Y-199990D01*
X-264674Y-199656D01*
X-264341Y-199323D01*
G01X-261491Y-197823D02*
X-258824D01*
X-259074Y-197240D01*
X-259491Y-196906D01*
X-260074Y-196740D01*
X-260658Y-196823D01*
X-261158Y-197073D01*
X-261491Y-197656D01*
X-261658Y-198156D01*
Y-198656D01*
X-261491Y-199156D01*
X-261074Y-199656D01*
X-260574Y-199990D01*
X-259991Y-200073D01*
X-259408Y-199906D01*
X-258824Y-199406D01*
G01X-255808Y-200073D02*
Y-196740D01*
G01Y-197406D02*
X-255391Y-197073D01*
X-254974Y-196823D01*
X-254391Y-196740D01*
X-253974Y-196823D01*
X-253474Y-197073D01*
G01X-245108Y-200073D02*
Y-195073D01*
X-243108D01*
X-242441Y-195323D01*
X-241941Y-195906D01*
X-241774Y-196573D01*
X-241941Y-197240D01*
X-242358Y-197740D01*
X-243108Y-197990D01*
X-245108D01*
G01X-239924Y-200073D02*
X-237841Y-195073D01*
X-235758Y-200073D01*
G01X-236508Y-198323D02*
X-239174D01*
G01X-234074Y-200073D02*
Y-195073D01*
X-232408D01*
X-231741Y-195323D01*
X-231241Y-195656D01*
X-230824Y-196156D01*
X-230491Y-196740D01*
X-230408Y-197573D01*
X-230491Y-198406D01*
X-230824Y-198990D01*
X-231241Y-199490D01*
X-231741Y-199823D01*
X-232408Y-200073D01*
X-234074D01*
G01X-222541Y-200240D02*
X-219541Y-195073D01*
G01X-217024Y-200073D02*
Y-195073D01*
X-213858D01*
G01X-215024Y-197490D02*
X-217024D01*
G01X-209841Y-196740D02*
Y-200073D01*
G01Y-195406D02*
X-210008Y-195323D01*
Y-195156D01*
X-209841Y-195073D01*
X-209674Y-195156D01*
Y-195323D01*
X-209841Y-195406D01*
G01X-202741Y-195073D02*
Y-200073D01*
G01Y-199323D02*
X-203074Y-199740D01*
X-203574Y-199990D01*
X-204158Y-200073D01*
X-204824Y-199906D01*
X-205324Y-199490D01*
X-205658Y-198990D01*
X-205741Y-198406D01*
X-205658Y-197823D01*
X-205324Y-197323D01*
X-204824Y-196906D01*
X-204158Y-196740D01*
X-203574Y-196823D01*
X-203158Y-196990D01*
X-202741Y-197323D01*
G01X-200058Y-196740D02*
Y-199073D01*
X-199724Y-199656D01*
X-199224Y-199990D01*
X-198641Y-200073D01*
X-198058Y-199990D01*
X-197558Y-199656D01*
X-197224Y-199073D01*
G01Y-200073D02*
Y-196740D01*
G01X-191708Y-197156D02*
X-192291Y-196823D01*
X-192791Y-196740D01*
X-193458Y-196906D01*
X-193958Y-197240D01*
X-194291Y-197823D01*
X-194374Y-198406D01*
X-194291Y-198990D01*
X-193958Y-199490D01*
X-193458Y-199906D01*
X-192791Y-200073D01*
X-192208Y-199906D01*
X-191708Y-199573D01*
G01X-187441Y-196740D02*
Y-200073D01*
G01Y-195406D02*
X-187608Y-195323D01*
Y-195156D01*
X-187441Y-195073D01*
X-187274Y-195156D01*
Y-195323D01*
X-187441Y-195406D01*
G01X-180341Y-200073D02*
Y-196740D01*
G01Y-197323D02*
X-180674Y-196990D01*
X-181174Y-196823D01*
X-181758Y-196740D01*
X-182341Y-196906D01*
X-182841Y-197240D01*
X-183174Y-197740D01*
X-183341Y-198406D01*
X-183174Y-199073D01*
X-182841Y-199573D01*
X-182341Y-199906D01*
X-181758Y-200073D01*
X-181174Y-199990D01*
X-180674Y-199740D01*
X-180341Y-199406D01*
G01X-176241Y-200073D02*
Y-195073D01*
G01X-321668Y-191030D02*
X-322501Y-190196D01*
X-322918Y-189363D01*
Y-186030D01*
X-322501Y-185196D01*
X-321668Y-184363D01*
G01X-318151Y-189363D02*
Y-186030D01*
G01Y-186946D02*
X-317901Y-186530D01*
X-317484Y-186196D01*
X-316901Y-186030D01*
X-316318Y-186196D01*
X-315901Y-186530D01*
X-315651Y-186946D01*
Y-189363D01*
G01Y-186946D02*
X-315401Y-186530D01*
X-314984Y-186196D01*
X-314401Y-186030D01*
X-313818Y-186196D01*
X-313401Y-186530D01*
X-313151Y-187030D01*
Y-189363D01*
G01X-311301Y-187113D02*
X-308634D01*
X-308884Y-186530D01*
X-309301Y-186196D01*
X-309884Y-186030D01*
X-310468Y-186113D01*
X-310968Y-186363D01*
X-311301Y-186946D01*
X-311468Y-187446D01*
Y-187946D01*
X-311301Y-188446D01*
X-310884Y-188946D01*
X-310384Y-189280D01*
X-309801Y-189363D01*
X-309218Y-189196D01*
X-308634Y-188696D01*
G01X-302951Y-189363D02*
Y-186030D01*
G01Y-186613D02*
X-303284Y-186280D01*
X-303784Y-186113D01*
X-304368Y-186030D01*
X-304951Y-186196D01*
X-305451Y-186530D01*
X-305784Y-187030D01*
X-305951Y-187696D01*
X-305784Y-188363D01*
X-305451Y-188863D01*
X-304951Y-189196D01*
X-304368Y-189363D01*
X-303784Y-189280D01*
X-303284Y-189030D01*
X-302951Y-188696D01*
G01X-300101Y-188780D02*
X-299684Y-189113D01*
X-299101Y-189363D01*
X-298601D01*
X-298101Y-189196D01*
X-297768Y-188946D01*
X-297601Y-188613D01*
X-297684Y-188113D01*
X-298018Y-187863D01*
X-299518Y-187363D01*
X-299851Y-186780D01*
X-299684Y-186363D01*
X-299351Y-186113D01*
X-298851Y-186030D01*
X-298351Y-186113D01*
X-297851Y-186363D01*
G01X-294668Y-186030D02*
Y-188363D01*
X-294334Y-188946D01*
X-293834Y-189280D01*
X-293251Y-189363D01*
X-292668Y-189280D01*
X-292168Y-188946D01*
X-291834Y-188363D01*
G01Y-189363D02*
Y-186030D01*
G01X-288818Y-189363D02*
Y-186030D01*
G01Y-186696D02*
X-288401Y-186363D01*
X-287984Y-186113D01*
X-287401Y-186030D01*
X-286984Y-186113D01*
X-286484Y-186363D01*
G01X-283301Y-187113D02*
X-280634D01*
X-280884Y-186530D01*
X-281301Y-186196D01*
X-281884Y-186030D01*
X-282468Y-186113D01*
X-282968Y-186363D01*
X-283301Y-186946D01*
X-283468Y-187446D01*
Y-187946D01*
X-283301Y-188446D01*
X-282884Y-188946D01*
X-282384Y-189280D01*
X-281801Y-189363D01*
X-281218Y-189196D01*
X-280634Y-188696D01*
G01X-270851Y-184363D02*
Y-189363D01*
G01X-272018Y-186030D02*
X-269684D01*
G01X-265251Y-189363D02*
X-265751Y-189280D01*
X-266251Y-188946D01*
X-266584Y-188363D01*
X-266751Y-187696D01*
X-266584Y-187030D01*
X-266251Y-186446D01*
X-265751Y-186113D01*
X-265251Y-186030D01*
X-264751Y-186113D01*
X-264251Y-186446D01*
X-263918Y-187030D01*
X-263834Y-187696D01*
X-263918Y-188363D01*
X-264251Y-188946D01*
X-264751Y-189280D01*
X-265251Y-189363D01*
G01X-261151Y-191030D02*
Y-186030D01*
G01Y-186780D02*
X-260734Y-186363D01*
X-260318Y-186113D01*
X-259651Y-186030D01*
X-259068Y-186113D01*
X-258484Y-186530D01*
X-258234Y-187113D01*
X-258151Y-187696D01*
X-258234Y-188280D01*
X-258484Y-188863D01*
X-258984Y-189196D01*
X-259651Y-189363D01*
X-260234Y-189280D01*
X-260818Y-189030D01*
X-261151Y-188696D01*
G01X-249701Y-188780D02*
X-249284Y-189113D01*
X-248701Y-189363D01*
X-248201D01*
X-247701Y-189196D01*
X-247368Y-188946D01*
X-247201Y-188613D01*
X-247284Y-188113D01*
X-247618Y-187863D01*
X-249118Y-187363D01*
X-249451Y-186780D01*
X-249284Y-186363D01*
X-248951Y-186113D01*
X-248451Y-186030D01*
X-247951Y-186113D01*
X-247451Y-186363D01*
G01X-242851Y-186030D02*
Y-189363D01*
G01Y-184696D02*
X-243018Y-184613D01*
Y-184446D01*
X-242851Y-184363D01*
X-242684Y-184446D01*
Y-184613D01*
X-242851Y-184696D01*
G01X-238501Y-186030D02*
X-236001D01*
X-238501Y-189363D01*
X-236001D01*
G01X-232901Y-187113D02*
X-230234D01*
X-230484Y-186530D01*
X-230901Y-186196D01*
X-231484Y-186030D01*
X-232068Y-186113D01*
X-232568Y-186363D01*
X-232901Y-186946D01*
X-233068Y-187446D01*
Y-187946D01*
X-232901Y-188446D01*
X-232484Y-188946D01*
X-231984Y-189280D01*
X-231401Y-189363D01*
X-230818Y-189196D01*
X-230234Y-188696D01*
G01X-220451Y-189363D02*
X-220951Y-189280D01*
X-221451Y-188946D01*
X-221784Y-188363D01*
X-221951Y-187696D01*
X-221784Y-187030D01*
X-221451Y-186446D01*
X-220951Y-186113D01*
X-220451Y-186030D01*
X-219951Y-186113D01*
X-219451Y-186446D01*
X-219118Y-187030D01*
X-219034Y-187696D01*
X-219118Y-188363D01*
X-219451Y-188946D01*
X-219951Y-189280D01*
X-220451Y-189363D01*
G01X-215351D02*
Y-185113D01*
X-215184Y-184696D01*
X-214851Y-184446D01*
X-214351Y-184363D01*
X-213851Y-184530D01*
X-213601Y-184946D01*
G01X-214601Y-186363D02*
X-216268D01*
G01X-205318Y-189363D02*
Y-184363D01*
X-203318D01*
X-202651Y-184613D01*
X-202151Y-185196D01*
X-201984Y-185863D01*
X-202151Y-186530D01*
X-202568Y-187030D01*
X-203318Y-187280D01*
X-205318D01*
G01X-200134Y-189363D02*
X-198051Y-184363D01*
X-195968Y-189363D01*
G01X-196718Y-187613D02*
X-199384D01*
G01X-194284Y-189363D02*
Y-184363D01*
X-192618D01*
X-191951Y-184613D01*
X-191451Y-184946D01*
X-191034Y-185446D01*
X-190701Y-186030D01*
X-190618Y-186863D01*
X-190701Y-187696D01*
X-191034Y-188280D01*
X-191451Y-188780D01*
X-191951Y-189113D01*
X-192618Y-189363D01*
X-194284D01*
G01X-182751Y-189530D02*
X-179751Y-184363D01*
G01X-322078Y-182203D02*
Y-177203D01*
X-320078D01*
X-319411Y-177453D01*
X-318911Y-178036D01*
X-318744Y-178703D01*
X-318911Y-179370D01*
X-319328Y-179870D01*
X-320078Y-180120D01*
X-322078D01*
G01X-316894Y-182203D02*
X-314811Y-177203D01*
X-312728Y-182203D01*
G01X-313478Y-180453D02*
X-316144D01*
G01X-311044Y-182203D02*
Y-177203D01*
X-309378D01*
X-308711Y-177453D01*
X-308211Y-177786D01*
X-307794Y-178286D01*
X-307461Y-178870D01*
X-307378Y-179703D01*
X-307461Y-180536D01*
X-307794Y-181120D01*
X-308211Y-181620D01*
X-308711Y-181953D01*
X-309378Y-182203D01*
X-311044D01*
G01X-299261Y-181620D02*
X-298844Y-181953D01*
X-298261Y-182203D01*
X-297761D01*
X-297261Y-182036D01*
X-296928Y-181786D01*
X-296761Y-181453D01*
X-296844Y-180953D01*
X-297178Y-180703D01*
X-298678Y-180203D01*
X-299011Y-179620D01*
X-298844Y-179203D01*
X-298511Y-178953D01*
X-298011Y-178870D01*
X-297511Y-178953D01*
X-297011Y-179203D01*
G01X-292411Y-178870D02*
Y-182203D01*
G01Y-177536D02*
X-292578Y-177453D01*
Y-177286D01*
X-292411Y-177203D01*
X-292244Y-177286D01*
Y-177453D01*
X-292411Y-177536D01*
G01X-288061Y-178870D02*
X-285561D01*
X-288061Y-182203D01*
X-285561D01*
G01X-282461Y-179953D02*
X-279794D01*
X-280044Y-179370D01*
X-280461Y-179036D01*
X-281044Y-178870D01*
X-281628Y-178953D01*
X-282128Y-179203D01*
X-282461Y-179786D01*
X-282628Y-180286D01*
Y-180786D01*
X-282461Y-181286D01*
X-282044Y-181786D01*
X-281544Y-182120D01*
X-280961Y-182203D01*
X-280378Y-182036D01*
X-279794Y-181536D01*
G01X-330911Y-173203D02*
X260089D01*
G01X-320411Y-148703D02*
Y-153703D01*
G01X-322328Y-148703D02*
X-318494D01*
G01X-315978Y-153703D02*
Y-150370D01*
G01Y-151036D02*
X-315561Y-150703D01*
X-315144Y-150453D01*
X-314561Y-150370D01*
X-314144Y-150453D01*
X-313644Y-150703D01*
G01X-307711Y-153703D02*
Y-150370D01*
G01Y-150953D02*
X-308044Y-150620D01*
X-308544Y-150453D01*
X-309128Y-150370D01*
X-309711Y-150536D01*
X-310211Y-150870D01*
X-310544Y-151370D01*
X-310711Y-152036D01*
X-310544Y-152703D01*
X-310211Y-153203D01*
X-309711Y-153536D01*
X-309128Y-153703D01*
X-308544Y-153620D01*
X-308044Y-153370D01*
X-307711Y-153036D01*
G01X-302278Y-150786D02*
X-302861Y-150453D01*
X-303361Y-150370D01*
X-304028Y-150536D01*
X-304528Y-150870D01*
X-304861Y-151453D01*
X-304944Y-152036D01*
X-304861Y-152620D01*
X-304528Y-153120D01*
X-304028Y-153536D01*
X-303361Y-153703D01*
X-302778Y-153536D01*
X-302278Y-153203D01*
G01X-299261Y-151453D02*
X-296594D01*
X-296844Y-150870D01*
X-297261Y-150536D01*
X-297844Y-150370D01*
X-298428Y-150453D01*
X-298928Y-150703D01*
X-299261Y-151286D01*
X-299428Y-151786D01*
Y-152286D01*
X-299261Y-152786D01*
X-298844Y-153286D01*
X-298344Y-153620D01*
X-297761Y-153703D01*
X-297178Y-153536D01*
X-296594Y-153036D01*
G01X-288894Y-150370D02*
X-287894Y-153703D01*
X-286811Y-150370D01*
X-285728Y-153703D01*
X-284728Y-150370D01*
G01X-281211D02*
Y-153703D01*
G01Y-149036D02*
X-281378Y-148953D01*
Y-148786D01*
X-281211Y-148703D01*
X-281044Y-148786D01*
Y-148953D01*
X-281211Y-149036D01*
G01X-274111Y-148703D02*
Y-153703D01*
G01Y-152953D02*
X-274444Y-153370D01*
X-274944Y-153620D01*
X-275528Y-153703D01*
X-276194Y-153536D01*
X-276694Y-153120D01*
X-277028Y-152620D01*
X-277111Y-152036D01*
X-277028Y-151453D01*
X-276694Y-150953D01*
X-276194Y-150536D01*
X-275528Y-150370D01*
X-274944Y-150453D01*
X-274528Y-150620D01*
X-274111Y-150953D01*
G01X-270011Y-148703D02*
Y-153703D01*
G01X-271178Y-150370D02*
X-268844D01*
G01X-265828Y-153703D02*
Y-148703D01*
G01Y-151120D02*
X-265411Y-150703D01*
X-264994Y-150453D01*
X-264328Y-150370D01*
X-263828Y-150453D01*
X-263244Y-150786D01*
X-262994Y-151286D01*
Y-153703D01*
G01X-322078Y-122203D02*
Y-117203D01*
X-319994D01*
X-319328Y-117453D01*
X-318911Y-117786D01*
X-318744Y-118453D01*
X-318911Y-119120D01*
X-319411Y-119536D01*
X-319994Y-119786D01*
X-322078D01*
G01X-319994D02*
X-318744Y-122203D01*
G01X-316061Y-119953D02*
X-313394D01*
X-313644Y-119370D01*
X-314061Y-119036D01*
X-314644Y-118870D01*
X-315228Y-118953D01*
X-315728Y-119203D01*
X-316061Y-119786D01*
X-316228Y-120286D01*
Y-120786D01*
X-316061Y-121286D01*
X-315644Y-121786D01*
X-315144Y-122120D01*
X-314561Y-122203D01*
X-313978Y-122036D01*
X-313394Y-121536D01*
G01X-309211Y-122203D02*
Y-117203D01*
G01X-302111Y-122203D02*
Y-118870D01*
G01Y-119453D02*
X-302444Y-119120D01*
X-302944Y-118953D01*
X-303528Y-118870D01*
X-304111Y-119036D01*
X-304611Y-119370D01*
X-304944Y-119870D01*
X-305111Y-120536D01*
X-304944Y-121203D01*
X-304611Y-121703D01*
X-304111Y-122036D01*
X-303528Y-122203D01*
X-302944Y-122120D01*
X-302444Y-121870D01*
X-302111Y-121536D01*
G01X-298011Y-117203D02*
Y-122203D01*
G01X-299178Y-118870D02*
X-296844D01*
G01X-292411D02*
Y-122203D01*
G01Y-117536D02*
X-292578Y-117453D01*
Y-117286D01*
X-292411Y-117203D01*
X-292244Y-117286D01*
Y-117453D01*
X-292411Y-117536D01*
G01X-288311Y-118870D02*
X-286811Y-122203D01*
X-285311Y-118870D01*
G01X-282461Y-119953D02*
X-279794D01*
X-280044Y-119370D01*
X-280461Y-119036D01*
X-281044Y-118870D01*
X-281628Y-118953D01*
X-282128Y-119203D01*
X-282461Y-119786D01*
X-282628Y-120286D01*
Y-120786D01*
X-282461Y-121286D01*
X-282044Y-121786D01*
X-281544Y-122120D01*
X-280961Y-122203D01*
X-280378Y-122036D01*
X-279794Y-121536D01*
G01X-271511Y-123870D02*
Y-118870D01*
G01Y-119620D02*
X-271094Y-119203D01*
X-270678Y-118953D01*
X-270011Y-118870D01*
X-269428Y-118953D01*
X-268844Y-119370D01*
X-268594Y-119953D01*
X-268511Y-120536D01*
X-268594Y-121120D01*
X-268844Y-121703D01*
X-269344Y-122036D01*
X-270011Y-122203D01*
X-270594Y-122120D01*
X-271178Y-121870D01*
X-271511Y-121536D01*
G01X-264411Y-122203D02*
X-264911Y-122120D01*
X-265411Y-121786D01*
X-265744Y-121203D01*
X-265911Y-120536D01*
X-265744Y-119870D01*
X-265411Y-119286D01*
X-264911Y-118953D01*
X-264411Y-118870D01*
X-263911Y-118953D01*
X-263411Y-119286D01*
X-263078Y-119870D01*
X-262994Y-120536D01*
X-263078Y-121203D01*
X-263411Y-121786D01*
X-263911Y-122120D01*
X-264411Y-122203D01*
G01X-260061Y-121620D02*
X-259644Y-121953D01*
X-259061Y-122203D01*
X-258561D01*
X-258061Y-122036D01*
X-257728Y-121786D01*
X-257561Y-121453D01*
X-257644Y-120953D01*
X-257978Y-120703D01*
X-259478Y-120203D01*
X-259811Y-119620D01*
X-259644Y-119203D01*
X-259311Y-118953D01*
X-258811Y-118870D01*
X-258311Y-118953D01*
X-257811Y-119203D01*
G01X-253211Y-118870D02*
Y-122203D01*
G01Y-117536D02*
X-253378Y-117453D01*
Y-117286D01*
X-253211Y-117203D01*
X-253044Y-117286D01*
Y-117453D01*
X-253211Y-117536D01*
G01X-247611Y-117203D02*
Y-122203D01*
G01X-248778Y-118870D02*
X-246444D01*
G01X-242011D02*
Y-122203D01*
G01Y-117536D02*
X-242178Y-117453D01*
Y-117286D01*
X-242011Y-117203D01*
X-241844Y-117286D01*
Y-117453D01*
X-242011Y-117536D01*
G01X-236411Y-122203D02*
X-236911Y-122120D01*
X-237411Y-121786D01*
X-237744Y-121203D01*
X-237911Y-120536D01*
X-237744Y-119870D01*
X-237411Y-119286D01*
X-236911Y-118953D01*
X-236411Y-118870D01*
X-235911Y-118953D01*
X-235411Y-119286D01*
X-235078Y-119870D01*
X-234994Y-120536D01*
X-235078Y-121203D01*
X-235411Y-121786D01*
X-235911Y-122120D01*
X-236411Y-122203D01*
G01X-232228D02*
Y-118870D01*
G01Y-119703D02*
X-231894Y-119286D01*
X-231394Y-118953D01*
X-230728Y-118870D01*
X-230144Y-118953D01*
X-229644Y-119286D01*
X-229394Y-119870D01*
Y-122203D01*
G01X-320411Y-90203D02*
Y-95203D01*
G01X-321578Y-91870D02*
X-319244D01*
G01X-316228Y-95203D02*
Y-90203D01*
G01Y-92620D02*
X-315811Y-92203D01*
X-315394Y-91953D01*
X-314728Y-91870D01*
X-314228Y-91953D01*
X-313644Y-92286D01*
X-313394Y-92786D01*
Y-95203D01*
G01X-309211Y-91870D02*
Y-95203D01*
G01Y-90536D02*
X-309378Y-90453D01*
Y-90286D01*
X-309211Y-90203D01*
X-309044Y-90286D01*
Y-90453D01*
X-309211Y-90536D01*
G01X-302278Y-92286D02*
X-302861Y-91953D01*
X-303361Y-91870D01*
X-304028Y-92036D01*
X-304528Y-92370D01*
X-304861Y-92953D01*
X-304944Y-93536D01*
X-304861Y-94120D01*
X-304528Y-94620D01*
X-304028Y-95036D01*
X-303361Y-95203D01*
X-302778Y-95036D01*
X-302278Y-94703D01*
G01X-299428Y-95203D02*
Y-90203D01*
G01X-296761Y-91870D02*
X-299428Y-93786D01*
G01X-298344Y-93036D02*
X-296594Y-95203D01*
G01X-293828D02*
Y-91870D01*
G01Y-92703D02*
X-293494Y-92286D01*
X-292994Y-91953D01*
X-292328Y-91870D01*
X-291744Y-91953D01*
X-291244Y-92286D01*
X-290994Y-92870D01*
Y-95203D01*
G01X-288061Y-92953D02*
X-285394D01*
X-285644Y-92370D01*
X-286061Y-92036D01*
X-286644Y-91870D01*
X-287228Y-91953D01*
X-287728Y-92203D01*
X-288061Y-92786D01*
X-288228Y-93286D01*
Y-93786D01*
X-288061Y-94286D01*
X-287644Y-94786D01*
X-287144Y-95120D01*
X-286561Y-95203D01*
X-285978Y-95036D01*
X-285394Y-94536D01*
G01X-282461Y-94620D02*
X-282044Y-94953D01*
X-281461Y-95203D01*
X-280961D01*
X-280461Y-95036D01*
X-280128Y-94786D01*
X-279961Y-94453D01*
X-280044Y-93953D01*
X-280378Y-93703D01*
X-281878Y-93203D01*
X-282211Y-92620D01*
X-282044Y-92203D01*
X-281711Y-91953D01*
X-281211Y-91870D01*
X-280711Y-91953D01*
X-280211Y-92203D01*
G01X-276861Y-94620D02*
X-276444Y-94953D01*
X-275861Y-95203D01*
X-275361D01*
X-274861Y-95036D01*
X-274528Y-94786D01*
X-274361Y-94453D01*
X-274444Y-93953D01*
X-274778Y-93703D01*
X-276278Y-93203D01*
X-276611Y-92620D01*
X-276444Y-92203D01*
X-276111Y-91953D01*
X-275611Y-91870D01*
X-275111Y-91953D01*
X-274611Y-92203D01*
G01X-262911Y-95203D02*
Y-91870D01*
G01Y-92453D02*
X-263244Y-92120D01*
X-263744Y-91953D01*
X-264328Y-91870D01*
X-264911Y-92036D01*
X-265411Y-92370D01*
X-265744Y-92870D01*
X-265911Y-93536D01*
X-265744Y-94203D01*
X-265411Y-94703D01*
X-264911Y-95036D01*
X-264328Y-95203D01*
X-263744Y-95120D01*
X-263244Y-94870D01*
X-262911Y-94536D01*
G01X-259311Y-95203D02*
Y-90953D01*
X-259144Y-90536D01*
X-258811Y-90286D01*
X-258311Y-90203D01*
X-257811Y-90370D01*
X-257561Y-90786D01*
G01X-258561Y-92203D02*
X-260228D01*
G01X-253211Y-90203D02*
Y-95203D01*
G01X-254378Y-91870D02*
X-252044D01*
G01X-248861Y-92953D02*
X-246194D01*
X-246444Y-92370D01*
X-246861Y-92036D01*
X-247444Y-91870D01*
X-248028Y-91953D01*
X-248528Y-92203D01*
X-248861Y-92786D01*
X-249028Y-93286D01*
Y-93786D01*
X-248861Y-94286D01*
X-248444Y-94786D01*
X-247944Y-95120D01*
X-247361Y-95203D01*
X-246778Y-95036D01*
X-246194Y-94536D01*
G01X-243178Y-95203D02*
Y-91870D01*
G01Y-92536D02*
X-242761Y-92203D01*
X-242344Y-91953D01*
X-241761Y-91870D01*
X-241344Y-91953D01*
X-240844Y-92203D01*
G01X-232311Y-96870D02*
Y-91870D01*
G01Y-92620D02*
X-231894Y-92203D01*
X-231478Y-91953D01*
X-230811Y-91870D01*
X-230228Y-91953D01*
X-229644Y-92370D01*
X-229394Y-92953D01*
X-229311Y-93536D01*
X-229394Y-94120D01*
X-229644Y-94703D01*
X-230144Y-95036D01*
X-230811Y-95203D01*
X-231394Y-95120D01*
X-231978Y-94870D01*
X-232311Y-94536D01*
G01X-225211Y-95203D02*
Y-90203D01*
G01X-218111Y-95203D02*
Y-91870D01*
G01Y-92453D02*
X-218444Y-92120D01*
X-218944Y-91953D01*
X-219528Y-91870D01*
X-220111Y-92036D01*
X-220611Y-92370D01*
X-220944Y-92870D01*
X-221111Y-93536D01*
X-220944Y-94203D01*
X-220611Y-94703D01*
X-220111Y-95036D01*
X-219528Y-95203D01*
X-218944Y-95120D01*
X-218444Y-94870D01*
X-218111Y-94536D01*
G01X-214011Y-90203D02*
Y-95203D01*
G01X-215178Y-91870D02*
X-212844D01*
G01X-208411D02*
Y-95203D01*
G01Y-90536D02*
X-208578Y-90453D01*
Y-90286D01*
X-208411Y-90203D01*
X-208244Y-90286D01*
Y-90453D01*
X-208411Y-90536D01*
G01X-204228Y-95203D02*
Y-91870D01*
G01Y-92703D02*
X-203894Y-92286D01*
X-203394Y-91953D01*
X-202728Y-91870D01*
X-202144Y-91953D01*
X-201644Y-92286D01*
X-201394Y-92870D01*
Y-95203D01*
G01X-198378Y-96453D02*
X-197794Y-96786D01*
X-197128Y-96870D01*
X-196544Y-96786D01*
X-196044Y-96370D01*
X-195711Y-95786D01*
Y-91870D01*
G01Y-92536D02*
X-196044Y-92203D01*
X-196544Y-91953D01*
X-197128Y-91870D01*
X-197794Y-92036D01*
X-198211Y-92370D01*
X-198544Y-92953D01*
X-198711Y-93536D01*
X-198628Y-94036D01*
X-198294Y-94620D01*
X-197794Y-95036D01*
X-197128Y-95203D01*
X-196628Y-95120D01*
X-196044Y-94786D01*
X-195711Y-94453D01*
G01X-318744Y-85203D02*
X-322078D01*
Y-80203D01*
X-318744D01*
G01X-320078Y-82620D02*
X-322078D01*
G01X-316061Y-81870D02*
X-313561Y-85203D01*
G01Y-81870D02*
X-316061Y-85203D01*
G01X-309211Y-80203D02*
Y-85203D01*
G01X-310378Y-81870D02*
X-308044D01*
G01X-304861Y-82953D02*
X-302194D01*
X-302444Y-82370D01*
X-302861Y-82036D01*
X-303444Y-81870D01*
X-304028Y-81953D01*
X-304528Y-82203D01*
X-304861Y-82786D01*
X-305028Y-83286D01*
Y-83786D01*
X-304861Y-84286D01*
X-304444Y-84786D01*
X-303944Y-85120D01*
X-303361Y-85203D01*
X-302778Y-85036D01*
X-302194Y-84536D01*
G01X-299178Y-85203D02*
Y-81870D01*
G01Y-82536D02*
X-298761Y-82203D01*
X-298344Y-81953D01*
X-297761Y-81870D01*
X-297344Y-81953D01*
X-296844Y-82203D01*
G01X-293828Y-85203D02*
Y-81870D01*
G01Y-82703D02*
X-293494Y-82286D01*
X-292994Y-81953D01*
X-292328Y-81870D01*
X-291744Y-81953D01*
X-291244Y-82286D01*
X-290994Y-82870D01*
Y-85203D01*
G01X-285311D02*
Y-81870D01*
G01Y-82453D02*
X-285644Y-82120D01*
X-286144Y-81953D01*
X-286728Y-81870D01*
X-287311Y-82036D01*
X-287811Y-82370D01*
X-288144Y-82870D01*
X-288311Y-83536D01*
X-288144Y-84203D01*
X-287811Y-84703D01*
X-287311Y-85036D01*
X-286728Y-85203D01*
X-286144Y-85120D01*
X-285644Y-84870D01*
X-285311Y-84536D01*
G01X-281211Y-85203D02*
Y-80203D01*
G01X-268678Y-82286D02*
X-269261Y-81953D01*
X-269761Y-81870D01*
X-270428Y-82036D01*
X-270928Y-82370D01*
X-271261Y-82953D01*
X-271344Y-83536D01*
X-271261Y-84120D01*
X-270928Y-84620D01*
X-270428Y-85036D01*
X-269761Y-85203D01*
X-269178Y-85036D01*
X-268678Y-84703D01*
G01X-264411Y-85203D02*
X-264911Y-85120D01*
X-265411Y-84786D01*
X-265744Y-84203D01*
X-265911Y-83536D01*
X-265744Y-82870D01*
X-265411Y-82286D01*
X-264911Y-81953D01*
X-264411Y-81870D01*
X-263911Y-81953D01*
X-263411Y-82286D01*
X-263078Y-82870D01*
X-262994Y-83536D01*
X-263078Y-84203D01*
X-263411Y-84786D01*
X-263911Y-85120D01*
X-264411Y-85203D01*
G01X-260228D02*
Y-81870D01*
G01Y-82703D02*
X-259894Y-82286D01*
X-259394Y-81953D01*
X-258728Y-81870D01*
X-258144Y-81953D01*
X-257644Y-82286D01*
X-257394Y-82870D01*
Y-85203D01*
G01X-251711Y-80203D02*
Y-85203D01*
G01Y-84453D02*
X-252044Y-84870D01*
X-252544Y-85120D01*
X-253128Y-85203D01*
X-253794Y-85036D01*
X-254294Y-84620D01*
X-254628Y-84120D01*
X-254711Y-83536D01*
X-254628Y-82953D01*
X-254294Y-82453D01*
X-253794Y-82036D01*
X-253128Y-81870D01*
X-252544Y-81953D01*
X-252128Y-82120D01*
X-251711Y-82453D01*
G01X-249028Y-81870D02*
Y-84203D01*
X-248694Y-84786D01*
X-248194Y-85120D01*
X-247611Y-85203D01*
X-247028Y-85120D01*
X-246528Y-84786D01*
X-246194Y-84203D01*
G01Y-85203D02*
Y-81870D01*
G01X-240678Y-82286D02*
X-241261Y-81953D01*
X-241761Y-81870D01*
X-242428Y-82036D01*
X-242928Y-82370D01*
X-243261Y-82953D01*
X-243344Y-83536D01*
X-243261Y-84120D01*
X-242928Y-84620D01*
X-242428Y-85036D01*
X-241761Y-85203D01*
X-241178Y-85036D01*
X-240678Y-84703D01*
G01X-236411Y-80203D02*
Y-85203D01*
G01X-237578Y-81870D02*
X-235244D01*
G01X-230811Y-85203D02*
X-231311Y-85120D01*
X-231811Y-84786D01*
X-232144Y-84203D01*
X-232311Y-83536D01*
X-232144Y-82870D01*
X-231811Y-82286D01*
X-231311Y-81953D01*
X-230811Y-81870D01*
X-230311Y-81953D01*
X-229811Y-82286D01*
X-229478Y-82870D01*
X-229394Y-83536D01*
X-229478Y-84203D01*
X-229811Y-84786D01*
X-230311Y-85120D01*
X-230811Y-85203D01*
G01X-226378D02*
Y-81870D01*
G01Y-82536D02*
X-225961Y-82203D01*
X-225544Y-81953D01*
X-224961Y-81870D01*
X-224544Y-81953D01*
X-224044Y-82203D01*
G01X-322078Y122797D02*
Y117797D01*
X-318744D01*
G01X-313311D02*
Y121130D01*
G01Y120547D02*
X-313644Y120880D01*
X-314144Y121047D01*
X-314728Y121130D01*
X-315311Y120964D01*
X-315811Y120630D01*
X-316144Y120130D01*
X-316311Y119464D01*
X-316144Y118797D01*
X-315811Y118297D01*
X-315311Y117964D01*
X-314728Y117797D01*
X-314144Y117880D01*
X-313644Y118130D01*
X-313311Y118464D01*
G01X-310461Y118380D02*
X-310044Y118047D01*
X-309461Y117797D01*
X-308961D01*
X-308461Y117964D01*
X-308128Y118214D01*
X-307961Y118547D01*
X-308044Y119047D01*
X-308378Y119297D01*
X-309878Y119797D01*
X-310211Y120380D01*
X-310044Y120797D01*
X-309711Y121047D01*
X-309211Y121130D01*
X-308711Y121047D01*
X-308211Y120797D01*
G01X-304861Y120047D02*
X-302194D01*
X-302444Y120630D01*
X-302861Y120964D01*
X-303444Y121130D01*
X-304028Y121047D01*
X-304528Y120797D01*
X-304861Y120214D01*
X-305028Y119714D01*
Y119214D01*
X-304861Y118714D01*
X-304444Y118214D01*
X-303944Y117880D01*
X-303361Y117797D01*
X-302778Y117964D01*
X-302194Y118464D01*
G01X-299178Y117797D02*
Y121130D01*
G01Y120464D02*
X-298761Y120797D01*
X-298344Y121047D01*
X-297761Y121130D01*
X-297344Y121047D01*
X-296844Y120797D01*
G01X-288311Y121130D02*
X-286811Y117797D01*
X-285311Y121130D01*
G01X-281211D02*
Y117797D01*
G01Y122464D02*
X-281378Y122547D01*
Y122714D01*
X-281211Y122797D01*
X-281044Y122714D01*
Y122547D01*
X-281211Y122464D01*
G01X-274111Y117797D02*
Y121130D01*
G01Y120547D02*
X-274444Y120880D01*
X-274944Y121047D01*
X-275528Y121130D01*
X-276111Y120964D01*
X-276611Y120630D01*
X-276944Y120130D01*
X-277111Y119464D01*
X-276944Y118797D01*
X-276611Y118297D01*
X-276111Y117964D01*
X-275528Y117797D01*
X-274944Y117880D01*
X-274444Y118130D01*
X-274111Y118464D01*
G01X-266244Y117630D02*
X-262578Y121297D01*
G01X-264411Y121964D02*
Y116964D01*
G01X-262578Y117630D02*
X-266244Y121297D01*
G01X-266911Y119464D02*
X-261911D01*
G01X-259228Y116130D02*
X-260061Y116964D01*
X-260478Y117797D01*
Y121130D01*
X-260061Y121964D01*
X-259228Y122797D01*
G01X-255044Y118547D02*
X-254544Y118130D01*
X-253961Y117880D01*
X-253211Y117797D01*
X-252461Y117964D01*
X-251878Y118297D01*
X-251461Y118880D01*
X-251378Y119547D01*
X-251544Y120214D01*
X-251961Y120630D01*
X-252544Y120964D01*
X-253128Y121047D01*
X-253711Y120964D01*
X-254461Y120630D01*
X-254211Y122797D01*
X-251961D01*
G01X-247611Y117630D02*
X-247778Y117714D01*
Y117880D01*
X-247611Y117964D01*
X-247444Y117880D01*
Y117714D01*
X-247611Y117630D01*
G01X-242011Y117797D02*
Y122797D01*
X-243011Y121797D01*
G01Y117797D02*
X-241011D01*
G01X-235994Y116130D02*
X-235161Y116964D01*
X-234744Y117797D01*
Y121130D01*
X-235161Y121964D01*
X-235994Y122797D01*
G01X-329411Y130797D02*
X260089D01*
G01X-322078Y172797D02*
Y177797D01*
X-320078D01*
X-319411Y177547D01*
X-318911Y176964D01*
X-318744Y176297D01*
X-318911Y175630D01*
X-319328Y175130D01*
X-320078Y174880D01*
X-322078D01*
G01X-314811Y177797D02*
Y172797D01*
G01X-316728Y177797D02*
X-312894D01*
G01X-310961Y172797D02*
Y177797D01*
G01X-307461D02*
Y172797D01*
G01Y175297D02*
X-310961D01*
G01X-299178Y172797D02*
Y176130D01*
G01Y175464D02*
X-298761Y175797D01*
X-298344Y176047D01*
X-297761Y176130D01*
X-297344Y176047D01*
X-296844Y175797D01*
G01X-293661Y175047D02*
X-290994D01*
X-291244Y175630D01*
X-291661Y175964D01*
X-292244Y176130D01*
X-292828Y176047D01*
X-293328Y175797D01*
X-293661Y175214D01*
X-293828Y174714D01*
Y174214D01*
X-293661Y173714D01*
X-293244Y173214D01*
X-292744Y172880D01*
X-292161Y172797D01*
X-291578Y172964D01*
X-290994Y173464D01*
G01X-287978Y171547D02*
X-287394Y171214D01*
X-286728Y171130D01*
X-286144Y171214D01*
X-285644Y171630D01*
X-285311Y172214D01*
Y176130D01*
G01Y175464D02*
X-285644Y175797D01*
X-286144Y176047D01*
X-286728Y176130D01*
X-287394Y175964D01*
X-287811Y175630D01*
X-288144Y175047D01*
X-288311Y174464D01*
X-288228Y173964D01*
X-287894Y173380D01*
X-287394Y172964D01*
X-286728Y172797D01*
X-286228Y172880D01*
X-285644Y173214D01*
X-285311Y173547D01*
G01X-281211Y176130D02*
Y172797D01*
G01Y177464D02*
X-281378Y177547D01*
Y177714D01*
X-281211Y177797D01*
X-281044Y177714D01*
Y177547D01*
X-281211Y177464D01*
G01X-276861Y173380D02*
X-276444Y173047D01*
X-275861Y172797D01*
X-275361D01*
X-274861Y172964D01*
X-274528Y173214D01*
X-274361Y173547D01*
X-274444Y174047D01*
X-274778Y174297D01*
X-276278Y174797D01*
X-276611Y175380D01*
X-276444Y175797D01*
X-276111Y176047D01*
X-275611Y176130D01*
X-275111Y176047D01*
X-274611Y175797D01*
G01X-270011Y177797D02*
Y172797D01*
G01X-271178Y176130D02*
X-268844D01*
G01X-265578Y172797D02*
Y176130D01*
G01Y175464D02*
X-265161Y175797D01*
X-264744Y176047D01*
X-264161Y176130D01*
X-263744Y176047D01*
X-263244Y175797D01*
G01X-257311Y172797D02*
Y176130D01*
G01Y175547D02*
X-257644Y175880D01*
X-258144Y176047D01*
X-258728Y176130D01*
X-259311Y175964D01*
X-259811Y175630D01*
X-260144Y175130D01*
X-260311Y174464D01*
X-260144Y173797D01*
X-259811Y173297D01*
X-259311Y172964D01*
X-258728Y172797D01*
X-258144Y172880D01*
X-257644Y173130D01*
X-257311Y173464D01*
G01X-253211Y177797D02*
Y172797D01*
G01X-254378Y176130D02*
X-252044D01*
G01X-247611D02*
Y172797D01*
G01Y177464D02*
X-247778Y177547D01*
Y177714D01*
X-247611Y177797D01*
X-247444Y177714D01*
Y177547D01*
X-247611Y177464D01*
G01X-242011Y172797D02*
X-242511Y172880D01*
X-243011Y173214D01*
X-243344Y173797D01*
X-243511Y174464D01*
X-243344Y175130D01*
X-243011Y175714D01*
X-242511Y176047D01*
X-242011Y176130D01*
X-241511Y176047D01*
X-241011Y175714D01*
X-240678Y175130D01*
X-240594Y174464D01*
X-240678Y173797D01*
X-241011Y173214D01*
X-241511Y172880D01*
X-242011Y172797D01*
G01X-237828D02*
Y176130D01*
G01Y175297D02*
X-237494Y175714D01*
X-236994Y176047D01*
X-236328Y176130D01*
X-235744Y176047D01*
X-235244Y175714D01*
X-234994Y175130D01*
Y172797D01*
G01X-330911Y190297D02*
X260089D01*
G01X-322244Y199297D02*
Y204297D01*
X-320578D01*
X-319911Y204047D01*
X-319411Y203714D01*
X-318994Y203214D01*
X-318661Y202630D01*
X-318578Y201797D01*
X-318661Y200964D01*
X-318994Y200380D01*
X-319411Y199880D01*
X-319911Y199547D01*
X-320578Y199297D01*
X-322244D01*
G01X-316061Y201547D02*
X-313394D01*
X-313644Y202130D01*
X-314061Y202464D01*
X-314644Y202630D01*
X-315228Y202547D01*
X-315728Y202297D01*
X-316061Y201714D01*
X-316228Y201214D01*
Y200714D01*
X-316061Y200214D01*
X-315644Y199714D01*
X-315144Y199380D01*
X-314561Y199297D01*
X-313978Y199464D01*
X-313394Y199964D01*
G01X-310711Y197630D02*
Y202630D01*
G01Y201880D02*
X-310294Y202297D01*
X-309878Y202547D01*
X-309211Y202630D01*
X-308628Y202547D01*
X-308044Y202130D01*
X-307794Y201547D01*
X-307711Y200964D01*
X-307794Y200380D01*
X-308044Y199797D01*
X-308544Y199464D01*
X-309211Y199297D01*
X-309794Y199380D01*
X-310378Y199630D01*
X-310711Y199964D01*
G01X-303611Y204297D02*
Y199297D01*
G01X-304778Y202630D02*
X-302444D01*
G01X-299428Y199297D02*
Y204297D01*
G01Y201880D02*
X-299011Y202297D01*
X-298594Y202547D01*
X-297928Y202630D01*
X-297428Y202547D01*
X-296844Y202214D01*
X-296594Y201714D01*
Y199297D01*
G01X-285478Y202214D02*
X-286061Y202547D01*
X-286561Y202630D01*
X-287228Y202464D01*
X-287728Y202130D01*
X-288061Y201547D01*
X-288144Y200964D01*
X-288061Y200380D01*
X-287728Y199880D01*
X-287228Y199464D01*
X-286561Y199297D01*
X-285978Y199464D01*
X-285478Y199797D01*
G01X-281211Y199297D02*
X-281711Y199380D01*
X-282211Y199714D01*
X-282544Y200297D01*
X-282711Y200964D01*
X-282544Y201630D01*
X-282211Y202214D01*
X-281711Y202547D01*
X-281211Y202630D01*
X-280711Y202547D01*
X-280211Y202214D01*
X-279878Y201630D01*
X-279794Y200964D01*
X-279878Y200297D01*
X-280211Y199714D01*
X-280711Y199380D01*
X-281211Y199297D01*
G01X-277028D02*
Y202630D01*
G01Y201797D02*
X-276694Y202214D01*
X-276194Y202547D01*
X-275528Y202630D01*
X-274944Y202547D01*
X-274444Y202214D01*
X-274194Y201630D01*
Y199297D01*
G01X-270011Y204297D02*
Y199297D01*
G01X-271178Y202630D02*
X-268844D01*
G01X-265578Y199297D02*
Y202630D01*
G01Y201964D02*
X-265161Y202297D01*
X-264744Y202547D01*
X-264161Y202630D01*
X-263744Y202547D01*
X-263244Y202297D01*
G01X-258811Y199297D02*
X-259311Y199380D01*
X-259811Y199714D01*
X-260144Y200297D01*
X-260311Y200964D01*
X-260144Y201630D01*
X-259811Y202214D01*
X-259311Y202547D01*
X-258811Y202630D01*
X-258311Y202547D01*
X-257811Y202214D01*
X-257478Y201630D01*
X-257394Y200964D01*
X-257478Y200297D01*
X-257811Y199714D01*
X-258311Y199380D01*
X-258811Y199297D01*
G01X-253211D02*
Y204297D01*
G01X-243428Y199297D02*
Y204297D01*
G01Y201880D02*
X-243011Y202297D01*
X-242594Y202547D01*
X-241928Y202630D01*
X-241428Y202547D01*
X-240844Y202214D01*
X-240594Y201714D01*
Y199297D01*
G01X-236411D02*
X-236911Y199380D01*
X-237411Y199714D01*
X-237744Y200297D01*
X-237911Y200964D01*
X-237744Y201630D01*
X-237411Y202214D01*
X-236911Y202547D01*
X-236411Y202630D01*
X-235911Y202547D01*
X-235411Y202214D01*
X-235078Y201630D01*
X-234994Y200964D01*
X-235078Y200297D01*
X-235411Y199714D01*
X-235911Y199380D01*
X-236411Y199297D01*
G01X-230811D02*
Y204297D01*
G01X-226461Y201547D02*
X-223794D01*
X-224044Y202130D01*
X-224461Y202464D01*
X-225044Y202630D01*
X-225628Y202547D01*
X-226128Y202297D01*
X-226461Y201714D01*
X-226628Y201214D01*
Y200714D01*
X-226461Y200214D01*
X-226044Y199714D01*
X-225544Y199380D01*
X-224961Y199297D01*
X-224378Y199464D01*
X-223794Y199964D01*
G01X-330911Y215297D02*
X260089D01*
G01X-322078Y221297D02*
Y226297D01*
X-319994D01*
X-319328Y226047D01*
X-318911Y225714D01*
X-318744Y225047D01*
X-318911Y224380D01*
X-319411Y223964D01*
X-319994Y223714D01*
X-322078D01*
G01X-319994D02*
X-318744Y221297D01*
G01X-314811D02*
X-315311Y221380D01*
X-315811Y221714D01*
X-316144Y222297D01*
X-316311Y222964D01*
X-316144Y223630D01*
X-315811Y224214D01*
X-315311Y224547D01*
X-314811Y224630D01*
X-314311Y224547D01*
X-313811Y224214D01*
X-313478Y223630D01*
X-313394Y222964D01*
X-313478Y222297D01*
X-313811Y221714D01*
X-314311Y221380D01*
X-314811Y221297D01*
G01X-310628Y224630D02*
Y222297D01*
X-310294Y221714D01*
X-309794Y221380D01*
X-309211Y221297D01*
X-308628Y221380D01*
X-308128Y221714D01*
X-307794Y222297D01*
G01Y221297D02*
Y224630D01*
G01X-304778Y220047D02*
X-304194Y219714D01*
X-303528Y219630D01*
X-302944Y219714D01*
X-302444Y220130D01*
X-302111Y220714D01*
Y224630D01*
G01Y223964D02*
X-302444Y224297D01*
X-302944Y224547D01*
X-303528Y224630D01*
X-304194Y224464D01*
X-304611Y224130D01*
X-304944Y223547D01*
X-305111Y222964D01*
X-305028Y222464D01*
X-304694Y221880D01*
X-304194Y221464D01*
X-303528Y221297D01*
X-303028Y221380D01*
X-302444Y221714D01*
X-302111Y222047D01*
G01X-299428Y221297D02*
Y226297D01*
G01Y223880D02*
X-299011Y224297D01*
X-298594Y224547D01*
X-297928Y224630D01*
X-297428Y224547D01*
X-296844Y224214D01*
X-296594Y223714D01*
Y221297D01*
G01X-293828D02*
Y224630D01*
G01Y223797D02*
X-293494Y224214D01*
X-292994Y224547D01*
X-292328Y224630D01*
X-291744Y224547D01*
X-291244Y224214D01*
X-290994Y223630D01*
Y221297D01*
G01X-288061Y223547D02*
X-285394D01*
X-285644Y224130D01*
X-286061Y224464D01*
X-286644Y224630D01*
X-287228Y224547D01*
X-287728Y224297D01*
X-288061Y223714D01*
X-288228Y223214D01*
Y222714D01*
X-288061Y222214D01*
X-287644Y221714D01*
X-287144Y221380D01*
X-286561Y221297D01*
X-285978Y221464D01*
X-285394Y221964D01*
G01X-282461Y221880D02*
X-282044Y221547D01*
X-281461Y221297D01*
X-280961D01*
X-280461Y221464D01*
X-280128Y221714D01*
X-279961Y222047D01*
X-280044Y222547D01*
X-280378Y222797D01*
X-281878Y223297D01*
X-282211Y223880D01*
X-282044Y224297D01*
X-281711Y224547D01*
X-281211Y224630D01*
X-280711Y224547D01*
X-280211Y224297D01*
G01X-276861Y221880D02*
X-276444Y221547D01*
X-275861Y221297D01*
X-275361D01*
X-274861Y221464D01*
X-274528Y221714D01*
X-274361Y222047D01*
X-274444Y222547D01*
X-274778Y222797D01*
X-276278Y223297D01*
X-276611Y223880D01*
X-276444Y224297D01*
X-276111Y224547D01*
X-275611Y224630D01*
X-275111Y224547D01*
X-274611Y224297D01*
G01X-330411Y230297D02*
X260089D01*
G01X-322161Y279797D02*
Y284797D01*
G01X-318661D02*
Y279797D01*
G01Y282297D02*
X-322161D01*
G01X-314811Y279797D02*
X-315311Y279880D01*
X-315811Y280214D01*
X-316144Y280797D01*
X-316311Y281464D01*
X-316144Y282130D01*
X-315811Y282714D01*
X-315311Y283047D01*
X-314811Y283130D01*
X-314311Y283047D01*
X-313811Y282714D01*
X-313478Y282130D01*
X-313394Y281464D01*
X-313478Y280797D01*
X-313811Y280214D01*
X-314311Y279880D01*
X-314811Y279797D01*
G01X-309211D02*
Y284797D01*
G01X-304861Y282047D02*
X-302194D01*
X-302444Y282630D01*
X-302861Y282964D01*
X-303444Y283130D01*
X-304028Y283047D01*
X-304528Y282797D01*
X-304861Y282214D01*
X-305028Y281714D01*
Y281214D01*
X-304861Y280714D01*
X-304444Y280214D01*
X-303944Y279880D01*
X-303361Y279797D01*
X-302778Y279964D01*
X-302194Y280464D01*
G01X-293661Y280380D02*
X-293244Y280047D01*
X-292661Y279797D01*
X-292161D01*
X-291661Y279964D01*
X-291328Y280214D01*
X-291161Y280547D01*
X-291244Y281047D01*
X-291578Y281297D01*
X-293078Y281797D01*
X-293411Y282380D01*
X-293244Y282797D01*
X-292911Y283047D01*
X-292411Y283130D01*
X-291911Y283047D01*
X-291411Y282797D01*
G01X-286811Y283130D02*
Y279797D01*
G01Y284464D02*
X-286978Y284547D01*
Y284714D01*
X-286811Y284797D01*
X-286644Y284714D01*
Y284547D01*
X-286811Y284464D01*
G01X-282461Y283130D02*
X-279961D01*
X-282461Y279797D01*
X-279961D01*
G01X-276861Y282047D02*
X-274194D01*
X-274444Y282630D01*
X-274861Y282964D01*
X-275444Y283130D01*
X-276028Y283047D01*
X-276528Y282797D01*
X-276861Y282214D01*
X-277028Y281714D01*
Y281214D01*
X-276861Y280714D01*
X-276444Y280214D01*
X-275944Y279880D01*
X-275361Y279797D01*
X-274778Y279964D01*
X-274194Y280464D01*
G01X-322161Y354797D02*
Y359797D01*
G01X-318661D02*
Y354797D01*
G01Y357297D02*
X-322161D01*
G01X-314811Y354797D02*
X-315311Y354880D01*
X-315811Y355214D01*
X-316144Y355797D01*
X-316311Y356464D01*
X-316144Y357130D01*
X-315811Y357714D01*
X-315311Y358047D01*
X-314811Y358130D01*
X-314311Y358047D01*
X-313811Y357714D01*
X-313478Y357130D01*
X-313394Y356464D01*
X-313478Y355797D01*
X-313811Y355214D01*
X-314311Y354880D01*
X-314811Y354797D01*
G01X-309211D02*
Y359797D01*
G01X-304861Y357047D02*
X-302194D01*
X-302444Y357630D01*
X-302861Y357964D01*
X-303444Y358130D01*
X-304028Y358047D01*
X-304528Y357797D01*
X-304861Y357214D01*
X-305028Y356714D01*
Y356214D01*
X-304861Y355714D01*
X-304444Y355214D01*
X-303944Y354880D01*
X-303361Y354797D01*
X-302778Y354964D01*
X-302194Y355464D01*
G01X-293911Y353130D02*
Y358130D01*
G01Y357380D02*
X-293494Y357797D01*
X-293078Y358047D01*
X-292411Y358130D01*
X-291828Y358047D01*
X-291244Y357630D01*
X-290994Y357047D01*
X-290911Y356464D01*
X-290994Y355880D01*
X-291244Y355297D01*
X-291744Y354964D01*
X-292411Y354797D01*
X-292994Y354880D01*
X-293578Y355130D01*
X-293911Y355464D01*
G01X-286811Y354797D02*
X-287311Y354880D01*
X-287811Y355214D01*
X-288144Y355797D01*
X-288311Y356464D01*
X-288144Y357130D01*
X-287811Y357714D01*
X-287311Y358047D01*
X-286811Y358130D01*
X-286311Y358047D01*
X-285811Y357714D01*
X-285478Y357130D01*
X-285394Y356464D01*
X-285478Y355797D01*
X-285811Y355214D01*
X-286311Y354880D01*
X-286811Y354797D01*
G01X-282461Y355380D02*
X-282044Y355047D01*
X-281461Y354797D01*
X-280961D01*
X-280461Y354964D01*
X-280128Y355214D01*
X-279961Y355547D01*
X-280044Y356047D01*
X-280378Y356297D01*
X-281878Y356797D01*
X-282211Y357380D01*
X-282044Y357797D01*
X-281711Y358047D01*
X-281211Y358130D01*
X-280711Y358047D01*
X-280211Y357797D01*
G01X-275611Y358130D02*
Y354797D01*
G01Y359464D02*
X-275778Y359547D01*
Y359714D01*
X-275611Y359797D01*
X-275444Y359714D01*
Y359547D01*
X-275611Y359464D01*
G01X-270011Y359797D02*
Y354797D01*
G01X-271178Y358130D02*
X-268844D01*
G01X-264411D02*
Y354797D01*
G01Y359464D02*
X-264578Y359547D01*
Y359714D01*
X-264411Y359797D01*
X-264244Y359714D01*
Y359547D01*
X-264411Y359464D01*
G01X-258811Y354797D02*
X-259311Y354880D01*
X-259811Y355214D01*
X-260144Y355797D01*
X-260311Y356464D01*
X-260144Y357130D01*
X-259811Y357714D01*
X-259311Y358047D01*
X-258811Y358130D01*
X-258311Y358047D01*
X-257811Y357714D01*
X-257478Y357130D01*
X-257394Y356464D01*
X-257478Y355797D01*
X-257811Y355214D01*
X-258311Y354880D01*
X-258811Y354797D01*
G01X-254628D02*
Y358130D01*
G01Y357297D02*
X-254294Y357714D01*
X-253794Y358047D01*
X-253128Y358130D01*
X-252544Y358047D01*
X-252044Y357714D01*
X-251794Y357130D01*
Y354797D01*
G01X-242011Y359797D02*
Y354797D01*
G01X-243178Y358130D02*
X-240844D01*
G01X-236411Y354797D02*
X-236911Y354880D01*
X-237411Y355214D01*
X-237744Y355797D01*
X-237911Y356464D01*
X-237744Y357130D01*
X-237411Y357714D01*
X-236911Y358047D01*
X-236411Y358130D01*
X-235911Y358047D01*
X-235411Y357714D01*
X-235078Y357130D01*
X-234994Y356464D01*
X-235078Y355797D01*
X-235411Y355214D01*
X-235911Y354880D01*
X-236411Y354797D01*
G01X-230811D02*
Y359797D01*
G01X-226461Y357047D02*
X-223794D01*
X-224044Y357630D01*
X-224461Y357964D01*
X-225044Y358130D01*
X-225628Y358047D01*
X-226128Y357797D01*
X-226461Y357214D01*
X-226628Y356714D01*
Y356214D01*
X-226461Y355714D01*
X-226044Y355214D01*
X-225544Y354880D01*
X-224961Y354797D01*
X-224378Y354964D01*
X-223794Y355464D01*
G01X-220778Y354797D02*
Y358130D01*
G01Y357464D02*
X-220361Y357797D01*
X-219944Y358047D01*
X-219361Y358130D01*
X-218944Y358047D01*
X-218444Y357797D01*
G01X-212511Y354797D02*
Y358130D01*
G01Y357547D02*
X-212844Y357880D01*
X-213344Y358047D01*
X-213928Y358130D01*
X-214511Y357964D01*
X-215011Y357630D01*
X-215344Y357130D01*
X-215511Y356464D01*
X-215344Y355797D01*
X-215011Y355297D01*
X-214511Y354964D01*
X-213928Y354797D01*
X-213344Y354880D01*
X-212844Y355130D01*
X-212511Y355464D01*
G01X-209828Y354797D02*
Y358130D01*
G01Y357297D02*
X-209494Y357714D01*
X-208994Y358047D01*
X-208328Y358130D01*
X-207744Y358047D01*
X-207244Y357714D01*
X-206994Y357130D01*
Y354797D01*
G01X-201478Y357714D02*
X-202061Y358047D01*
X-202561Y358130D01*
X-203228Y357964D01*
X-203728Y357630D01*
X-204061Y357047D01*
X-204144Y356464D01*
X-204061Y355880D01*
X-203728Y355380D01*
X-203228Y354964D01*
X-202561Y354797D01*
X-201978Y354964D01*
X-201478Y355297D01*
G01X-198461Y357047D02*
X-195794D01*
X-196044Y357630D01*
X-196461Y357964D01*
X-197044Y358130D01*
X-197628Y358047D01*
X-198128Y357797D01*
X-198461Y357214D01*
X-198628Y356714D01*
Y356214D01*
X-198461Y355714D01*
X-198044Y355214D01*
X-197544Y354880D01*
X-196961Y354797D01*
X-196378Y354964D01*
X-195794Y355464D01*
G01X-330911Y350297D02*
X260089D01*
G01X-322494Y376297D02*
X-320411Y371297D01*
X-318328Y376297D01*
G01X-314811Y374630D02*
Y371297D01*
G01Y375964D02*
X-314978Y376047D01*
Y376214D01*
X-314811Y376297D01*
X-314644Y376214D01*
Y376047D01*
X-314811Y375964D01*
G01X-307711Y371297D02*
Y374630D01*
G01Y374047D02*
X-308044Y374380D01*
X-308544Y374547D01*
X-309128Y374630D01*
X-309711Y374464D01*
X-310211Y374130D01*
X-310544Y373630D01*
X-310711Y372964D01*
X-310544Y372297D01*
X-310211Y371797D01*
X-309711Y371464D01*
X-309128Y371297D01*
X-308544Y371380D01*
X-308044Y371630D01*
X-307711Y371964D01*
G01X-299428Y371297D02*
Y376297D01*
G01Y373880D02*
X-299011Y374297D01*
X-298594Y374547D01*
X-297928Y374630D01*
X-297428Y374547D01*
X-296844Y374214D01*
X-296594Y373714D01*
Y371297D01*
G01X-292411D02*
X-292911Y371380D01*
X-293411Y371714D01*
X-293744Y372297D01*
X-293911Y372964D01*
X-293744Y373630D01*
X-293411Y374214D01*
X-292911Y374547D01*
X-292411Y374630D01*
X-291911Y374547D01*
X-291411Y374214D01*
X-291078Y373630D01*
X-290994Y372964D01*
X-291078Y372297D01*
X-291411Y371714D01*
X-291911Y371380D01*
X-292411Y371297D01*
G01X-286811D02*
Y376297D01*
G01X-282461Y373547D02*
X-279794D01*
X-280044Y374130D01*
X-280461Y374464D01*
X-281044Y374630D01*
X-281628Y374547D01*
X-282128Y374297D01*
X-282461Y373714D01*
X-282628Y373214D01*
Y372714D01*
X-282461Y372214D01*
X-282044Y371714D01*
X-281544Y371380D01*
X-280961Y371297D01*
X-280378Y371464D01*
X-279794Y371964D01*
G01X-270011Y376297D02*
Y371297D01*
G01X-271178Y374630D02*
X-268844D01*
G01X-265828Y371297D02*
Y376297D01*
G01Y373880D02*
X-265411Y374297D01*
X-264994Y374547D01*
X-264328Y374630D01*
X-263828Y374547D01*
X-263244Y374214D01*
X-262994Y373714D01*
Y371297D01*
G01X-260061Y373547D02*
X-257394D01*
X-257644Y374130D01*
X-258061Y374464D01*
X-258644Y374630D01*
X-259228Y374547D01*
X-259728Y374297D01*
X-260061Y373714D01*
X-260228Y373214D01*
Y372714D01*
X-260061Y372214D01*
X-259644Y371714D01*
X-259144Y371380D01*
X-258561Y371297D01*
X-257978Y371464D01*
X-257394Y371964D01*
G01X-254378Y371297D02*
Y374630D01*
G01Y373964D02*
X-253961Y374297D01*
X-253544Y374547D01*
X-252961Y374630D01*
X-252544Y374547D01*
X-252044Y374297D01*
G01X-250111Y371297D02*
Y374630D01*
G01Y373714D02*
X-249861Y374130D01*
X-249444Y374464D01*
X-248861Y374630D01*
X-248278Y374464D01*
X-247861Y374130D01*
X-247611Y373714D01*
Y371297D01*
G01Y373714D02*
X-247361Y374130D01*
X-246944Y374464D01*
X-246361Y374630D01*
X-245778Y374464D01*
X-245361Y374130D01*
X-245111Y373630D01*
Y371297D01*
G01X-240511D02*
Y374630D01*
G01Y374047D02*
X-240844Y374380D01*
X-241344Y374547D01*
X-241928Y374630D01*
X-242511Y374464D01*
X-243011Y374130D01*
X-243344Y373630D01*
X-243511Y372964D01*
X-243344Y372297D01*
X-243011Y371797D01*
X-242511Y371464D01*
X-241928Y371297D01*
X-241344Y371380D01*
X-240844Y371630D01*
X-240511Y371964D01*
G01X-236411Y371297D02*
Y376297D01*
G01X-226711Y369630D02*
Y374630D01*
G01Y373880D02*
X-226294Y374297D01*
X-225878Y374547D01*
X-225211Y374630D01*
X-224628Y374547D01*
X-224044Y374130D01*
X-223794Y373547D01*
X-223711Y372964D01*
X-223794Y372380D01*
X-224044Y371797D01*
X-224544Y371464D01*
X-225211Y371297D01*
X-225794Y371380D01*
X-226378Y371630D01*
X-226711Y371964D01*
G01X-218111Y371297D02*
Y374630D01*
G01Y374047D02*
X-218444Y374380D01*
X-218944Y374547D01*
X-219528Y374630D01*
X-220111Y374464D01*
X-220611Y374130D01*
X-220944Y373630D01*
X-221111Y372964D01*
X-220944Y372297D01*
X-220611Y371797D01*
X-220111Y371464D01*
X-219528Y371297D01*
X-218944Y371380D01*
X-218444Y371630D01*
X-218111Y371964D01*
G01X-212511Y376297D02*
Y371297D01*
G01Y372047D02*
X-212844Y371630D01*
X-213344Y371380D01*
X-213928Y371297D01*
X-214594Y371464D01*
X-215094Y371880D01*
X-215428Y372380D01*
X-215511Y372964D01*
X-215428Y373547D01*
X-215094Y374047D01*
X-214594Y374464D01*
X-213928Y374630D01*
X-213344Y374547D01*
X-212928Y374380D01*
X-212511Y374047D01*
G01X-322494Y386297D02*
X-320411Y391297D01*
X-318328Y386297D01*
G01X-319078Y388047D02*
X-321744D01*
G01X-316228Y386297D02*
Y389630D01*
G01Y388797D02*
X-315894Y389214D01*
X-315394Y389547D01*
X-314728Y389630D01*
X-314144Y389547D01*
X-313644Y389214D01*
X-313394Y388630D01*
Y386297D01*
G01X-309211Y391297D02*
Y386297D01*
G01X-310378Y389630D02*
X-308044D01*
G01X-303611D02*
Y386297D01*
G01Y390964D02*
X-303778Y391047D01*
Y391214D01*
X-303611Y391297D01*
X-303444Y391214D01*
Y391047D01*
X-303611Y390964D01*
G01X-299094Y387964D02*
X-296928D01*
G01X-288311Y384630D02*
Y389630D01*
G01Y388880D02*
X-287894Y389297D01*
X-287478Y389547D01*
X-286811Y389630D01*
X-286228Y389547D01*
X-285644Y389130D01*
X-285394Y388547D01*
X-285311Y387964D01*
X-285394Y387380D01*
X-285644Y386797D01*
X-286144Y386464D01*
X-286811Y386297D01*
X-287394Y386380D01*
X-287978Y386630D01*
X-288311Y386964D01*
G01X-279711Y386297D02*
Y389630D01*
G01Y389047D02*
X-280044Y389380D01*
X-280544Y389547D01*
X-281128Y389630D01*
X-281711Y389464D01*
X-282211Y389130D01*
X-282544Y388630D01*
X-282711Y387964D01*
X-282544Y387297D01*
X-282211Y386797D01*
X-281711Y386464D01*
X-281128Y386297D01*
X-280544Y386380D01*
X-280044Y386630D01*
X-279711Y386964D01*
G01X-274111Y391297D02*
Y386297D01*
G01Y387047D02*
X-274444Y386630D01*
X-274944Y386380D01*
X-275528Y386297D01*
X-276194Y386464D01*
X-276694Y386880D01*
X-277028Y387380D01*
X-277111Y387964D01*
X-277028Y388547D01*
X-276694Y389047D01*
X-276194Y389464D01*
X-275528Y389630D01*
X-274944Y389547D01*
X-274528Y389380D01*
X-274111Y389047D01*
G01X-330911Y380297D02*
X260089D01*
G01X-330911Y395297D02*
X260089D01*
G01X-322568Y405887D02*
Y410887D01*
X-318734Y405887D01*
Y410887D01*
G01X-315051Y405887D02*
X-315551Y405970D01*
X-316051Y406304D01*
X-316384Y406887D01*
X-316551Y407554D01*
X-316384Y408220D01*
X-316051Y408804D01*
X-315551Y409137D01*
X-315051Y409220D01*
X-314551Y409137D01*
X-314051Y408804D01*
X-313718Y408220D01*
X-313634Y407554D01*
X-313718Y406887D01*
X-314051Y406304D01*
X-314551Y405970D01*
X-315051Y405887D01*
G01X-310868D02*
Y409220D01*
G01Y408387D02*
X-310534Y408804D01*
X-310034Y409137D01*
X-309368Y409220D01*
X-308784Y409137D01*
X-308284Y408804D01*
X-308034Y408220D01*
Y405887D01*
G01X-304934Y407554D02*
X-302768D01*
G01X-298751Y405887D02*
Y410137D01*
X-298584Y410554D01*
X-298251Y410804D01*
X-297751Y410887D01*
X-297251Y410720D01*
X-297001Y410304D01*
G01X-298001Y408887D02*
X-299668D01*
G01X-294068Y409220D02*
Y406887D01*
X-293734Y406304D01*
X-293234Y405970D01*
X-292651Y405887D01*
X-292068Y405970D01*
X-291568Y406304D01*
X-291234Y406887D01*
G01Y405887D02*
Y409220D01*
G01X-288468Y405887D02*
Y409220D01*
G01Y408387D02*
X-288134Y408804D01*
X-287634Y409137D01*
X-286968Y409220D01*
X-286384Y409137D01*
X-285884Y408804D01*
X-285634Y408220D01*
Y405887D01*
G01X-280118Y408804D02*
X-280701Y409137D01*
X-281201Y409220D01*
X-281868Y409054D01*
X-282368Y408720D01*
X-282701Y408137D01*
X-282784Y407554D01*
X-282701Y406970D01*
X-282368Y406470D01*
X-281868Y406054D01*
X-281201Y405887D01*
X-280618Y406054D01*
X-280118Y406387D01*
G01X-275851Y410887D02*
Y405887D01*
G01X-277018Y409220D02*
X-274684D01*
G01X-270251D02*
Y405887D01*
G01Y410554D02*
X-270418Y410637D01*
Y410804D01*
X-270251Y410887D01*
X-270084Y410804D01*
Y410637D01*
X-270251Y410554D01*
G01X-264651Y405887D02*
X-265151Y405970D01*
X-265651Y406304D01*
X-265984Y406887D01*
X-266151Y407554D01*
X-265984Y408220D01*
X-265651Y408804D01*
X-265151Y409137D01*
X-264651Y409220D01*
X-264151Y409137D01*
X-263651Y408804D01*
X-263318Y408220D01*
X-263234Y407554D01*
X-263318Y406887D01*
X-263651Y406304D01*
X-264151Y405970D01*
X-264651Y405887D01*
G01X-260468D02*
Y409220D01*
G01Y408387D02*
X-260134Y408804D01*
X-259634Y409137D01*
X-258968Y409220D01*
X-258384Y409137D01*
X-257884Y408804D01*
X-257634Y408220D01*
Y405887D01*
G01X-251951D02*
Y409220D01*
G01Y408637D02*
X-252284Y408970D01*
X-252784Y409137D01*
X-253368Y409220D01*
X-253951Y409054D01*
X-254451Y408720D01*
X-254784Y408220D01*
X-254951Y407554D01*
X-254784Y406887D01*
X-254451Y406387D01*
X-253951Y406054D01*
X-253368Y405887D01*
X-252784Y405970D01*
X-252284Y406220D01*
X-251951Y406554D01*
G01X-247851Y405887D02*
Y410887D01*
G01X-238151Y404220D02*
Y409220D01*
G01Y408470D02*
X-237734Y408887D01*
X-237318Y409137D01*
X-236651Y409220D01*
X-236068Y409137D01*
X-235484Y408720D01*
X-235234Y408137D01*
X-235151Y407554D01*
X-235234Y406970D01*
X-235484Y406387D01*
X-235984Y406054D01*
X-236651Y405887D01*
X-237234Y405970D01*
X-237818Y406220D01*
X-238151Y406554D01*
G01X-229551Y405887D02*
Y409220D01*
G01Y408637D02*
X-229884Y408970D01*
X-230384Y409137D01*
X-230968Y409220D01*
X-231551Y409054D01*
X-232051Y408720D01*
X-232384Y408220D01*
X-232551Y407554D01*
X-232384Y406887D01*
X-232051Y406387D01*
X-231551Y406054D01*
X-230968Y405887D01*
X-230384Y405970D01*
X-229884Y406220D01*
X-229551Y406554D01*
G01X-223951Y410887D02*
Y405887D01*
G01Y406637D02*
X-224284Y406220D01*
X-224784Y405970D01*
X-225368Y405887D01*
X-226034Y406054D01*
X-226534Y406470D01*
X-226868Y406970D01*
X-226951Y407554D01*
X-226868Y408137D01*
X-226534Y408637D01*
X-226034Y409054D01*
X-225368Y409220D01*
X-224784Y409137D01*
X-224368Y408970D01*
X-223951Y408637D01*
G01X-274078Y434380D02*
X-274578Y434630D01*
X-275161Y434797D01*
X-275828D01*
X-276578Y434547D01*
X-277161Y434130D01*
X-277578Y433630D01*
X-277911Y432797D01*
X-277994Y432047D01*
X-277828Y431297D01*
X-277578Y430797D01*
X-277078Y430297D01*
X-276494Y429964D01*
X-275911Y429797D01*
X-275328D01*
X-274744Y429964D01*
X-274244Y430214D01*
X-273828Y430547D01*
G01X-270311Y429797D02*
Y434797D01*
G01X-263211Y429797D02*
Y433130D01*
G01Y432547D02*
X-263544Y432880D01*
X-264044Y433047D01*
X-264628Y433130D01*
X-265211Y432964D01*
X-265711Y432630D01*
X-266044Y432130D01*
X-266211Y431464D01*
X-266044Y430797D01*
X-265711Y430297D01*
X-265211Y429964D01*
X-264628Y429797D01*
X-264044Y429880D01*
X-263544Y430130D01*
X-263211Y430464D01*
G01X-260361Y430380D02*
X-259944Y430047D01*
X-259361Y429797D01*
X-258861D01*
X-258361Y429964D01*
X-258028Y430214D01*
X-257861Y430547D01*
X-257944Y431047D01*
X-258278Y431297D01*
X-259778Y431797D01*
X-260111Y432380D01*
X-259944Y432797D01*
X-259611Y433047D01*
X-259111Y433130D01*
X-258611Y433047D01*
X-258111Y432797D01*
G01X-254761Y430380D02*
X-254344Y430047D01*
X-253761Y429797D01*
X-253261D01*
X-252761Y429964D01*
X-252428Y430214D01*
X-252261Y430547D01*
X-252344Y431047D01*
X-252678Y431297D01*
X-254178Y431797D01*
X-254511Y432380D01*
X-254344Y432797D01*
X-254011Y433047D01*
X-253511Y433130D01*
X-253011Y433047D01*
X-252511Y432797D01*
G01X-247911Y433130D02*
Y429797D01*
G01Y434464D02*
X-248078Y434547D01*
Y434714D01*
X-247911Y434797D01*
X-247744Y434714D01*
Y434547D01*
X-247911Y434464D01*
G01X-242811Y429797D02*
Y434047D01*
X-242644Y434464D01*
X-242311Y434714D01*
X-241811Y434797D01*
X-241311Y434630D01*
X-241061Y434214D01*
G01X-242061Y432797D02*
X-243728D01*
G01X-238461Y428297D02*
X-237961Y428130D01*
X-237294Y428297D01*
X-236878Y428630D01*
X-236544Y429047D01*
X-236044Y430380D01*
X-234961Y433130D01*
G01X-237628D02*
X-236044Y430380D01*
G01X-160411Y-297203D02*
Y-293870D01*
G01Y-294453D02*
X-160744Y-294120D01*
X-161244Y-293953D01*
X-161828Y-293870D01*
X-162411Y-294036D01*
X-162911Y-294370D01*
X-163244Y-294870D01*
X-163411Y-295536D01*
X-163244Y-296203D01*
X-162911Y-296703D01*
X-162411Y-297036D01*
X-161828Y-297203D01*
X-161244Y-297120D01*
X-160744Y-296870D01*
X-160411Y-296536D01*
G01X-154811Y-292203D02*
Y-297203D01*
G01Y-296453D02*
X-155144Y-296870D01*
X-155644Y-297120D01*
X-156228Y-297203D01*
X-156894Y-297036D01*
X-157394Y-296620D01*
X-157728Y-296120D01*
X-157811Y-295536D01*
X-157728Y-294953D01*
X-157394Y-294453D01*
X-156894Y-294036D01*
X-156228Y-293870D01*
X-155644Y-293953D01*
X-155228Y-294120D01*
X-154811Y-294453D01*
G01X-149211Y-292203D02*
Y-297203D01*
G01Y-296453D02*
X-149544Y-296870D01*
X-150044Y-297120D01*
X-150628Y-297203D01*
X-151294Y-297036D01*
X-151794Y-296620D01*
X-152128Y-296120D01*
X-152211Y-295536D01*
X-152128Y-294953D01*
X-151794Y-294453D01*
X-151294Y-294036D01*
X-150628Y-293870D01*
X-150044Y-293953D01*
X-149628Y-294120D01*
X-149211Y-294453D01*
G01X-140761Y-296620D02*
X-140344Y-296953D01*
X-139761Y-297203D01*
X-139261D01*
X-138761Y-297036D01*
X-138428Y-296786D01*
X-138261Y-296453D01*
X-138344Y-295953D01*
X-138678Y-295703D01*
X-140178Y-295203D01*
X-140511Y-294620D01*
X-140344Y-294203D01*
X-140011Y-293953D01*
X-139511Y-293870D01*
X-139011Y-293953D01*
X-138511Y-294203D01*
G01X-135328Y-293870D02*
Y-296203D01*
X-134994Y-296786D01*
X-134494Y-297120D01*
X-133911Y-297203D01*
X-133328Y-297120D01*
X-132828Y-296786D01*
X-132494Y-296203D01*
G01Y-297203D02*
Y-293870D01*
G01X-129811Y-298870D02*
Y-293870D01*
G01Y-294620D02*
X-129394Y-294203D01*
X-128978Y-293953D01*
X-128311Y-293870D01*
X-127728Y-293953D01*
X-127144Y-294370D01*
X-126894Y-294953D01*
X-126811Y-295536D01*
X-126894Y-296120D01*
X-127144Y-296703D01*
X-127644Y-297036D01*
X-128311Y-297203D01*
X-128894Y-297120D01*
X-129478Y-296870D01*
X-129811Y-296536D01*
G01X-124211Y-298870D02*
Y-293870D01*
G01Y-294620D02*
X-123794Y-294203D01*
X-123378Y-293953D01*
X-122711Y-293870D01*
X-122128Y-293953D01*
X-121544Y-294370D01*
X-121294Y-294953D01*
X-121211Y-295536D01*
X-121294Y-296120D01*
X-121544Y-296703D01*
X-122044Y-297036D01*
X-122711Y-297203D01*
X-123294Y-297120D01*
X-123878Y-296870D01*
X-124211Y-296536D01*
G01X-117111Y-297203D02*
Y-292203D01*
G01X-111511Y-293870D02*
Y-297203D01*
G01Y-292536D02*
X-111678Y-292453D01*
Y-292286D01*
X-111511Y-292203D01*
X-111344Y-292286D01*
Y-292453D01*
X-111511Y-292536D01*
G01X-107161Y-294953D02*
X-104494D01*
X-104744Y-294370D01*
X-105161Y-294036D01*
X-105744Y-293870D01*
X-106328Y-293953D01*
X-106828Y-294203D01*
X-107161Y-294786D01*
X-107328Y-295286D01*
Y-295786D01*
X-107161Y-296286D01*
X-106744Y-296786D01*
X-106244Y-297120D01*
X-105661Y-297203D01*
X-105078Y-297036D01*
X-104494Y-296536D01*
G01X-101478Y-297203D02*
Y-293870D01*
G01Y-294536D02*
X-101061Y-294203D01*
X-100644Y-293953D01*
X-100061Y-293870D01*
X-99644Y-293953D01*
X-99144Y-294203D01*
G01X-94711Y-293870D02*
X-93878Y-292828D01*
Y-292203D01*
X-94503D01*
Y-292828D01*
X-93878D01*
G01X-90361Y-296620D02*
X-89944Y-296953D01*
X-89361Y-297203D01*
X-88861D01*
X-88361Y-297036D01*
X-88028Y-296786D01*
X-87861Y-296453D01*
X-87944Y-295953D01*
X-88278Y-295703D01*
X-89778Y-295203D01*
X-90111Y-294620D01*
X-89944Y-294203D01*
X-89611Y-293953D01*
X-89111Y-293870D01*
X-88611Y-293953D01*
X-88111Y-294203D01*
G01X-79578Y-292203D02*
Y-297203D01*
X-76244D01*
G01X-72311D02*
X-72811Y-297120D01*
X-73311Y-296786D01*
X-73644Y-296203D01*
X-73811Y-295536D01*
X-73644Y-294870D01*
X-73311Y-294286D01*
X-72811Y-293953D01*
X-72311Y-293870D01*
X-71811Y-293953D01*
X-71311Y-294286D01*
X-70978Y-294870D01*
X-70894Y-295536D01*
X-70978Y-296203D01*
X-71311Y-296786D01*
X-71811Y-297120D01*
X-72311Y-297203D01*
G01X-67878Y-298453D02*
X-67294Y-298786D01*
X-66628Y-298870D01*
X-66044Y-298786D01*
X-65544Y-298370D01*
X-65211Y-297786D01*
Y-293870D01*
G01Y-294536D02*
X-65544Y-294203D01*
X-66044Y-293953D01*
X-66628Y-293870D01*
X-67294Y-294036D01*
X-67711Y-294370D01*
X-68044Y-294953D01*
X-68211Y-295536D01*
X-68128Y-296036D01*
X-67794Y-296620D01*
X-67294Y-297036D01*
X-66628Y-297203D01*
X-66128Y-297120D01*
X-65544Y-296786D01*
X-65211Y-296453D01*
G01X-61111Y-297203D02*
X-61611Y-297120D01*
X-62111Y-296786D01*
X-62444Y-296203D01*
X-62611Y-295536D01*
X-62444Y-294870D01*
X-62111Y-294286D01*
X-61611Y-293953D01*
X-61111Y-293870D01*
X-60611Y-293953D01*
X-60111Y-294286D01*
X-59778Y-294870D01*
X-59694Y-295536D01*
X-59778Y-296203D01*
X-60111Y-296786D01*
X-60611Y-297120D01*
X-61111Y-297203D01*
G01X-48411D02*
Y-293870D01*
G01Y-294453D02*
X-48744Y-294120D01*
X-49244Y-293953D01*
X-49828Y-293870D01*
X-50411Y-294036D01*
X-50911Y-294370D01*
X-51244Y-294870D01*
X-51411Y-295536D01*
X-51244Y-296203D01*
X-50911Y-296703D01*
X-50411Y-297036D01*
X-49828Y-297203D01*
X-49244Y-297120D01*
X-48744Y-296870D01*
X-48411Y-296536D01*
G01X-45728Y-297203D02*
Y-293870D01*
G01Y-294703D02*
X-45394Y-294286D01*
X-44894Y-293953D01*
X-44228Y-293870D01*
X-43644Y-293953D01*
X-43144Y-294286D01*
X-42894Y-294870D01*
Y-297203D01*
G01X-37211Y-292203D02*
Y-297203D01*
G01Y-296453D02*
X-37544Y-296870D01*
X-38044Y-297120D01*
X-38628Y-297203D01*
X-39294Y-297036D01*
X-39794Y-296620D01*
X-40128Y-296120D01*
X-40211Y-295536D01*
X-40128Y-294953D01*
X-39794Y-294453D01*
X-39294Y-294036D01*
X-38628Y-293870D01*
X-38044Y-293953D01*
X-37628Y-294120D01*
X-37211Y-294453D01*
G01X-29344Y-292203D02*
Y-295786D01*
X-29011Y-296536D01*
X-28344Y-297036D01*
X-27511Y-297203D01*
X-26678Y-297036D01*
X-26011Y-296536D01*
X-25678Y-295786D01*
Y-292203D01*
G01X-23578D02*
Y-297203D01*
X-20244D01*
G01X-11211D02*
Y-292953D01*
X-11044Y-292536D01*
X-10711Y-292286D01*
X-10211Y-292203D01*
X-9711Y-292370D01*
X-9461Y-292786D01*
G01X-10461Y-294203D02*
X-12128D01*
G01X-5111Y-293870D02*
Y-297203D01*
G01Y-292536D02*
X-5278Y-292453D01*
Y-292286D01*
X-5111Y-292203D01*
X-4944Y-292286D01*
Y-292453D01*
X-5111Y-292536D01*
G01X489Y-297203D02*
Y-292203D01*
G01X4839Y-294953D02*
X7506D01*
X7256Y-294370D01*
X6839Y-294036D01*
X6256Y-293870D01*
X5672Y-293953D01*
X5172Y-294203D01*
X4839Y-294786D01*
X4672Y-295286D01*
Y-295786D01*
X4839Y-296286D01*
X5256Y-296786D01*
X5756Y-297120D01*
X6339Y-297203D01*
X6922Y-297036D01*
X7506Y-296536D01*
G01X15372Y-297203D02*
Y-292203D01*
X19206Y-297203D01*
Y-292203D01*
G01X21472Y-293870D02*
Y-296203D01*
X21806Y-296786D01*
X22306Y-297120D01*
X22889Y-297203D01*
X23472Y-297120D01*
X23972Y-296786D01*
X24306Y-296203D01*
G01Y-297203D02*
Y-293870D01*
G01X25989Y-297203D02*
Y-293870D01*
G01Y-294786D02*
X26239Y-294370D01*
X26656Y-294036D01*
X27239Y-293870D01*
X27822Y-294036D01*
X28239Y-294370D01*
X28489Y-294786D01*
Y-297203D01*
G01Y-294786D02*
X28739Y-294370D01*
X29156Y-294036D01*
X29739Y-293870D01*
X30322Y-294036D01*
X30739Y-294370D01*
X30989Y-294870D01*
Y-297203D01*
G01X32589D02*
Y-292203D01*
G01Y-294703D02*
X33006Y-294203D01*
X33506Y-293953D01*
X34006Y-293870D01*
X34756Y-294036D01*
X35256Y-294370D01*
X35589Y-294953D01*
Y-295620D01*
X35422Y-296286D01*
X35089Y-296786D01*
X34506Y-297120D01*
X34006Y-297203D01*
X33506Y-297120D01*
X33006Y-296870D01*
X32589Y-296453D01*
G01X38439Y-294953D02*
X41106D01*
X40856Y-294370D01*
X40439Y-294036D01*
X39856Y-293870D01*
X39272Y-293953D01*
X38772Y-294203D01*
X38439Y-294786D01*
X38272Y-295286D01*
Y-295786D01*
X38439Y-296286D01*
X38856Y-296786D01*
X39356Y-297120D01*
X39939Y-297203D01*
X40522Y-297036D01*
X41106Y-296536D01*
G01X44122Y-297203D02*
Y-293870D01*
G01Y-294536D02*
X44539Y-294203D01*
X44956Y-293953D01*
X45539Y-293870D01*
X45956Y-293953D01*
X46456Y-294203D01*
G01X56489Y-293870D02*
Y-297203D01*
G01Y-292536D02*
X56322Y-292453D01*
Y-292286D01*
X56489Y-292203D01*
X56656Y-292286D01*
Y-292453D01*
X56489Y-292536D01*
G01X60672Y-297203D02*
Y-293870D01*
G01Y-294703D02*
X61006Y-294286D01*
X61506Y-293953D01*
X62172Y-293870D01*
X62756Y-293953D01*
X63256Y-294286D01*
X63506Y-294870D01*
Y-297203D01*
G01X72039Y-296620D02*
X72456Y-296953D01*
X73039Y-297203D01*
X73539D01*
X74039Y-297036D01*
X74372Y-296786D01*
X74539Y-296453D01*
X74456Y-295953D01*
X74122Y-295703D01*
X72622Y-295203D01*
X72289Y-294620D01*
X72456Y-294203D01*
X72789Y-293953D01*
X73289Y-293870D01*
X73789Y-293953D01*
X74289Y-294203D01*
G01X78889Y-293870D02*
Y-297203D01*
G01Y-292536D02*
X78722Y-292453D01*
Y-292286D01*
X78889Y-292203D01*
X79056Y-292286D01*
Y-292453D01*
X78889Y-292536D01*
G01X84489Y-297203D02*
Y-292203D01*
G01X88672Y-297203D02*
Y-292203D01*
G01X91339Y-293870D02*
X88672Y-295786D01*
G01X89756Y-295036D02*
X91506Y-297203D01*
G01X94439Y-296620D02*
X94856Y-296953D01*
X95439Y-297203D01*
X95939D01*
X96439Y-297036D01*
X96772Y-296786D01*
X96939Y-296453D01*
X96856Y-295953D01*
X96522Y-295703D01*
X95022Y-295203D01*
X94689Y-294620D01*
X94856Y-294203D01*
X95189Y-293953D01*
X95689Y-293870D01*
X96189Y-293953D01*
X96689Y-294203D01*
G01X102622Y-294286D02*
X102039Y-293953D01*
X101539Y-293870D01*
X100872Y-294036D01*
X100372Y-294370D01*
X100039Y-294953D01*
X99956Y-295536D01*
X100039Y-296120D01*
X100372Y-296620D01*
X100872Y-297036D01*
X101539Y-297203D01*
X102122Y-297036D01*
X102622Y-296703D01*
G01X105722Y-297203D02*
Y-293870D01*
G01Y-294536D02*
X106139Y-294203D01*
X106556Y-293953D01*
X107139Y-293870D01*
X107556Y-293953D01*
X108056Y-294203D01*
G01X111239Y-294953D02*
X113906D01*
X113656Y-294370D01*
X113239Y-294036D01*
X112656Y-293870D01*
X112072Y-293953D01*
X111572Y-294203D01*
X111239Y-294786D01*
X111072Y-295286D01*
Y-295786D01*
X111239Y-296286D01*
X111656Y-296786D01*
X112156Y-297120D01*
X112739Y-297203D01*
X113322Y-297036D01*
X113906Y-296536D01*
G01X116839Y-294953D02*
X119506D01*
X119256Y-294370D01*
X118839Y-294036D01*
X118256Y-293870D01*
X117672Y-293953D01*
X117172Y-294203D01*
X116839Y-294786D01*
X116672Y-295286D01*
Y-295786D01*
X116839Y-296286D01*
X117256Y-296786D01*
X117756Y-297120D01*
X118339Y-297203D01*
X118922Y-297036D01*
X119506Y-296536D01*
G01X122272Y-297203D02*
Y-293870D01*
G01Y-294703D02*
X122606Y-294286D01*
X123106Y-293953D01*
X123772Y-293870D01*
X124356Y-293953D01*
X124856Y-294286D01*
X125106Y-294870D01*
Y-297203D01*
G01X-163661Y-281536D02*
X-162994Y-281953D01*
X-162244Y-282203D01*
X-161578D01*
X-160911Y-281953D01*
X-160411Y-281536D01*
X-160161Y-280953D01*
X-160328Y-280370D01*
X-160744Y-279870D01*
X-161494Y-279536D01*
X-162494Y-279370D01*
X-163078Y-279036D01*
X-163328Y-278453D01*
X-163161Y-277870D01*
X-162744Y-277453D01*
X-162161Y-277203D01*
X-161578D01*
X-160994Y-277370D01*
X-160494Y-277786D01*
G01X-156311Y-282203D02*
X-156811Y-282120D01*
X-157311Y-281786D01*
X-157644Y-281203D01*
X-157811Y-280536D01*
X-157644Y-279870D01*
X-157311Y-279286D01*
X-156811Y-278953D01*
X-156311Y-278870D01*
X-155811Y-278953D01*
X-155311Y-279286D01*
X-154978Y-279870D01*
X-154894Y-280536D01*
X-154978Y-281203D01*
X-155311Y-281786D01*
X-155811Y-282120D01*
X-156311Y-282203D01*
G01X-150711D02*
Y-277203D01*
G01X-143611D02*
Y-282203D01*
G01Y-281453D02*
X-143944Y-281870D01*
X-144444Y-282120D01*
X-145028Y-282203D01*
X-145694Y-282036D01*
X-146194Y-281620D01*
X-146528Y-281120D01*
X-146611Y-280536D01*
X-146528Y-279953D01*
X-146194Y-279453D01*
X-145694Y-279036D01*
X-145028Y-278870D01*
X-144444Y-278953D01*
X-144028Y-279120D01*
X-143611Y-279453D01*
G01X-140761Y-279953D02*
X-138094D01*
X-138344Y-279370D01*
X-138761Y-279036D01*
X-139344Y-278870D01*
X-139928Y-278953D01*
X-140428Y-279203D01*
X-140761Y-279786D01*
X-140928Y-280286D01*
Y-280786D01*
X-140761Y-281286D01*
X-140344Y-281786D01*
X-139844Y-282120D01*
X-139261Y-282203D01*
X-138678Y-282036D01*
X-138094Y-281536D01*
G01X-135078Y-282203D02*
Y-278870D01*
G01Y-279536D02*
X-134661Y-279203D01*
X-134244Y-278953D01*
X-133661Y-278870D01*
X-133244Y-278953D01*
X-132744Y-279203D01*
G01X-125211Y-282203D02*
Y-278870D01*
G01Y-279786D02*
X-124961Y-279370D01*
X-124544Y-279036D01*
X-123961Y-278870D01*
X-123378Y-279036D01*
X-122961Y-279370D01*
X-122711Y-279786D01*
Y-282203D01*
G01Y-279786D02*
X-122461Y-279370D01*
X-122044Y-279036D01*
X-121461Y-278870D01*
X-120878Y-279036D01*
X-120461Y-279370D01*
X-120211Y-279870D01*
Y-282203D01*
G01X-115611D02*
Y-278870D01*
G01Y-279453D02*
X-115944Y-279120D01*
X-116444Y-278953D01*
X-117028Y-278870D01*
X-117611Y-279036D01*
X-118111Y-279370D01*
X-118444Y-279870D01*
X-118611Y-280536D01*
X-118444Y-281203D01*
X-118111Y-281703D01*
X-117611Y-282036D01*
X-117028Y-282203D01*
X-116444Y-282120D01*
X-115944Y-281870D01*
X-115611Y-281536D01*
G01X-112761Y-281620D02*
X-112344Y-281953D01*
X-111761Y-282203D01*
X-111261D01*
X-110761Y-282036D01*
X-110428Y-281786D01*
X-110261Y-281453D01*
X-110344Y-280953D01*
X-110678Y-280703D01*
X-112178Y-280203D01*
X-112511Y-279620D01*
X-112344Y-279203D01*
X-112011Y-278953D01*
X-111511Y-278870D01*
X-111011Y-278953D01*
X-110511Y-279203D01*
G01X-107328Y-282203D02*
Y-277203D01*
G01X-104661Y-278870D02*
X-107328Y-280786D01*
G01X-106244Y-280036D02*
X-104494Y-282203D01*
G01X-94711Y-277203D02*
Y-282203D01*
G01X-95878Y-278870D02*
X-93544D01*
G01X-90528Y-282203D02*
Y-277203D01*
G01Y-279620D02*
X-90111Y-279203D01*
X-89694Y-278953D01*
X-89028Y-278870D01*
X-88528Y-278953D01*
X-87944Y-279286D01*
X-87694Y-279786D01*
Y-282203D01*
G01X-83511Y-278870D02*
Y-282203D01*
G01Y-277536D02*
X-83678Y-277453D01*
Y-277286D01*
X-83511Y-277203D01*
X-83344Y-277286D01*
Y-277453D01*
X-83511Y-277536D01*
G01X-76578Y-279286D02*
X-77161Y-278953D01*
X-77661Y-278870D01*
X-78328Y-279036D01*
X-78828Y-279370D01*
X-79161Y-279953D01*
X-79244Y-280536D01*
X-79161Y-281120D01*
X-78828Y-281620D01*
X-78328Y-282036D01*
X-77661Y-282203D01*
X-77078Y-282036D01*
X-76578Y-281703D01*
G01X-73728Y-282203D02*
Y-277203D01*
G01X-71061Y-278870D02*
X-73728Y-280786D01*
G01X-72644Y-280036D02*
X-70894Y-282203D01*
G01X-68128D02*
Y-278870D01*
G01Y-279703D02*
X-67794Y-279286D01*
X-67294Y-278953D01*
X-66628Y-278870D01*
X-66044Y-278953D01*
X-65544Y-279286D01*
X-65294Y-279870D01*
Y-282203D01*
G01X-62361Y-279953D02*
X-59694D01*
X-59944Y-279370D01*
X-60361Y-279036D01*
X-60944Y-278870D01*
X-61528Y-278953D01*
X-62028Y-279203D01*
X-62361Y-279786D01*
X-62528Y-280286D01*
Y-280786D01*
X-62361Y-281286D01*
X-61944Y-281786D01*
X-61444Y-282120D01*
X-60861Y-282203D01*
X-60278Y-282036D01*
X-59694Y-281536D01*
G01X-56761Y-281620D02*
X-56344Y-281953D01*
X-55761Y-282203D01*
X-55261D01*
X-54761Y-282036D01*
X-54428Y-281786D01*
X-54261Y-281453D01*
X-54344Y-280953D01*
X-54678Y-280703D01*
X-56178Y-280203D01*
X-56511Y-279620D01*
X-56344Y-279203D01*
X-56011Y-278953D01*
X-55511Y-278870D01*
X-55011Y-278953D01*
X-54511Y-279203D01*
G01X-51161Y-281620D02*
X-50744Y-281953D01*
X-50161Y-282203D01*
X-49661D01*
X-49161Y-282036D01*
X-48828Y-281786D01*
X-48661Y-281453D01*
X-48744Y-280953D01*
X-49078Y-280703D01*
X-50578Y-280203D01*
X-50911Y-279620D01*
X-50744Y-279203D01*
X-50411Y-278953D01*
X-49911Y-278870D01*
X-49411Y-278953D01*
X-48911Y-279203D01*
G01X-40211Y-283870D02*
Y-278870D01*
G01Y-279620D02*
X-39794Y-279203D01*
X-39378Y-278953D01*
X-38711Y-278870D01*
X-38128Y-278953D01*
X-37544Y-279370D01*
X-37294Y-279953D01*
X-37211Y-280536D01*
X-37294Y-281120D01*
X-37544Y-281703D01*
X-38044Y-282036D01*
X-38711Y-282203D01*
X-39294Y-282120D01*
X-39878Y-281870D01*
X-40211Y-281536D01*
G01X-33111Y-282203D02*
Y-277203D01*
G01X-28928Y-278870D02*
Y-281203D01*
X-28594Y-281786D01*
X-28094Y-282120D01*
X-27511Y-282203D01*
X-26928Y-282120D01*
X-26428Y-281786D01*
X-26094Y-281203D01*
G01Y-282203D02*
Y-278870D01*
G01X-23161Y-281620D02*
X-22744Y-281953D01*
X-22161Y-282203D01*
X-21661D01*
X-21161Y-282036D01*
X-20828Y-281786D01*
X-20661Y-281453D01*
X-20744Y-280953D01*
X-21078Y-280703D01*
X-22578Y-280203D01*
X-22911Y-279620D01*
X-22744Y-279203D01*
X-22411Y-278953D01*
X-21911Y-278870D01*
X-21411Y-278953D01*
X-20911Y-279203D01*
G01X-10711Y-282203D02*
Y-277203D01*
G01X-6361Y-279953D02*
X-3694D01*
X-3944Y-279370D01*
X-4361Y-279036D01*
X-4944Y-278870D01*
X-5528Y-278953D01*
X-6028Y-279203D01*
X-6361Y-279786D01*
X-6528Y-280286D01*
Y-280786D01*
X-6361Y-281286D01*
X-5944Y-281786D01*
X-5444Y-282120D01*
X-4861Y-282203D01*
X-4278Y-282036D01*
X-3694Y-281536D01*
G01X-678Y-283453D02*
X-94Y-283786D01*
X572Y-283870D01*
X1156Y-283786D01*
X1656Y-283370D01*
X1989Y-282786D01*
Y-278870D01*
G01Y-279536D02*
X1656Y-279203D01*
X1156Y-278953D01*
X572Y-278870D01*
X-94Y-279036D01*
X-511Y-279370D01*
X-844Y-279953D01*
X-1011Y-280536D01*
X-928Y-281036D01*
X-594Y-281620D01*
X-94Y-282036D01*
X572Y-282203D01*
X1072Y-282120D01*
X1656Y-281786D01*
X1989Y-281453D01*
G01X4839Y-279953D02*
X7506D01*
X7256Y-279370D01*
X6839Y-279036D01*
X6256Y-278870D01*
X5672Y-278953D01*
X5172Y-279203D01*
X4839Y-279786D01*
X4672Y-280286D01*
Y-280786D01*
X4839Y-281286D01*
X5256Y-281786D01*
X5756Y-282120D01*
X6339Y-282203D01*
X6922Y-282036D01*
X7506Y-281536D01*
G01X10272Y-282203D02*
Y-278870D01*
G01Y-279703D02*
X10606Y-279286D01*
X11106Y-278953D01*
X11772Y-278870D01*
X12356Y-278953D01*
X12856Y-279286D01*
X13106Y-279870D01*
Y-282203D01*
G01X18789Y-277203D02*
Y-282203D01*
G01Y-281453D02*
X18456Y-281870D01*
X17956Y-282120D01*
X17372Y-282203D01*
X16706Y-282036D01*
X16206Y-281620D01*
X15872Y-281120D01*
X15789Y-280536D01*
X15872Y-279953D01*
X16206Y-279453D01*
X16706Y-279036D01*
X17372Y-278870D01*
X17956Y-278953D01*
X18372Y-279120D01*
X18789Y-279453D01*
G01X28489Y-277203D02*
Y-282203D01*
G01X27322Y-278870D02*
X29656D01*
G01X32672Y-282203D02*
Y-277203D01*
G01Y-279620D02*
X33089Y-279203D01*
X33506Y-278953D01*
X34172Y-278870D01*
X34672Y-278953D01*
X35256Y-279286D01*
X35506Y-279786D01*
Y-282203D01*
G01X39689Y-278870D02*
Y-282203D01*
G01Y-277536D02*
X39522Y-277453D01*
Y-277286D01*
X39689Y-277203D01*
X39856Y-277286D01*
Y-277453D01*
X39689Y-277536D01*
G01X46622Y-279286D02*
X46039Y-278953D01*
X45539Y-278870D01*
X44872Y-279036D01*
X44372Y-279370D01*
X44039Y-279953D01*
X43956Y-280536D01*
X44039Y-281120D01*
X44372Y-281620D01*
X44872Y-282036D01*
X45539Y-282203D01*
X46122Y-282036D01*
X46622Y-281703D01*
G01X49472Y-282203D02*
Y-277203D01*
G01X52139Y-278870D02*
X49472Y-280786D01*
G01X50556Y-280036D02*
X52306Y-282203D01*
G01X55072D02*
Y-278870D01*
G01Y-279703D02*
X55406Y-279286D01*
X55906Y-278953D01*
X56572Y-278870D01*
X57156Y-278953D01*
X57656Y-279286D01*
X57906Y-279870D01*
Y-282203D01*
G01X60839Y-279953D02*
X63506D01*
X63256Y-279370D01*
X62839Y-279036D01*
X62256Y-278870D01*
X61672Y-278953D01*
X61172Y-279203D01*
X60839Y-279786D01*
X60672Y-280286D01*
Y-280786D01*
X60839Y-281286D01*
X61256Y-281786D01*
X61756Y-282120D01*
X62339Y-282203D01*
X62922Y-282036D01*
X63506Y-281536D01*
G01X66439Y-281620D02*
X66856Y-281953D01*
X67439Y-282203D01*
X67939D01*
X68439Y-282036D01*
X68772Y-281786D01*
X68939Y-281453D01*
X68856Y-280953D01*
X68522Y-280703D01*
X67022Y-280203D01*
X66689Y-279620D01*
X66856Y-279203D01*
X67189Y-278953D01*
X67689Y-278870D01*
X68189Y-278953D01*
X68689Y-279203D01*
G01X72039Y-281620D02*
X72456Y-281953D01*
X73039Y-282203D01*
X73539D01*
X74039Y-282036D01*
X74372Y-281786D01*
X74539Y-281453D01*
X74456Y-280953D01*
X74122Y-280703D01*
X72622Y-280203D01*
X72289Y-279620D01*
X72456Y-279203D01*
X72789Y-278953D01*
X73289Y-278870D01*
X73789Y-278953D01*
X74289Y-279203D01*
G01X84489Y-282203D02*
X83989Y-282120D01*
X83489Y-281786D01*
X83156Y-281203D01*
X82989Y-280536D01*
X83156Y-279870D01*
X83489Y-279286D01*
X83989Y-278953D01*
X84489Y-278870D01*
X84989Y-278953D01*
X85489Y-279286D01*
X85822Y-279870D01*
X85906Y-280536D01*
X85822Y-281203D01*
X85489Y-281786D01*
X84989Y-282120D01*
X84489Y-282203D01*
G01X88672D02*
Y-278870D01*
G01Y-279703D02*
X89006Y-279286D01*
X89506Y-278953D01*
X90172Y-278870D01*
X90756Y-278953D01*
X91256Y-279286D01*
X91506Y-279870D01*
Y-282203D01*
G01X101289Y-277203D02*
Y-282203D01*
G01X100122Y-278870D02*
X102456D01*
G01X105722Y-282203D02*
Y-278870D01*
G01Y-279536D02*
X106139Y-279203D01*
X106556Y-278953D01*
X107139Y-278870D01*
X107556Y-278953D01*
X108056Y-279203D01*
G01X113989Y-282203D02*
Y-278870D01*
G01Y-279453D02*
X113656Y-279120D01*
X113156Y-278953D01*
X112572Y-278870D01*
X111989Y-279036D01*
X111489Y-279370D01*
X111156Y-279870D01*
X110989Y-280536D01*
X111156Y-281203D01*
X111489Y-281703D01*
X111989Y-282036D01*
X112572Y-282203D01*
X113156Y-282120D01*
X113656Y-281870D01*
X113989Y-281536D01*
G01X119422Y-279286D02*
X118839Y-278953D01*
X118339Y-278870D01*
X117672Y-279036D01*
X117172Y-279370D01*
X116839Y-279953D01*
X116756Y-280536D01*
X116839Y-281120D01*
X117172Y-281620D01*
X117672Y-282036D01*
X118339Y-282203D01*
X118922Y-282036D01*
X119422Y-281703D01*
G01X122439Y-279953D02*
X125106D01*
X124856Y-279370D01*
X124439Y-279036D01*
X123856Y-278870D01*
X123272Y-278953D01*
X122772Y-279203D01*
X122439Y-279786D01*
X122272Y-280286D01*
Y-280786D01*
X122439Y-281286D01*
X122856Y-281786D01*
X123356Y-282120D01*
X123939Y-282203D01*
X124522Y-282036D01*
X125106Y-281536D01*
G01X129289Y-282370D02*
X129122Y-282286D01*
Y-282120D01*
X129289Y-282036D01*
X129456Y-282120D01*
Y-282286D01*
X129289Y-282370D01*
G01X-171911Y-303203D02*
Y205297D01*
G01X-161911Y-267203D02*
Y-262203D01*
G01X-157561Y-264953D02*
X-154894D01*
X-155144Y-264370D01*
X-155561Y-264036D01*
X-156144Y-263870D01*
X-156728Y-263953D01*
X-157228Y-264203D01*
X-157561Y-264786D01*
X-157728Y-265286D01*
Y-265786D01*
X-157561Y-266286D01*
X-157144Y-266786D01*
X-156644Y-267120D01*
X-156061Y-267203D01*
X-155478Y-267036D01*
X-154894Y-266536D01*
G01X-151878Y-268453D02*
X-151294Y-268786D01*
X-150628Y-268870D01*
X-150044Y-268786D01*
X-149544Y-268370D01*
X-149211Y-267786D01*
Y-263870D01*
G01Y-264536D02*
X-149544Y-264203D01*
X-150044Y-263953D01*
X-150628Y-263870D01*
X-151294Y-264036D01*
X-151711Y-264370D01*
X-152044Y-264953D01*
X-152211Y-265536D01*
X-152128Y-266036D01*
X-151794Y-266620D01*
X-151294Y-267036D01*
X-150628Y-267203D01*
X-150128Y-267120D01*
X-149544Y-266786D01*
X-149211Y-266453D01*
G01X-146361Y-264953D02*
X-143694D01*
X-143944Y-264370D01*
X-144361Y-264036D01*
X-144944Y-263870D01*
X-145528Y-263953D01*
X-146028Y-264203D01*
X-146361Y-264786D01*
X-146528Y-265286D01*
Y-265786D01*
X-146361Y-266286D01*
X-145944Y-266786D01*
X-145444Y-267120D01*
X-144861Y-267203D01*
X-144278Y-267036D01*
X-143694Y-266536D01*
G01X-140928Y-267203D02*
Y-263870D01*
G01Y-264703D02*
X-140594Y-264286D01*
X-140094Y-263953D01*
X-139428Y-263870D01*
X-138844Y-263953D01*
X-138344Y-264286D01*
X-138094Y-264870D01*
Y-267203D01*
G01X-132411Y-262203D02*
Y-267203D01*
G01Y-266453D02*
X-132744Y-266870D01*
X-133244Y-267120D01*
X-133828Y-267203D01*
X-134494Y-267036D01*
X-134994Y-266620D01*
X-135328Y-266120D01*
X-135411Y-265536D01*
X-135328Y-264953D01*
X-134994Y-264453D01*
X-134494Y-264036D01*
X-133828Y-263870D01*
X-133244Y-263953D01*
X-132828Y-264120D01*
X-132411Y-264453D01*
G01X-122711Y-262203D02*
Y-267203D01*
G01X-123878Y-263870D02*
X-121544D01*
G01X-118528Y-267203D02*
Y-262203D01*
G01Y-264620D02*
X-118111Y-264203D01*
X-117694Y-263953D01*
X-117028Y-263870D01*
X-116528Y-263953D01*
X-115944Y-264286D01*
X-115694Y-264786D01*
Y-267203D01*
G01X-111511Y-263870D02*
Y-267203D01*
G01Y-262536D02*
X-111678Y-262453D01*
Y-262286D01*
X-111511Y-262203D01*
X-111344Y-262286D01*
Y-262453D01*
X-111511Y-262536D01*
G01X-104578Y-264286D02*
X-105161Y-263953D01*
X-105661Y-263870D01*
X-106328Y-264036D01*
X-106828Y-264370D01*
X-107161Y-264953D01*
X-107244Y-265536D01*
X-107161Y-266120D01*
X-106828Y-266620D01*
X-106328Y-267036D01*
X-105661Y-267203D01*
X-105078Y-267036D01*
X-104578Y-266703D01*
G01X-101728Y-267203D02*
Y-262203D01*
G01X-99061Y-263870D02*
X-101728Y-265786D01*
G01X-100644Y-265036D02*
X-98894Y-267203D01*
G01X-96128D02*
Y-263870D01*
G01Y-264703D02*
X-95794Y-264286D01*
X-95294Y-263953D01*
X-94628Y-263870D01*
X-94044Y-263953D01*
X-93544Y-264286D01*
X-93294Y-264870D01*
Y-267203D01*
G01X-90361Y-264953D02*
X-87694D01*
X-87944Y-264370D01*
X-88361Y-264036D01*
X-88944Y-263870D01*
X-89528Y-263953D01*
X-90028Y-264203D01*
X-90361Y-264786D01*
X-90528Y-265286D01*
Y-265786D01*
X-90361Y-266286D01*
X-89944Y-266786D01*
X-89444Y-267120D01*
X-88861Y-267203D01*
X-88278Y-267036D01*
X-87694Y-266536D01*
G01X-84761Y-266620D02*
X-84344Y-266953D01*
X-83761Y-267203D01*
X-83261D01*
X-82761Y-267036D01*
X-82428Y-266786D01*
X-82261Y-266453D01*
X-82344Y-265953D01*
X-82678Y-265703D01*
X-84178Y-265203D01*
X-84511Y-264620D01*
X-84344Y-264203D01*
X-84011Y-263953D01*
X-83511Y-263870D01*
X-83011Y-263953D01*
X-82511Y-264203D01*
G01X-79161Y-266620D02*
X-78744Y-266953D01*
X-78161Y-267203D01*
X-77661D01*
X-77161Y-267036D01*
X-76828Y-266786D01*
X-76661Y-266453D01*
X-76744Y-265953D01*
X-77078Y-265703D01*
X-78578Y-265203D01*
X-78911Y-264620D01*
X-78744Y-264203D01*
X-78411Y-263953D01*
X-77911Y-263870D01*
X-77411Y-263953D01*
X-76911Y-264203D01*
G01X-66711Y-267203D02*
X-67211Y-267120D01*
X-67711Y-266786D01*
X-68044Y-266203D01*
X-68211Y-265536D01*
X-68044Y-264870D01*
X-67711Y-264286D01*
X-67211Y-263953D01*
X-66711Y-263870D01*
X-66211Y-263953D01*
X-65711Y-264286D01*
X-65378Y-264870D01*
X-65294Y-265536D01*
X-65378Y-266203D01*
X-65711Y-266786D01*
X-66211Y-267120D01*
X-66711Y-267203D01*
G01X-62528D02*
Y-263870D01*
G01Y-264703D02*
X-62194Y-264286D01*
X-61694Y-263953D01*
X-61028Y-263870D01*
X-60444Y-263953D01*
X-59944Y-264286D01*
X-59694Y-264870D01*
Y-267203D01*
G01X-48578Y-264286D02*
X-49161Y-263953D01*
X-49661Y-263870D01*
X-50328Y-264036D01*
X-50828Y-264370D01*
X-51161Y-264953D01*
X-51244Y-265536D01*
X-51161Y-266120D01*
X-50828Y-266620D01*
X-50328Y-267036D01*
X-49661Y-267203D01*
X-49078Y-267036D01*
X-48578Y-266703D01*
G01X-44311Y-267203D02*
X-44811Y-267120D01*
X-45311Y-266786D01*
X-45644Y-266203D01*
X-45811Y-265536D01*
X-45644Y-264870D01*
X-45311Y-264286D01*
X-44811Y-263953D01*
X-44311Y-263870D01*
X-43811Y-263953D01*
X-43311Y-264286D01*
X-42978Y-264870D01*
X-42894Y-265536D01*
X-42978Y-266203D01*
X-43311Y-266786D01*
X-43811Y-267120D01*
X-44311Y-267203D01*
G01X-40211Y-268870D02*
Y-263870D01*
G01Y-264620D02*
X-39794Y-264203D01*
X-39378Y-263953D01*
X-38711Y-263870D01*
X-38128Y-263953D01*
X-37544Y-264370D01*
X-37294Y-264953D01*
X-37211Y-265536D01*
X-37294Y-266120D01*
X-37544Y-266703D01*
X-38044Y-267036D01*
X-38711Y-267203D01*
X-39294Y-267120D01*
X-39878Y-266870D01*
X-40211Y-266536D01*
G01X-34611Y-268870D02*
Y-263870D01*
G01Y-264620D02*
X-34194Y-264203D01*
X-33778Y-263953D01*
X-33111Y-263870D01*
X-32528Y-263953D01*
X-31944Y-264370D01*
X-31694Y-264953D01*
X-31611Y-265536D01*
X-31694Y-266120D01*
X-31944Y-266703D01*
X-32444Y-267036D01*
X-33111Y-267203D01*
X-33694Y-267120D01*
X-34278Y-266870D01*
X-34611Y-266536D01*
G01X-28761Y-264953D02*
X-26094D01*
X-26344Y-264370D01*
X-26761Y-264036D01*
X-27344Y-263870D01*
X-27928Y-263953D01*
X-28428Y-264203D01*
X-28761Y-264786D01*
X-28928Y-265286D01*
Y-265786D01*
X-28761Y-266286D01*
X-28344Y-266786D01*
X-27844Y-267120D01*
X-27261Y-267203D01*
X-26678Y-267036D01*
X-26094Y-266536D01*
G01X-23078Y-267203D02*
Y-263870D01*
G01Y-264536D02*
X-22661Y-264203D01*
X-22244Y-263953D01*
X-21661Y-263870D01*
X-21244Y-263953D01*
X-20744Y-264203D01*
G01X-11128Y-268870D02*
X-11961Y-268036D01*
X-12378Y-267203D01*
Y-263870D01*
X-11961Y-263036D01*
X-11128Y-262203D01*
G01X-7194Y-263870D02*
X-6194Y-267203D01*
X-5111Y-263870D01*
X-4028Y-267203D01*
X-3028Y-263870D01*
G01X-928Y-267203D02*
Y-262203D01*
G01Y-264620D02*
X-511Y-264203D01*
X-94Y-263953D01*
X572Y-263870D01*
X1072Y-263953D01*
X1656Y-264286D01*
X1906Y-264786D01*
Y-267203D01*
G01X6089Y-263870D02*
Y-267203D01*
G01Y-262536D02*
X5922Y-262453D01*
Y-262286D01*
X6089Y-262203D01*
X6256Y-262286D01*
Y-262453D01*
X6089Y-262536D01*
G01X13022Y-264286D02*
X12439Y-263953D01*
X11939Y-263870D01*
X11272Y-264036D01*
X10772Y-264370D01*
X10439Y-264953D01*
X10356Y-265536D01*
X10439Y-266120D01*
X10772Y-266620D01*
X11272Y-267036D01*
X11939Y-267203D01*
X12522Y-267036D01*
X13022Y-266703D01*
G01X15872Y-267203D02*
Y-262203D01*
G01Y-264620D02*
X16289Y-264203D01*
X16706Y-263953D01*
X17372Y-263870D01*
X17872Y-263953D01*
X18456Y-264286D01*
X18706Y-264786D01*
Y-267203D01*
G01X28489Y-263870D02*
Y-267203D01*
G01Y-262536D02*
X28322Y-262453D01*
Y-262286D01*
X28489Y-262203D01*
X28656Y-262286D01*
Y-262453D01*
X28489Y-262536D01*
G01X32839Y-266620D02*
X33256Y-266953D01*
X33839Y-267203D01*
X34339D01*
X34839Y-267036D01*
X35172Y-266786D01*
X35339Y-266453D01*
X35256Y-265953D01*
X34922Y-265703D01*
X33422Y-265203D01*
X33089Y-264620D01*
X33256Y-264203D01*
X33589Y-263953D01*
X34089Y-263870D01*
X34589Y-263953D01*
X35089Y-264203D01*
G01X43789Y-267203D02*
Y-262203D01*
G01Y-264703D02*
X44206Y-264203D01*
X44706Y-263953D01*
X45206Y-263870D01*
X45956Y-264036D01*
X46456Y-264370D01*
X46789Y-264953D01*
Y-265620D01*
X46622Y-266286D01*
X46289Y-266786D01*
X45706Y-267120D01*
X45206Y-267203D01*
X44706Y-267120D01*
X44206Y-266870D01*
X43789Y-266453D01*
G01X49639Y-264953D02*
X52306D01*
X52056Y-264370D01*
X51639Y-264036D01*
X51056Y-263870D01*
X50472Y-263953D01*
X49972Y-264203D01*
X49639Y-264786D01*
X49472Y-265286D01*
Y-265786D01*
X49639Y-266286D01*
X50056Y-266786D01*
X50556Y-267120D01*
X51139Y-267203D01*
X51722Y-267036D01*
X52306Y-266536D01*
G01X56489Y-262203D02*
Y-267203D01*
G01X55322Y-263870D02*
X57656D01*
G01X62089Y-262203D02*
Y-267203D01*
G01X60922Y-263870D02*
X63256D01*
G01X66439Y-264953D02*
X69106D01*
X68856Y-264370D01*
X68439Y-264036D01*
X67856Y-263870D01*
X67272Y-263953D01*
X66772Y-264203D01*
X66439Y-264786D01*
X66272Y-265286D01*
Y-265786D01*
X66439Y-266286D01*
X66856Y-266786D01*
X67356Y-267120D01*
X67939Y-267203D01*
X68522Y-267036D01*
X69106Y-266536D01*
G01X72122Y-267203D02*
Y-263870D01*
G01Y-264536D02*
X72539Y-264203D01*
X72956Y-263953D01*
X73539Y-263870D01*
X73956Y-263953D01*
X74456Y-264203D01*
G01X79306Y-268870D02*
X80139Y-268036D01*
X80556Y-267203D01*
Y-263870D01*
X80139Y-263036D01*
X79306Y-262203D01*
G01X-170411Y-273203D02*
X260089D01*
G01X-161911Y-233703D02*
Y-238703D01*
G01X-163828Y-233703D02*
X-159994D01*
G01X-157728Y-238703D02*
Y-233703D01*
G01Y-236120D02*
X-157311Y-235703D01*
X-156894Y-235453D01*
X-156228Y-235370D01*
X-155728Y-235453D01*
X-155144Y-235786D01*
X-154894Y-236286D01*
Y-238703D01*
G01X-151961Y-236453D02*
X-149294D01*
X-149544Y-235870D01*
X-149961Y-235536D01*
X-150544Y-235370D01*
X-151128Y-235453D01*
X-151628Y-235703D01*
X-151961Y-236286D01*
X-152128Y-236786D01*
Y-237286D01*
X-151961Y-237786D01*
X-151544Y-238286D01*
X-151044Y-238620D01*
X-150461Y-238703D01*
X-149878Y-238536D01*
X-149294Y-238036D01*
G01X-139511Y-238703D02*
Y-233703D01*
G01X-132411Y-238703D02*
Y-235370D01*
G01Y-235953D02*
X-132744Y-235620D01*
X-133244Y-235453D01*
X-133828Y-235370D01*
X-134411Y-235536D01*
X-134911Y-235870D01*
X-135244Y-236370D01*
X-135411Y-237036D01*
X-135244Y-237703D01*
X-134911Y-238203D01*
X-134411Y-238536D01*
X-133828Y-238703D01*
X-133244Y-238620D01*
X-132744Y-238370D01*
X-132411Y-238036D01*
G01X-129478Y-238703D02*
Y-235370D01*
G01Y-236036D02*
X-129061Y-235703D01*
X-128644Y-235453D01*
X-128061Y-235370D01*
X-127644Y-235453D01*
X-127144Y-235703D01*
G01X-123878Y-239953D02*
X-123294Y-240286D01*
X-122628Y-240370D01*
X-122044Y-240286D01*
X-121544Y-239870D01*
X-121211Y-239286D01*
Y-235370D01*
G01Y-236036D02*
X-121544Y-235703D01*
X-122044Y-235453D01*
X-122628Y-235370D01*
X-123294Y-235536D01*
X-123711Y-235870D01*
X-124044Y-236453D01*
X-124211Y-237036D01*
X-124128Y-237536D01*
X-123794Y-238120D01*
X-123294Y-238536D01*
X-122628Y-238703D01*
X-122128Y-238620D01*
X-121544Y-238286D01*
X-121211Y-237953D01*
G01X-118361Y-236453D02*
X-115694D01*
X-115944Y-235870D01*
X-116361Y-235536D01*
X-116944Y-235370D01*
X-117528Y-235453D01*
X-118028Y-235703D01*
X-118361Y-236286D01*
X-118528Y-236786D01*
Y-237286D01*
X-118361Y-237786D01*
X-117944Y-238286D01*
X-117444Y-238620D01*
X-116861Y-238703D01*
X-116278Y-238536D01*
X-115694Y-238036D01*
G01X-112761Y-238120D02*
X-112344Y-238453D01*
X-111761Y-238703D01*
X-111261D01*
X-110761Y-238536D01*
X-110428Y-238286D01*
X-110261Y-237953D01*
X-110344Y-237453D01*
X-110678Y-237203D01*
X-112178Y-236703D01*
X-112511Y-236120D01*
X-112344Y-235703D01*
X-112011Y-235453D01*
X-111511Y-235370D01*
X-111011Y-235453D01*
X-110511Y-235703D01*
G01X-105911Y-233703D02*
Y-238703D01*
G01X-107078Y-235370D02*
X-104744D01*
G01X-93211Y-233703D02*
Y-238703D01*
G01Y-237953D02*
X-93544Y-238370D01*
X-94044Y-238620D01*
X-94628Y-238703D01*
X-95294Y-238536D01*
X-95794Y-238120D01*
X-96128Y-237620D01*
X-96211Y-237036D01*
X-96128Y-236453D01*
X-95794Y-235953D01*
X-95294Y-235536D01*
X-94628Y-235370D01*
X-94044Y-235453D01*
X-93628Y-235620D01*
X-93211Y-235953D01*
G01X-89111Y-235370D02*
Y-238703D01*
G01Y-234036D02*
X-89278Y-233953D01*
Y-233786D01*
X-89111Y-233703D01*
X-88944Y-233786D01*
Y-233953D01*
X-89111Y-234036D01*
G01X-86011Y-238703D02*
Y-235370D01*
G01Y-236286D02*
X-85761Y-235870D01*
X-85344Y-235536D01*
X-84761Y-235370D01*
X-84178Y-235536D01*
X-83761Y-235870D01*
X-83511Y-236286D01*
Y-238703D01*
G01Y-236286D02*
X-83261Y-235870D01*
X-82844Y-235536D01*
X-82261Y-235370D01*
X-81678Y-235536D01*
X-81261Y-235870D01*
X-81011Y-236370D01*
Y-238703D01*
G01X-79161Y-236453D02*
X-76494D01*
X-76744Y-235870D01*
X-77161Y-235536D01*
X-77744Y-235370D01*
X-78328Y-235453D01*
X-78828Y-235703D01*
X-79161Y-236286D01*
X-79328Y-236786D01*
Y-237286D01*
X-79161Y-237786D01*
X-78744Y-238286D01*
X-78244Y-238620D01*
X-77661Y-238703D01*
X-77078Y-238536D01*
X-76494Y-238036D01*
G01X-73728Y-238703D02*
Y-235370D01*
G01Y-236203D02*
X-73394Y-235786D01*
X-72894Y-235453D01*
X-72228Y-235370D01*
X-71644Y-235453D01*
X-71144Y-235786D01*
X-70894Y-236370D01*
Y-238703D01*
G01X-67961Y-238120D02*
X-67544Y-238453D01*
X-66961Y-238703D01*
X-66461D01*
X-65961Y-238536D01*
X-65628Y-238286D01*
X-65461Y-237953D01*
X-65544Y-237453D01*
X-65878Y-237203D01*
X-67378Y-236703D01*
X-67711Y-236120D01*
X-67544Y-235703D01*
X-67211Y-235453D01*
X-66711Y-235370D01*
X-66211Y-235453D01*
X-65711Y-235703D01*
G01X-61111Y-235370D02*
Y-238703D01*
G01Y-234036D02*
X-61278Y-233953D01*
Y-233786D01*
X-61111Y-233703D01*
X-60944Y-233786D01*
Y-233953D01*
X-61111Y-234036D01*
G01X-55511Y-238703D02*
X-56011Y-238620D01*
X-56511Y-238286D01*
X-56844Y-237703D01*
X-57011Y-237036D01*
X-56844Y-236370D01*
X-56511Y-235786D01*
X-56011Y-235453D01*
X-55511Y-235370D01*
X-55011Y-235453D01*
X-54511Y-235786D01*
X-54178Y-236370D01*
X-54094Y-237036D01*
X-54178Y-237703D01*
X-54511Y-238286D01*
X-55011Y-238620D01*
X-55511Y-238703D01*
G01X-51328D02*
Y-235370D01*
G01Y-236203D02*
X-50994Y-235786D01*
X-50494Y-235453D01*
X-49828Y-235370D01*
X-49244Y-235453D01*
X-48744Y-235786D01*
X-48494Y-236370D01*
Y-238703D01*
G01X-38711D02*
X-39211Y-238620D01*
X-39711Y-238286D01*
X-40044Y-237703D01*
X-40211Y-237036D01*
X-40044Y-236370D01*
X-39711Y-235786D01*
X-39211Y-235453D01*
X-38711Y-235370D01*
X-38211Y-235453D01*
X-37711Y-235786D01*
X-37378Y-236370D01*
X-37294Y-237036D01*
X-37378Y-237703D01*
X-37711Y-238286D01*
X-38211Y-238620D01*
X-38711Y-238703D01*
G01X-33611D02*
Y-234453D01*
X-33444Y-234036D01*
X-33111Y-233786D01*
X-32611Y-233703D01*
X-32111Y-233870D01*
X-31861Y-234286D01*
G01X-32861Y-235703D02*
X-34528D01*
G01X-23411Y-240370D02*
Y-235370D01*
G01Y-236120D02*
X-22994Y-235703D01*
X-22578Y-235453D01*
X-21911Y-235370D01*
X-21328Y-235453D01*
X-20744Y-235870D01*
X-20494Y-236453D01*
X-20411Y-237036D01*
X-20494Y-237620D01*
X-20744Y-238203D01*
X-21244Y-238536D01*
X-21911Y-238703D01*
X-22494Y-238620D01*
X-23078Y-238370D01*
X-23411Y-238036D01*
G01X-14811Y-238703D02*
Y-235370D01*
G01Y-235953D02*
X-15144Y-235620D01*
X-15644Y-235453D01*
X-16228Y-235370D01*
X-16811Y-235536D01*
X-17311Y-235870D01*
X-17644Y-236370D01*
X-17811Y-237036D01*
X-17644Y-237703D01*
X-17311Y-238203D01*
X-16811Y-238536D01*
X-16228Y-238703D01*
X-15644Y-238620D01*
X-15144Y-238370D01*
X-14811Y-238036D01*
G01X-9211Y-233703D02*
Y-238703D01*
G01Y-237953D02*
X-9544Y-238370D01*
X-10044Y-238620D01*
X-10628Y-238703D01*
X-11294Y-238536D01*
X-11794Y-238120D01*
X-12128Y-237620D01*
X-12211Y-237036D01*
X-12128Y-236453D01*
X-11794Y-235953D01*
X-11294Y-235536D01*
X-10628Y-235370D01*
X-10044Y-235453D01*
X-9628Y-235620D01*
X-9211Y-235953D01*
G01X489Y-238703D02*
X-11Y-238620D01*
X-511Y-238286D01*
X-844Y-237703D01*
X-1011Y-237036D01*
X-844Y-236370D01*
X-511Y-235786D01*
X-11Y-235453D01*
X489Y-235370D01*
X989Y-235453D01*
X1489Y-235786D01*
X1822Y-236370D01*
X1906Y-237036D01*
X1822Y-237703D01*
X1489Y-238286D01*
X989Y-238620D01*
X489Y-238703D01*
G01X4922D02*
Y-235370D01*
G01Y-236036D02*
X5339Y-235703D01*
X5756Y-235453D01*
X6339Y-235370D01*
X6756Y-235453D01*
X7256Y-235703D01*
G01X18789Y-233703D02*
Y-238703D01*
G01Y-237953D02*
X18456Y-238370D01*
X17956Y-238620D01*
X17372Y-238703D01*
X16706Y-238536D01*
X16206Y-238120D01*
X15872Y-237620D01*
X15789Y-237036D01*
X15872Y-236453D01*
X16206Y-235953D01*
X16706Y-235536D01*
X17372Y-235370D01*
X17956Y-235453D01*
X18372Y-235620D01*
X18789Y-235953D01*
G01X22889Y-235370D02*
Y-238703D01*
G01Y-234036D02*
X22722Y-233953D01*
Y-233786D01*
X22889Y-233703D01*
X23056Y-233786D01*
Y-233953D01*
X22889Y-234036D01*
G01X29989Y-238703D02*
Y-235370D01*
G01Y-235953D02*
X29656Y-235620D01*
X29156Y-235453D01*
X28572Y-235370D01*
X27989Y-235536D01*
X27489Y-235870D01*
X27156Y-236370D01*
X26989Y-237036D01*
X27156Y-237703D01*
X27489Y-238203D01*
X27989Y-238536D01*
X28572Y-238703D01*
X29156Y-238620D01*
X29656Y-238370D01*
X29989Y-238036D01*
G01X31589Y-238703D02*
Y-235370D01*
G01Y-236286D02*
X31839Y-235870D01*
X32256Y-235536D01*
X32839Y-235370D01*
X33422Y-235536D01*
X33839Y-235870D01*
X34089Y-236286D01*
Y-238703D01*
G01Y-236286D02*
X34339Y-235870D01*
X34756Y-235536D01*
X35339Y-235370D01*
X35922Y-235536D01*
X36339Y-235870D01*
X36589Y-236370D01*
Y-238703D01*
G01X38439Y-236453D02*
X41106D01*
X40856Y-235870D01*
X40439Y-235536D01*
X39856Y-235370D01*
X39272Y-235453D01*
X38772Y-235703D01*
X38439Y-236286D01*
X38272Y-236786D01*
Y-237286D01*
X38439Y-237786D01*
X38856Y-238286D01*
X39356Y-238620D01*
X39939Y-238703D01*
X40522Y-238536D01*
X41106Y-238036D01*
G01X45289Y-233703D02*
Y-238703D01*
G01X44122Y-235370D02*
X46456D01*
G01X49639Y-236453D02*
X52306D01*
X52056Y-235870D01*
X51639Y-235536D01*
X51056Y-235370D01*
X50472Y-235453D01*
X49972Y-235703D01*
X49639Y-236286D01*
X49472Y-236786D01*
Y-237286D01*
X49639Y-237786D01*
X50056Y-238286D01*
X50556Y-238620D01*
X51139Y-238703D01*
X51722Y-238536D01*
X52306Y-238036D01*
G01X55322Y-238703D02*
Y-235370D01*
G01Y-236036D02*
X55739Y-235703D01*
X56156Y-235453D01*
X56739Y-235370D01*
X57156Y-235453D01*
X57656Y-235703D01*
G01X69356Y-238703D02*
X66022Y-237036D01*
X69356Y-235370D01*
G01X72206Y-237786D02*
X74372D01*
G01Y-236286D02*
X72206D01*
G01X84489Y-238703D02*
Y-233703D01*
X83489Y-234703D01*
G01Y-238703D02*
X85489D01*
G01X91089D02*
Y-233703D01*
X88006Y-237286D01*
X92172D01*
G01X98789Y-238703D02*
Y-235370D01*
G01Y-236286D02*
X99039Y-235870D01*
X99456Y-235536D01*
X100039Y-235370D01*
X100622Y-235536D01*
X101039Y-235870D01*
X101289Y-236286D01*
Y-238703D01*
G01Y-236286D02*
X101539Y-235870D01*
X101956Y-235536D01*
X102539Y-235370D01*
X103122Y-235536D01*
X103539Y-235870D01*
X103789Y-236370D01*
Y-238703D01*
G01X106889Y-235370D02*
Y-238703D01*
G01Y-234036D02*
X106722Y-233953D01*
Y-233786D01*
X106889Y-233703D01*
X107056Y-233786D01*
Y-233953D01*
X106889Y-234036D01*
G01X112489Y-238703D02*
Y-233703D01*
G01X-163161Y-253120D02*
X-162744Y-253453D01*
X-162161Y-253703D01*
X-161661D01*
X-161161Y-253536D01*
X-160828Y-253286D01*
X-160661Y-252953D01*
X-160744Y-252453D01*
X-161078Y-252203D01*
X-162578Y-251703D01*
X-162911Y-251120D01*
X-162744Y-250703D01*
X-162411Y-250453D01*
X-161911Y-250370D01*
X-161411Y-250453D01*
X-160911Y-250703D01*
G01X-156311Y-253703D02*
X-156811Y-253620D01*
X-157311Y-253286D01*
X-157644Y-252703D01*
X-157811Y-252036D01*
X-157644Y-251370D01*
X-157311Y-250786D01*
X-156811Y-250453D01*
X-156311Y-250370D01*
X-155811Y-250453D01*
X-155311Y-250786D01*
X-154978Y-251370D01*
X-154894Y-252036D01*
X-154978Y-252703D01*
X-155311Y-253286D01*
X-155811Y-253620D01*
X-156311Y-253703D01*
G01X-150711D02*
Y-248703D01*
G01X-143611D02*
Y-253703D01*
G01Y-252953D02*
X-143944Y-253370D01*
X-144444Y-253620D01*
X-145028Y-253703D01*
X-145694Y-253536D01*
X-146194Y-253120D01*
X-146528Y-252620D01*
X-146611Y-252036D01*
X-146528Y-251453D01*
X-146194Y-250953D01*
X-145694Y-250536D01*
X-145028Y-250370D01*
X-144444Y-250453D01*
X-144028Y-250620D01*
X-143611Y-250953D01*
G01X-140761Y-251453D02*
X-138094D01*
X-138344Y-250870D01*
X-138761Y-250536D01*
X-139344Y-250370D01*
X-139928Y-250453D01*
X-140428Y-250703D01*
X-140761Y-251286D01*
X-140928Y-251786D01*
Y-252286D01*
X-140761Y-252786D01*
X-140344Y-253286D01*
X-139844Y-253620D01*
X-139261Y-253703D01*
X-138678Y-253536D01*
X-138094Y-253036D01*
G01X-135078Y-253703D02*
Y-250370D01*
G01Y-251036D02*
X-134661Y-250703D01*
X-134244Y-250453D01*
X-133661Y-250370D01*
X-133244Y-250453D01*
X-132744Y-250703D01*
G01X-125211Y-253703D02*
Y-250370D01*
G01Y-251286D02*
X-124961Y-250870D01*
X-124544Y-250536D01*
X-123961Y-250370D01*
X-123378Y-250536D01*
X-122961Y-250870D01*
X-122711Y-251286D01*
Y-253703D01*
G01Y-251286D02*
X-122461Y-250870D01*
X-122044Y-250536D01*
X-121461Y-250370D01*
X-120878Y-250536D01*
X-120461Y-250870D01*
X-120211Y-251370D01*
Y-253703D01*
G01X-115611D02*
Y-250370D01*
G01Y-250953D02*
X-115944Y-250620D01*
X-116444Y-250453D01*
X-117028Y-250370D01*
X-117611Y-250536D01*
X-118111Y-250870D01*
X-118444Y-251370D01*
X-118611Y-252036D01*
X-118444Y-252703D01*
X-118111Y-253203D01*
X-117611Y-253536D01*
X-117028Y-253703D01*
X-116444Y-253620D01*
X-115944Y-253370D01*
X-115611Y-253036D01*
G01X-112761Y-253120D02*
X-112344Y-253453D01*
X-111761Y-253703D01*
X-111261D01*
X-110761Y-253536D01*
X-110428Y-253286D01*
X-110261Y-252953D01*
X-110344Y-252453D01*
X-110678Y-252203D01*
X-112178Y-251703D01*
X-112511Y-251120D01*
X-112344Y-250703D01*
X-112011Y-250453D01*
X-111511Y-250370D01*
X-111011Y-250453D01*
X-110511Y-250703D01*
G01X-107328Y-253703D02*
Y-248703D01*
G01X-104661Y-250370D02*
X-107328Y-252286D01*
G01X-106244Y-251536D02*
X-104494Y-253703D01*
G01X-94711Y-248703D02*
Y-253703D01*
G01X-95878Y-250370D02*
X-93544D01*
G01X-90528Y-253703D02*
Y-248703D01*
G01Y-251120D02*
X-90111Y-250703D01*
X-89694Y-250453D01*
X-89028Y-250370D01*
X-88528Y-250453D01*
X-87944Y-250786D01*
X-87694Y-251286D01*
Y-253703D01*
G01X-83511Y-250370D02*
Y-253703D01*
G01Y-249036D02*
X-83678Y-248953D01*
Y-248786D01*
X-83511Y-248703D01*
X-83344Y-248786D01*
Y-248953D01*
X-83511Y-249036D01*
G01X-76578Y-250786D02*
X-77161Y-250453D01*
X-77661Y-250370D01*
X-78328Y-250536D01*
X-78828Y-250870D01*
X-79161Y-251453D01*
X-79244Y-252036D01*
X-79161Y-252620D01*
X-78828Y-253120D01*
X-78328Y-253536D01*
X-77661Y-253703D01*
X-77078Y-253536D01*
X-76578Y-253203D01*
G01X-73728Y-253703D02*
Y-248703D01*
G01X-71061Y-250370D02*
X-73728Y-252286D01*
G01X-72644Y-251536D02*
X-70894Y-253703D01*
G01X-68128D02*
Y-250370D01*
G01Y-251203D02*
X-67794Y-250786D01*
X-67294Y-250453D01*
X-66628Y-250370D01*
X-66044Y-250453D01*
X-65544Y-250786D01*
X-65294Y-251370D01*
Y-253703D01*
G01X-62361Y-251453D02*
X-59694D01*
X-59944Y-250870D01*
X-60361Y-250536D01*
X-60944Y-250370D01*
X-61528Y-250453D01*
X-62028Y-250703D01*
X-62361Y-251286D01*
X-62528Y-251786D01*
Y-252286D01*
X-62361Y-252786D01*
X-61944Y-253286D01*
X-61444Y-253620D01*
X-60861Y-253703D01*
X-60278Y-253536D01*
X-59694Y-253036D01*
G01X-56761Y-253120D02*
X-56344Y-253453D01*
X-55761Y-253703D01*
X-55261D01*
X-54761Y-253536D01*
X-54428Y-253286D01*
X-54261Y-252953D01*
X-54344Y-252453D01*
X-54678Y-252203D01*
X-56178Y-251703D01*
X-56511Y-251120D01*
X-56344Y-250703D01*
X-56011Y-250453D01*
X-55511Y-250370D01*
X-55011Y-250453D01*
X-54511Y-250703D01*
G01X-51161Y-253120D02*
X-50744Y-253453D01*
X-50161Y-253703D01*
X-49661D01*
X-49161Y-253536D01*
X-48828Y-253286D01*
X-48661Y-252953D01*
X-48744Y-252453D01*
X-49078Y-252203D01*
X-50578Y-251703D01*
X-50911Y-251120D01*
X-50744Y-250703D01*
X-50411Y-250453D01*
X-49911Y-250370D01*
X-49411Y-250453D01*
X-48911Y-250703D01*
G01X-161911Y-218703D02*
Y-223703D01*
G01X-163828Y-218703D02*
X-159994D01*
G01X-157728Y-223703D02*
Y-218703D01*
G01Y-221120D02*
X-157311Y-220703D01*
X-156894Y-220453D01*
X-156228Y-220370D01*
X-155728Y-220453D01*
X-155144Y-220786D01*
X-154894Y-221286D01*
Y-223703D01*
G01X-151961Y-221453D02*
X-149294D01*
X-149544Y-220870D01*
X-149961Y-220536D01*
X-150544Y-220370D01*
X-151128Y-220453D01*
X-151628Y-220703D01*
X-151961Y-221286D01*
X-152128Y-221786D01*
Y-222286D01*
X-151961Y-222786D01*
X-151544Y-223286D01*
X-151044Y-223620D01*
X-150461Y-223703D01*
X-149878Y-223536D01*
X-149294Y-223036D01*
G01X-139511Y-223703D02*
Y-218703D01*
G01X-132411Y-223703D02*
Y-220370D01*
G01Y-220953D02*
X-132744Y-220620D01*
X-133244Y-220453D01*
X-133828Y-220370D01*
X-134411Y-220536D01*
X-134911Y-220870D01*
X-135244Y-221370D01*
X-135411Y-222036D01*
X-135244Y-222703D01*
X-134911Y-223203D01*
X-134411Y-223536D01*
X-133828Y-223703D01*
X-133244Y-223620D01*
X-132744Y-223370D01*
X-132411Y-223036D01*
G01X-129478Y-223703D02*
Y-220370D01*
G01Y-221036D02*
X-129061Y-220703D01*
X-128644Y-220453D01*
X-128061Y-220370D01*
X-127644Y-220453D01*
X-127144Y-220703D01*
G01X-123878Y-224953D02*
X-123294Y-225286D01*
X-122628Y-225370D01*
X-122044Y-225286D01*
X-121544Y-224870D01*
X-121211Y-224286D01*
Y-220370D01*
G01Y-221036D02*
X-121544Y-220703D01*
X-122044Y-220453D01*
X-122628Y-220370D01*
X-123294Y-220536D01*
X-123711Y-220870D01*
X-124044Y-221453D01*
X-124211Y-222036D01*
X-124128Y-222536D01*
X-123794Y-223120D01*
X-123294Y-223536D01*
X-122628Y-223703D01*
X-122128Y-223620D01*
X-121544Y-223286D01*
X-121211Y-222953D01*
G01X-118361Y-221453D02*
X-115694D01*
X-115944Y-220870D01*
X-116361Y-220536D01*
X-116944Y-220370D01*
X-117528Y-220453D01*
X-118028Y-220703D01*
X-118361Y-221286D01*
X-118528Y-221786D01*
Y-222286D01*
X-118361Y-222786D01*
X-117944Y-223286D01*
X-117444Y-223620D01*
X-116861Y-223703D01*
X-116278Y-223536D01*
X-115694Y-223036D01*
G01X-112761Y-223120D02*
X-112344Y-223453D01*
X-111761Y-223703D01*
X-111261D01*
X-110761Y-223536D01*
X-110428Y-223286D01*
X-110261Y-222953D01*
X-110344Y-222453D01*
X-110678Y-222203D01*
X-112178Y-221703D01*
X-112511Y-221120D01*
X-112344Y-220703D01*
X-112011Y-220453D01*
X-111511Y-220370D01*
X-111011Y-220453D01*
X-110511Y-220703D01*
G01X-105911Y-218703D02*
Y-223703D01*
G01X-107078Y-220370D02*
X-104744D01*
G01X-93211Y-218703D02*
Y-223703D01*
G01Y-222953D02*
X-93544Y-223370D01*
X-94044Y-223620D01*
X-94628Y-223703D01*
X-95294Y-223536D01*
X-95794Y-223120D01*
X-96128Y-222620D01*
X-96211Y-222036D01*
X-96128Y-221453D01*
X-95794Y-220953D01*
X-95294Y-220536D01*
X-94628Y-220370D01*
X-94044Y-220453D01*
X-93628Y-220620D01*
X-93211Y-220953D01*
G01X-89111Y-220370D02*
Y-223703D01*
G01Y-219036D02*
X-89278Y-218953D01*
Y-218786D01*
X-89111Y-218703D01*
X-88944Y-218786D01*
Y-218953D01*
X-89111Y-219036D01*
G01X-86011Y-223703D02*
Y-220370D01*
G01Y-221286D02*
X-85761Y-220870D01*
X-85344Y-220536D01*
X-84761Y-220370D01*
X-84178Y-220536D01*
X-83761Y-220870D01*
X-83511Y-221286D01*
Y-223703D01*
G01Y-221286D02*
X-83261Y-220870D01*
X-82844Y-220536D01*
X-82261Y-220370D01*
X-81678Y-220536D01*
X-81261Y-220870D01*
X-81011Y-221370D01*
Y-223703D01*
G01X-79161Y-221453D02*
X-76494D01*
X-76744Y-220870D01*
X-77161Y-220536D01*
X-77744Y-220370D01*
X-78328Y-220453D01*
X-78828Y-220703D01*
X-79161Y-221286D01*
X-79328Y-221786D01*
Y-222286D01*
X-79161Y-222786D01*
X-78744Y-223286D01*
X-78244Y-223620D01*
X-77661Y-223703D01*
X-77078Y-223536D01*
X-76494Y-223036D01*
G01X-73728Y-223703D02*
Y-220370D01*
G01Y-221203D02*
X-73394Y-220786D01*
X-72894Y-220453D01*
X-72228Y-220370D01*
X-71644Y-220453D01*
X-71144Y-220786D01*
X-70894Y-221370D01*
Y-223703D01*
G01X-67961Y-223120D02*
X-67544Y-223453D01*
X-66961Y-223703D01*
X-66461D01*
X-65961Y-223536D01*
X-65628Y-223286D01*
X-65461Y-222953D01*
X-65544Y-222453D01*
X-65878Y-222203D01*
X-67378Y-221703D01*
X-67711Y-221120D01*
X-67544Y-220703D01*
X-67211Y-220453D01*
X-66711Y-220370D01*
X-66211Y-220453D01*
X-65711Y-220703D01*
G01X-61111Y-220370D02*
Y-223703D01*
G01Y-219036D02*
X-61278Y-218953D01*
Y-218786D01*
X-61111Y-218703D01*
X-60944Y-218786D01*
Y-218953D01*
X-61111Y-219036D01*
G01X-55511Y-223703D02*
X-56011Y-223620D01*
X-56511Y-223286D01*
X-56844Y-222703D01*
X-57011Y-222036D01*
X-56844Y-221370D01*
X-56511Y-220786D01*
X-56011Y-220453D01*
X-55511Y-220370D01*
X-55011Y-220453D01*
X-54511Y-220786D01*
X-54178Y-221370D01*
X-54094Y-222036D01*
X-54178Y-222703D01*
X-54511Y-223286D01*
X-55011Y-223620D01*
X-55511Y-223703D01*
G01X-51328D02*
Y-220370D01*
G01Y-221203D02*
X-50994Y-220786D01*
X-50494Y-220453D01*
X-49828Y-220370D01*
X-49244Y-220453D01*
X-48744Y-220786D01*
X-48494Y-221370D01*
Y-223703D01*
G01X-38711D02*
X-39211Y-223620D01*
X-39711Y-223286D01*
X-40044Y-222703D01*
X-40211Y-222036D01*
X-40044Y-221370D01*
X-39711Y-220786D01*
X-39211Y-220453D01*
X-38711Y-220370D01*
X-38211Y-220453D01*
X-37711Y-220786D01*
X-37378Y-221370D01*
X-37294Y-222036D01*
X-37378Y-222703D01*
X-37711Y-223286D01*
X-38211Y-223620D01*
X-38711Y-223703D01*
G01X-33611D02*
Y-219453D01*
X-33444Y-219036D01*
X-33111Y-218786D01*
X-32611Y-218703D01*
X-32111Y-218870D01*
X-31861Y-219286D01*
G01X-32861Y-220703D02*
X-34528D01*
G01X-23411Y-225370D02*
Y-220370D01*
G01Y-221120D02*
X-22994Y-220703D01*
X-22578Y-220453D01*
X-21911Y-220370D01*
X-21328Y-220453D01*
X-20744Y-220870D01*
X-20494Y-221453D01*
X-20411Y-222036D01*
X-20494Y-222620D01*
X-20744Y-223203D01*
X-21244Y-223536D01*
X-21911Y-223703D01*
X-22494Y-223620D01*
X-23078Y-223370D01*
X-23411Y-223036D01*
G01X-14811Y-223703D02*
Y-220370D01*
G01Y-220953D02*
X-15144Y-220620D01*
X-15644Y-220453D01*
X-16228Y-220370D01*
X-16811Y-220536D01*
X-17311Y-220870D01*
X-17644Y-221370D01*
X-17811Y-222036D01*
X-17644Y-222703D01*
X-17311Y-223203D01*
X-16811Y-223536D01*
X-16228Y-223703D01*
X-15644Y-223620D01*
X-15144Y-223370D01*
X-14811Y-223036D01*
G01X-9211Y-218703D02*
Y-223703D01*
G01Y-222953D02*
X-9544Y-223370D01*
X-10044Y-223620D01*
X-10628Y-223703D01*
X-11294Y-223536D01*
X-11794Y-223120D01*
X-12128Y-222620D01*
X-12211Y-222036D01*
X-12128Y-221453D01*
X-11794Y-220953D01*
X-11294Y-220536D01*
X-10628Y-220370D01*
X-10044Y-220453D01*
X-9628Y-220620D01*
X-9211Y-220953D01*
G01X489Y-223703D02*
X-11Y-223620D01*
X-511Y-223286D01*
X-844Y-222703D01*
X-1011Y-222036D01*
X-844Y-221370D01*
X-511Y-220786D01*
X-11Y-220453D01*
X489Y-220370D01*
X989Y-220453D01*
X1489Y-220786D01*
X1822Y-221370D01*
X1906Y-222036D01*
X1822Y-222703D01*
X1489Y-223286D01*
X989Y-223620D01*
X489Y-223703D01*
G01X4922D02*
Y-220370D01*
G01Y-221036D02*
X5339Y-220703D01*
X5756Y-220453D01*
X6339Y-220370D01*
X6756Y-220453D01*
X7256Y-220703D01*
G01X18789Y-218703D02*
Y-223703D01*
G01Y-222953D02*
X18456Y-223370D01*
X17956Y-223620D01*
X17372Y-223703D01*
X16706Y-223536D01*
X16206Y-223120D01*
X15872Y-222620D01*
X15789Y-222036D01*
X15872Y-221453D01*
X16206Y-220953D01*
X16706Y-220536D01*
X17372Y-220370D01*
X17956Y-220453D01*
X18372Y-220620D01*
X18789Y-220953D01*
G01X22889Y-220370D02*
Y-223703D01*
G01Y-219036D02*
X22722Y-218953D01*
Y-218786D01*
X22889Y-218703D01*
X23056Y-218786D01*
Y-218953D01*
X22889Y-219036D01*
G01X29989Y-223703D02*
Y-220370D01*
G01Y-220953D02*
X29656Y-220620D01*
X29156Y-220453D01*
X28572Y-220370D01*
X27989Y-220536D01*
X27489Y-220870D01*
X27156Y-221370D01*
X26989Y-222036D01*
X27156Y-222703D01*
X27489Y-223203D01*
X27989Y-223536D01*
X28572Y-223703D01*
X29156Y-223620D01*
X29656Y-223370D01*
X29989Y-223036D01*
G01X31589Y-223703D02*
Y-220370D01*
G01Y-221286D02*
X31839Y-220870D01*
X32256Y-220536D01*
X32839Y-220370D01*
X33422Y-220536D01*
X33839Y-220870D01*
X34089Y-221286D01*
Y-223703D01*
G01Y-221286D02*
X34339Y-220870D01*
X34756Y-220536D01*
X35339Y-220370D01*
X35922Y-220536D01*
X36339Y-220870D01*
X36589Y-221370D01*
Y-223703D01*
G01X38439Y-221453D02*
X41106D01*
X40856Y-220870D01*
X40439Y-220536D01*
X39856Y-220370D01*
X39272Y-220453D01*
X38772Y-220703D01*
X38439Y-221286D01*
X38272Y-221786D01*
Y-222286D01*
X38439Y-222786D01*
X38856Y-223286D01*
X39356Y-223620D01*
X39939Y-223703D01*
X40522Y-223536D01*
X41106Y-223036D01*
G01X45289Y-218703D02*
Y-223703D01*
G01X44122Y-220370D02*
X46456D01*
G01X49639Y-221453D02*
X52306D01*
X52056Y-220870D01*
X51639Y-220536D01*
X51056Y-220370D01*
X50472Y-220453D01*
X49972Y-220703D01*
X49639Y-221286D01*
X49472Y-221786D01*
Y-222286D01*
X49639Y-222786D01*
X50056Y-223286D01*
X50556Y-223620D01*
X51139Y-223703D01*
X51722Y-223536D01*
X52306Y-223036D01*
G01X55322Y-223703D02*
Y-220370D01*
G01Y-221036D02*
X55739Y-220703D01*
X56156Y-220453D01*
X56739Y-220370D01*
X57156Y-220453D01*
X57656Y-220703D01*
G01X66022Y-223703D02*
X69356Y-222036D01*
X66022Y-220370D01*
G01X73289Y-223703D02*
Y-218703D01*
X72289Y-219703D01*
G01Y-223703D02*
X74289D01*
G01X79889D02*
Y-218703D01*
X76806Y-222286D01*
X80972D01*
G01X87589Y-223703D02*
Y-220370D01*
G01Y-221286D02*
X87839Y-220870D01*
X88256Y-220536D01*
X88839Y-220370D01*
X89422Y-220536D01*
X89839Y-220870D01*
X90089Y-221286D01*
Y-223703D01*
G01Y-221286D02*
X90339Y-220870D01*
X90756Y-220536D01*
X91339Y-220370D01*
X91922Y-220536D01*
X92339Y-220870D01*
X92589Y-221370D01*
Y-223703D01*
G01X95689Y-220370D02*
Y-223703D01*
G01Y-219036D02*
X95522Y-218953D01*
Y-218786D01*
X95689Y-218703D01*
X95856Y-218786D01*
Y-218953D01*
X95689Y-219036D01*
G01X101289Y-223703D02*
Y-218703D01*
G01X-170411Y-228203D02*
X260089D01*
G01X-160831Y-201033D02*
Y-206033D01*
G01X-162748Y-201033D02*
X-158914D01*
G01X-156648Y-206033D02*
Y-201033D01*
G01Y-203450D02*
X-156231Y-203033D01*
X-155814Y-202783D01*
X-155148Y-202700D01*
X-154648Y-202783D01*
X-154064Y-203116D01*
X-153814Y-203616D01*
Y-206033D01*
G01X-150881Y-203783D02*
X-148214D01*
X-148464Y-203200D01*
X-148881Y-202866D01*
X-149464Y-202700D01*
X-150048Y-202783D01*
X-150548Y-203033D01*
X-150881Y-203616D01*
X-151048Y-204116D01*
Y-204616D01*
X-150881Y-205116D01*
X-150464Y-205616D01*
X-149964Y-205950D01*
X-149381Y-206033D01*
X-148798Y-205866D01*
X-148214Y-205366D01*
G01X-138431Y-206033D02*
Y-201033D01*
G01X-131331Y-206033D02*
Y-202700D01*
G01Y-203283D02*
X-131664Y-202950D01*
X-132164Y-202783D01*
X-132748Y-202700D01*
X-133331Y-202866D01*
X-133831Y-203200D01*
X-134164Y-203700D01*
X-134331Y-204366D01*
X-134164Y-205033D01*
X-133831Y-205533D01*
X-133331Y-205866D01*
X-132748Y-206033D01*
X-132164Y-205950D01*
X-131664Y-205700D01*
X-131331Y-205366D01*
G01X-128398Y-206033D02*
Y-202700D01*
G01Y-203366D02*
X-127981Y-203033D01*
X-127564Y-202783D01*
X-126981Y-202700D01*
X-126564Y-202783D01*
X-126064Y-203033D01*
G01X-122798Y-207283D02*
X-122214Y-207616D01*
X-121548Y-207700D01*
X-120964Y-207616D01*
X-120464Y-207200D01*
X-120131Y-206616D01*
Y-202700D01*
G01Y-203366D02*
X-120464Y-203033D01*
X-120964Y-202783D01*
X-121548Y-202700D01*
X-122214Y-202866D01*
X-122631Y-203200D01*
X-122964Y-203783D01*
X-123131Y-204366D01*
X-123048Y-204866D01*
X-122714Y-205450D01*
X-122214Y-205866D01*
X-121548Y-206033D01*
X-121048Y-205950D01*
X-120464Y-205616D01*
X-120131Y-205283D01*
G01X-117281Y-203783D02*
X-114614D01*
X-114864Y-203200D01*
X-115281Y-202866D01*
X-115864Y-202700D01*
X-116448Y-202783D01*
X-116948Y-203033D01*
X-117281Y-203616D01*
X-117448Y-204116D01*
Y-204616D01*
X-117281Y-205116D01*
X-116864Y-205616D01*
X-116364Y-205950D01*
X-115781Y-206033D01*
X-115198Y-205866D01*
X-114614Y-205366D01*
G01X-111681Y-205450D02*
X-111264Y-205783D01*
X-110681Y-206033D01*
X-110181D01*
X-109681Y-205866D01*
X-109348Y-205616D01*
X-109181Y-205283D01*
X-109264Y-204783D01*
X-109598Y-204533D01*
X-111098Y-204033D01*
X-111431Y-203450D01*
X-111264Y-203033D01*
X-110931Y-202783D01*
X-110431Y-202700D01*
X-109931Y-202783D01*
X-109431Y-203033D01*
G01X-104831Y-201033D02*
Y-206033D01*
G01X-105998Y-202700D02*
X-103664D01*
G01X-92131Y-201033D02*
Y-206033D01*
G01Y-205283D02*
X-92464Y-205700D01*
X-92964Y-205950D01*
X-93548Y-206033D01*
X-94214Y-205866D01*
X-94714Y-205450D01*
X-95048Y-204950D01*
X-95131Y-204366D01*
X-95048Y-203783D01*
X-94714Y-203283D01*
X-94214Y-202866D01*
X-93548Y-202700D01*
X-92964Y-202783D01*
X-92548Y-202950D01*
X-92131Y-203283D01*
G01X-88031Y-202700D02*
Y-206033D01*
G01Y-201366D02*
X-88198Y-201283D01*
Y-201116D01*
X-88031Y-201033D01*
X-87864Y-201116D01*
Y-201283D01*
X-88031Y-201366D01*
G01X-84931Y-206033D02*
Y-202700D01*
G01Y-203616D02*
X-84681Y-203200D01*
X-84264Y-202866D01*
X-83681Y-202700D01*
X-83098Y-202866D01*
X-82681Y-203200D01*
X-82431Y-203616D01*
Y-206033D01*
G01Y-203616D02*
X-82181Y-203200D01*
X-81764Y-202866D01*
X-81181Y-202700D01*
X-80598Y-202866D01*
X-80181Y-203200D01*
X-79931Y-203700D01*
Y-206033D01*
G01X-78081Y-203783D02*
X-75414D01*
X-75664Y-203200D01*
X-76081Y-202866D01*
X-76664Y-202700D01*
X-77248Y-202783D01*
X-77748Y-203033D01*
X-78081Y-203616D01*
X-78248Y-204116D01*
Y-204616D01*
X-78081Y-205116D01*
X-77664Y-205616D01*
X-77164Y-205950D01*
X-76581Y-206033D01*
X-75998Y-205866D01*
X-75414Y-205366D01*
G01X-72648Y-206033D02*
Y-202700D01*
G01Y-203533D02*
X-72314Y-203116D01*
X-71814Y-202783D01*
X-71148Y-202700D01*
X-70564Y-202783D01*
X-70064Y-203116D01*
X-69814Y-203700D01*
Y-206033D01*
G01X-66881Y-205450D02*
X-66464Y-205783D01*
X-65881Y-206033D01*
X-65381D01*
X-64881Y-205866D01*
X-64548Y-205616D01*
X-64381Y-205283D01*
X-64464Y-204783D01*
X-64798Y-204533D01*
X-66298Y-204033D01*
X-66631Y-203450D01*
X-66464Y-203033D01*
X-66131Y-202783D01*
X-65631Y-202700D01*
X-65131Y-202783D01*
X-64631Y-203033D01*
G01X-60031Y-202700D02*
Y-206033D01*
G01Y-201366D02*
X-60198Y-201283D01*
Y-201116D01*
X-60031Y-201033D01*
X-59864Y-201116D01*
Y-201283D01*
X-60031Y-201366D01*
G01X-54431Y-206033D02*
X-54931Y-205950D01*
X-55431Y-205616D01*
X-55764Y-205033D01*
X-55931Y-204366D01*
X-55764Y-203700D01*
X-55431Y-203116D01*
X-54931Y-202783D01*
X-54431Y-202700D01*
X-53931Y-202783D01*
X-53431Y-203116D01*
X-53098Y-203700D01*
X-53014Y-204366D01*
X-53098Y-205033D01*
X-53431Y-205616D01*
X-53931Y-205950D01*
X-54431Y-206033D01*
G01X-50248D02*
Y-202700D01*
G01Y-203533D02*
X-49914Y-203116D01*
X-49414Y-202783D01*
X-48748Y-202700D01*
X-48164Y-202783D01*
X-47664Y-203116D01*
X-47414Y-203700D01*
Y-206033D01*
G01X-37631D02*
X-38131Y-205950D01*
X-38631Y-205616D01*
X-38964Y-205033D01*
X-39131Y-204366D01*
X-38964Y-203700D01*
X-38631Y-203116D01*
X-38131Y-202783D01*
X-37631Y-202700D01*
X-37131Y-202783D01*
X-36631Y-203116D01*
X-36298Y-203700D01*
X-36214Y-204366D01*
X-36298Y-205033D01*
X-36631Y-205616D01*
X-37131Y-205950D01*
X-37631Y-206033D01*
G01X-32531D02*
Y-201783D01*
X-32364Y-201366D01*
X-32031Y-201116D01*
X-31531Y-201033D01*
X-31031Y-201200D01*
X-30781Y-201616D01*
G01X-31781Y-203033D02*
X-33448D01*
G01X-22331Y-207700D02*
Y-202700D01*
G01Y-203450D02*
X-21914Y-203033D01*
X-21498Y-202783D01*
X-20831Y-202700D01*
X-20248Y-202783D01*
X-19664Y-203200D01*
X-19414Y-203783D01*
X-19331Y-204366D01*
X-19414Y-204950D01*
X-19664Y-205533D01*
X-20164Y-205866D01*
X-20831Y-206033D01*
X-21414Y-205950D01*
X-21998Y-205700D01*
X-22331Y-205366D01*
G01X-13731Y-206033D02*
Y-202700D01*
G01Y-203283D02*
X-14064Y-202950D01*
X-14564Y-202783D01*
X-15148Y-202700D01*
X-15731Y-202866D01*
X-16231Y-203200D01*
X-16564Y-203700D01*
X-16731Y-204366D01*
X-16564Y-205033D01*
X-16231Y-205533D01*
X-15731Y-205866D01*
X-15148Y-206033D01*
X-14564Y-205950D01*
X-14064Y-205700D01*
X-13731Y-205366D01*
G01X-8131Y-201033D02*
Y-206033D01*
G01Y-205283D02*
X-8464Y-205700D01*
X-8964Y-205950D01*
X-9548Y-206033D01*
X-10214Y-205866D01*
X-10714Y-205450D01*
X-11048Y-204950D01*
X-11131Y-204366D01*
X-11048Y-203783D01*
X-10714Y-203283D01*
X-10214Y-202866D01*
X-9548Y-202700D01*
X-8964Y-202783D01*
X-8548Y-202950D01*
X-8131Y-203283D01*
G01X1569Y-206033D02*
X1069Y-205950D01*
X569Y-205616D01*
X236Y-205033D01*
X69Y-204366D01*
X236Y-203700D01*
X569Y-203116D01*
X1069Y-202783D01*
X1569Y-202700D01*
X2069Y-202783D01*
X2569Y-203116D01*
X2902Y-203700D01*
X2986Y-204366D01*
X2902Y-205033D01*
X2569Y-205616D01*
X2069Y-205950D01*
X1569Y-206033D01*
G01X6002D02*
Y-202700D01*
G01Y-203366D02*
X6419Y-203033D01*
X6836Y-202783D01*
X7419Y-202700D01*
X7836Y-202783D01*
X8336Y-203033D01*
G01X19869Y-201033D02*
Y-206033D01*
G01Y-205283D02*
X19536Y-205700D01*
X19036Y-205950D01*
X18452Y-206033D01*
X17786Y-205866D01*
X17286Y-205450D01*
X16952Y-204950D01*
X16869Y-204366D01*
X16952Y-203783D01*
X17286Y-203283D01*
X17786Y-202866D01*
X18452Y-202700D01*
X19036Y-202783D01*
X19452Y-202950D01*
X19869Y-203283D01*
G01X23969Y-202700D02*
Y-206033D01*
G01Y-201366D02*
X23802Y-201283D01*
Y-201116D01*
X23969Y-201033D01*
X24136Y-201116D01*
Y-201283D01*
X23969Y-201366D01*
G01X31069Y-206033D02*
Y-202700D01*
G01Y-203283D02*
X30736Y-202950D01*
X30236Y-202783D01*
X29652Y-202700D01*
X29069Y-202866D01*
X28569Y-203200D01*
X28236Y-203700D01*
X28069Y-204366D01*
X28236Y-205033D01*
X28569Y-205533D01*
X29069Y-205866D01*
X29652Y-206033D01*
X30236Y-205950D01*
X30736Y-205700D01*
X31069Y-205366D01*
G01X32669Y-206033D02*
Y-202700D01*
G01Y-203616D02*
X32919Y-203200D01*
X33336Y-202866D01*
X33919Y-202700D01*
X34502Y-202866D01*
X34919Y-203200D01*
X35169Y-203616D01*
Y-206033D01*
G01Y-203616D02*
X35419Y-203200D01*
X35836Y-202866D01*
X36419Y-202700D01*
X37002Y-202866D01*
X37419Y-203200D01*
X37669Y-203700D01*
Y-206033D01*
G01X39519Y-203783D02*
X42186D01*
X41936Y-203200D01*
X41519Y-202866D01*
X40936Y-202700D01*
X40352Y-202783D01*
X39852Y-203033D01*
X39519Y-203616D01*
X39352Y-204116D01*
Y-204616D01*
X39519Y-205116D01*
X39936Y-205616D01*
X40436Y-205950D01*
X41019Y-206033D01*
X41602Y-205866D01*
X42186Y-205366D01*
G01X46369Y-201033D02*
Y-206033D01*
G01X45202Y-202700D02*
X47536D01*
G01X50719Y-203783D02*
X53386D01*
X53136Y-203200D01*
X52719Y-202866D01*
X52136Y-202700D01*
X51552Y-202783D01*
X51052Y-203033D01*
X50719Y-203616D01*
X50552Y-204116D01*
Y-204616D01*
X50719Y-205116D01*
X51136Y-205616D01*
X51636Y-205950D01*
X52219Y-206033D01*
X52802Y-205866D01*
X53386Y-205366D01*
G01X56402Y-206033D02*
Y-202700D01*
G01Y-203366D02*
X56819Y-203033D01*
X57236Y-202783D01*
X57819Y-202700D01*
X58236Y-202783D01*
X58736Y-203033D01*
G01X70436Y-206033D02*
X67102Y-204366D01*
X70436Y-202700D01*
G01X73286Y-205116D02*
X75452D01*
G01Y-203616D02*
X73286D01*
G01X85569Y-206033D02*
Y-201033D01*
X84569Y-202033D01*
G01Y-206033D02*
X86569D01*
G01X92169D02*
Y-201033D01*
X89086Y-204616D01*
X93252D01*
G01X99869Y-206033D02*
Y-202700D01*
G01Y-203616D02*
X100119Y-203200D01*
X100536Y-202866D01*
X101119Y-202700D01*
X101702Y-202866D01*
X102119Y-203200D01*
X102369Y-203616D01*
Y-206033D01*
G01Y-203616D02*
X102619Y-203200D01*
X103036Y-202866D01*
X103619Y-202700D01*
X104202Y-202866D01*
X104619Y-203200D01*
X104869Y-203700D01*
Y-206033D01*
G01X107969Y-202700D02*
Y-206033D01*
G01Y-201366D02*
X107802Y-201283D01*
Y-201116D01*
X107969Y-201033D01*
X108136Y-201116D01*
Y-201283D01*
X107969Y-201366D01*
G01X113569Y-206033D02*
Y-201033D01*
G01X-170411Y-193203D02*
X260089D01*
G01X-161911Y-162203D02*
Y-167203D01*
G01X-163078Y-163870D02*
X-160744D01*
G01X-157478Y-167203D02*
Y-163870D01*
G01Y-164536D02*
X-157061Y-164203D01*
X-156644Y-163953D01*
X-156061Y-163870D01*
X-155644Y-163953D01*
X-155144Y-164203D01*
G01X-149211Y-167203D02*
Y-163870D01*
G01Y-164453D02*
X-149544Y-164120D01*
X-150044Y-163953D01*
X-150628Y-163870D01*
X-151211Y-164036D01*
X-151711Y-164370D01*
X-152044Y-164870D01*
X-152211Y-165536D01*
X-152044Y-166203D01*
X-151711Y-166703D01*
X-151211Y-167036D01*
X-150628Y-167203D01*
X-150044Y-167120D01*
X-149544Y-166870D01*
X-149211Y-166536D01*
G01X-143778Y-164286D02*
X-144361Y-163953D01*
X-144861Y-163870D01*
X-145528Y-164036D01*
X-146028Y-164370D01*
X-146361Y-164953D01*
X-146444Y-165536D01*
X-146361Y-166120D01*
X-146028Y-166620D01*
X-145528Y-167036D01*
X-144861Y-167203D01*
X-144278Y-167036D01*
X-143778Y-166703D01*
G01X-140761Y-164953D02*
X-138094D01*
X-138344Y-164370D01*
X-138761Y-164036D01*
X-139344Y-163870D01*
X-139928Y-163953D01*
X-140428Y-164203D01*
X-140761Y-164786D01*
X-140928Y-165286D01*
Y-165786D01*
X-140761Y-166286D01*
X-140344Y-166786D01*
X-139844Y-167120D01*
X-139261Y-167203D01*
X-138678Y-167036D01*
X-138094Y-166536D01*
G01X-130394Y-163870D02*
X-129394Y-167203D01*
X-128311Y-163870D01*
X-127228Y-167203D01*
X-126228Y-163870D01*
G01X-122711D02*
Y-167203D01*
G01Y-162536D02*
X-122878Y-162453D01*
Y-162286D01*
X-122711Y-162203D01*
X-122544Y-162286D01*
Y-162453D01*
X-122711Y-162536D01*
G01X-115611Y-162203D02*
Y-167203D01*
G01Y-166453D02*
X-115944Y-166870D01*
X-116444Y-167120D01*
X-117028Y-167203D01*
X-117694Y-167036D01*
X-118194Y-166620D01*
X-118528Y-166120D01*
X-118611Y-165536D01*
X-118528Y-164953D01*
X-118194Y-164453D01*
X-117694Y-164036D01*
X-117028Y-163870D01*
X-116444Y-163953D01*
X-116028Y-164120D01*
X-115611Y-164453D01*
G01X-111511Y-162203D02*
Y-167203D01*
G01X-112678Y-163870D02*
X-110344D01*
G01X-107328Y-167203D02*
Y-162203D01*
G01Y-164620D02*
X-106911Y-164203D01*
X-106494Y-163953D01*
X-105828Y-163870D01*
X-105328Y-163953D01*
X-104744Y-164286D01*
X-104494Y-164786D01*
Y-167203D01*
G01X-96378D02*
X-93044Y-165536D01*
X-96378Y-163870D01*
G01X-83678Y-167203D02*
X-83511Y-166120D01*
X-83261Y-165203D01*
X-82928Y-164370D01*
X-82511Y-163453D01*
X-81844Y-162203D01*
X-85178D01*
G01X-74811Y-167203D02*
Y-163870D01*
G01Y-164786D02*
X-74561Y-164370D01*
X-74144Y-164036D01*
X-73561Y-163870D01*
X-72978Y-164036D01*
X-72561Y-164370D01*
X-72311Y-164786D01*
Y-167203D01*
G01Y-164786D02*
X-72061Y-164370D01*
X-71644Y-164036D01*
X-71061Y-163870D01*
X-70478Y-164036D01*
X-70061Y-164370D01*
X-69811Y-164870D01*
Y-167203D01*
G01X-66711Y-163870D02*
Y-167203D01*
G01Y-162536D02*
X-66878Y-162453D01*
Y-162286D01*
X-66711Y-162203D01*
X-66544Y-162286D01*
Y-162453D01*
X-66711Y-162536D01*
G01X-61111Y-167203D02*
Y-162203D01*
G01X-161911Y-181703D02*
Y-186703D01*
G01X-163828Y-181703D02*
X-159994D01*
G01X-157728Y-186703D02*
Y-181703D01*
G01Y-184120D02*
X-157311Y-183703D01*
X-156894Y-183453D01*
X-156228Y-183370D01*
X-155728Y-183453D01*
X-155144Y-183786D01*
X-154894Y-184286D01*
Y-186703D01*
G01X-151961Y-184453D02*
X-149294D01*
X-149544Y-183870D01*
X-149961Y-183536D01*
X-150544Y-183370D01*
X-151128Y-183453D01*
X-151628Y-183703D01*
X-151961Y-184286D01*
X-152128Y-184786D01*
Y-185286D01*
X-151961Y-185786D01*
X-151544Y-186286D01*
X-151044Y-186620D01*
X-150461Y-186703D01*
X-149878Y-186536D01*
X-149294Y-186036D01*
G01X-139511Y-186703D02*
Y-181703D01*
G01X-132411Y-186703D02*
Y-183370D01*
G01Y-183953D02*
X-132744Y-183620D01*
X-133244Y-183453D01*
X-133828Y-183370D01*
X-134411Y-183536D01*
X-134911Y-183870D01*
X-135244Y-184370D01*
X-135411Y-185036D01*
X-135244Y-185703D01*
X-134911Y-186203D01*
X-134411Y-186536D01*
X-133828Y-186703D01*
X-133244Y-186620D01*
X-132744Y-186370D01*
X-132411Y-186036D01*
G01X-129478Y-186703D02*
Y-183370D01*
G01Y-184036D02*
X-129061Y-183703D01*
X-128644Y-183453D01*
X-128061Y-183370D01*
X-127644Y-183453D01*
X-127144Y-183703D01*
G01X-123878Y-187953D02*
X-123294Y-188286D01*
X-122628Y-188370D01*
X-122044Y-188286D01*
X-121544Y-187870D01*
X-121211Y-187286D01*
Y-183370D01*
G01Y-184036D02*
X-121544Y-183703D01*
X-122044Y-183453D01*
X-122628Y-183370D01*
X-123294Y-183536D01*
X-123711Y-183870D01*
X-124044Y-184453D01*
X-124211Y-185036D01*
X-124128Y-185536D01*
X-123794Y-186120D01*
X-123294Y-186536D01*
X-122628Y-186703D01*
X-122128Y-186620D01*
X-121544Y-186286D01*
X-121211Y-185953D01*
G01X-118361Y-184453D02*
X-115694D01*
X-115944Y-183870D01*
X-116361Y-183536D01*
X-116944Y-183370D01*
X-117528Y-183453D01*
X-118028Y-183703D01*
X-118361Y-184286D01*
X-118528Y-184786D01*
Y-185286D01*
X-118361Y-185786D01*
X-117944Y-186286D01*
X-117444Y-186620D01*
X-116861Y-186703D01*
X-116278Y-186536D01*
X-115694Y-186036D01*
G01X-112761Y-186120D02*
X-112344Y-186453D01*
X-111761Y-186703D01*
X-111261D01*
X-110761Y-186536D01*
X-110428Y-186286D01*
X-110261Y-185953D01*
X-110344Y-185453D01*
X-110678Y-185203D01*
X-112178Y-184703D01*
X-112511Y-184120D01*
X-112344Y-183703D01*
X-112011Y-183453D01*
X-111511Y-183370D01*
X-111011Y-183453D01*
X-110511Y-183703D01*
G01X-105911Y-181703D02*
Y-186703D01*
G01X-107078Y-183370D02*
X-104744D01*
G01X-93211Y-181703D02*
Y-186703D01*
G01Y-185953D02*
X-93544Y-186370D01*
X-94044Y-186620D01*
X-94628Y-186703D01*
X-95294Y-186536D01*
X-95794Y-186120D01*
X-96128Y-185620D01*
X-96211Y-185036D01*
X-96128Y-184453D01*
X-95794Y-183953D01*
X-95294Y-183536D01*
X-94628Y-183370D01*
X-94044Y-183453D01*
X-93628Y-183620D01*
X-93211Y-183953D01*
G01X-89111Y-183370D02*
Y-186703D01*
G01Y-182036D02*
X-89278Y-181953D01*
Y-181786D01*
X-89111Y-181703D01*
X-88944Y-181786D01*
Y-181953D01*
X-89111Y-182036D01*
G01X-86011Y-186703D02*
Y-183370D01*
G01Y-184286D02*
X-85761Y-183870D01*
X-85344Y-183536D01*
X-84761Y-183370D01*
X-84178Y-183536D01*
X-83761Y-183870D01*
X-83511Y-184286D01*
Y-186703D01*
G01Y-184286D02*
X-83261Y-183870D01*
X-82844Y-183536D01*
X-82261Y-183370D01*
X-81678Y-183536D01*
X-81261Y-183870D01*
X-81011Y-184370D01*
Y-186703D01*
G01X-79161Y-184453D02*
X-76494D01*
X-76744Y-183870D01*
X-77161Y-183536D01*
X-77744Y-183370D01*
X-78328Y-183453D01*
X-78828Y-183703D01*
X-79161Y-184286D01*
X-79328Y-184786D01*
Y-185286D01*
X-79161Y-185786D01*
X-78744Y-186286D01*
X-78244Y-186620D01*
X-77661Y-186703D01*
X-77078Y-186536D01*
X-76494Y-186036D01*
G01X-73728Y-186703D02*
Y-183370D01*
G01Y-184203D02*
X-73394Y-183786D01*
X-72894Y-183453D01*
X-72228Y-183370D01*
X-71644Y-183453D01*
X-71144Y-183786D01*
X-70894Y-184370D01*
Y-186703D01*
G01X-67961Y-186120D02*
X-67544Y-186453D01*
X-66961Y-186703D01*
X-66461D01*
X-65961Y-186536D01*
X-65628Y-186286D01*
X-65461Y-185953D01*
X-65544Y-185453D01*
X-65878Y-185203D01*
X-67378Y-184703D01*
X-67711Y-184120D01*
X-67544Y-183703D01*
X-67211Y-183453D01*
X-66711Y-183370D01*
X-66211Y-183453D01*
X-65711Y-183703D01*
G01X-61111Y-183370D02*
Y-186703D01*
G01Y-182036D02*
X-61278Y-181953D01*
Y-181786D01*
X-61111Y-181703D01*
X-60944Y-181786D01*
Y-181953D01*
X-61111Y-182036D01*
G01X-55511Y-186703D02*
X-56011Y-186620D01*
X-56511Y-186286D01*
X-56844Y-185703D01*
X-57011Y-185036D01*
X-56844Y-184370D01*
X-56511Y-183786D01*
X-56011Y-183453D01*
X-55511Y-183370D01*
X-55011Y-183453D01*
X-54511Y-183786D01*
X-54178Y-184370D01*
X-54094Y-185036D01*
X-54178Y-185703D01*
X-54511Y-186286D01*
X-55011Y-186620D01*
X-55511Y-186703D01*
G01X-51328D02*
Y-183370D01*
G01Y-184203D02*
X-50994Y-183786D01*
X-50494Y-183453D01*
X-49828Y-183370D01*
X-49244Y-183453D01*
X-48744Y-183786D01*
X-48494Y-184370D01*
Y-186703D01*
G01X-38711D02*
X-39211Y-186620D01*
X-39711Y-186286D01*
X-40044Y-185703D01*
X-40211Y-185036D01*
X-40044Y-184370D01*
X-39711Y-183786D01*
X-39211Y-183453D01*
X-38711Y-183370D01*
X-38211Y-183453D01*
X-37711Y-183786D01*
X-37378Y-184370D01*
X-37294Y-185036D01*
X-37378Y-185703D01*
X-37711Y-186286D01*
X-38211Y-186620D01*
X-38711Y-186703D01*
G01X-33611D02*
Y-182453D01*
X-33444Y-182036D01*
X-33111Y-181786D01*
X-32611Y-181703D01*
X-32111Y-181870D01*
X-31861Y-182286D01*
G01X-32861Y-183703D02*
X-34528D01*
G01X-23411Y-188370D02*
Y-183370D01*
G01Y-184120D02*
X-22994Y-183703D01*
X-22578Y-183453D01*
X-21911Y-183370D01*
X-21328Y-183453D01*
X-20744Y-183870D01*
X-20494Y-184453D01*
X-20411Y-185036D01*
X-20494Y-185620D01*
X-20744Y-186203D01*
X-21244Y-186536D01*
X-21911Y-186703D01*
X-22494Y-186620D01*
X-23078Y-186370D01*
X-23411Y-186036D01*
G01X-14811Y-186703D02*
Y-183370D01*
G01Y-183953D02*
X-15144Y-183620D01*
X-15644Y-183453D01*
X-16228Y-183370D01*
X-16811Y-183536D01*
X-17311Y-183870D01*
X-17644Y-184370D01*
X-17811Y-185036D01*
X-17644Y-185703D01*
X-17311Y-186203D01*
X-16811Y-186536D01*
X-16228Y-186703D01*
X-15644Y-186620D01*
X-15144Y-186370D01*
X-14811Y-186036D01*
G01X-9211Y-181703D02*
Y-186703D01*
G01Y-185953D02*
X-9544Y-186370D01*
X-10044Y-186620D01*
X-10628Y-186703D01*
X-11294Y-186536D01*
X-11794Y-186120D01*
X-12128Y-185620D01*
X-12211Y-185036D01*
X-12128Y-184453D01*
X-11794Y-183953D01*
X-11294Y-183536D01*
X-10628Y-183370D01*
X-10044Y-183453D01*
X-9628Y-183620D01*
X-9211Y-183953D01*
G01X489Y-186703D02*
X-11Y-186620D01*
X-511Y-186286D01*
X-844Y-185703D01*
X-1011Y-185036D01*
X-844Y-184370D01*
X-511Y-183786D01*
X-11Y-183453D01*
X489Y-183370D01*
X989Y-183453D01*
X1489Y-183786D01*
X1822Y-184370D01*
X1906Y-185036D01*
X1822Y-185703D01*
X1489Y-186286D01*
X989Y-186620D01*
X489Y-186703D01*
G01X4922D02*
Y-183370D01*
G01Y-184036D02*
X5339Y-183703D01*
X5756Y-183453D01*
X6339Y-183370D01*
X6756Y-183453D01*
X7256Y-183703D01*
G01X18789Y-181703D02*
Y-186703D01*
G01Y-185953D02*
X18456Y-186370D01*
X17956Y-186620D01*
X17372Y-186703D01*
X16706Y-186536D01*
X16206Y-186120D01*
X15872Y-185620D01*
X15789Y-185036D01*
X15872Y-184453D01*
X16206Y-183953D01*
X16706Y-183536D01*
X17372Y-183370D01*
X17956Y-183453D01*
X18372Y-183620D01*
X18789Y-183953D01*
G01X22889Y-183370D02*
Y-186703D01*
G01Y-182036D02*
X22722Y-181953D01*
Y-181786D01*
X22889Y-181703D01*
X23056Y-181786D01*
Y-181953D01*
X22889Y-182036D01*
G01X29989Y-186703D02*
Y-183370D01*
G01Y-183953D02*
X29656Y-183620D01*
X29156Y-183453D01*
X28572Y-183370D01*
X27989Y-183536D01*
X27489Y-183870D01*
X27156Y-184370D01*
X26989Y-185036D01*
X27156Y-185703D01*
X27489Y-186203D01*
X27989Y-186536D01*
X28572Y-186703D01*
X29156Y-186620D01*
X29656Y-186370D01*
X29989Y-186036D01*
G01X31589Y-186703D02*
Y-183370D01*
G01Y-184286D02*
X31839Y-183870D01*
X32256Y-183536D01*
X32839Y-183370D01*
X33422Y-183536D01*
X33839Y-183870D01*
X34089Y-184286D01*
Y-186703D01*
G01Y-184286D02*
X34339Y-183870D01*
X34756Y-183536D01*
X35339Y-183370D01*
X35922Y-183536D01*
X36339Y-183870D01*
X36589Y-184370D01*
Y-186703D01*
G01X38439Y-184453D02*
X41106D01*
X40856Y-183870D01*
X40439Y-183536D01*
X39856Y-183370D01*
X39272Y-183453D01*
X38772Y-183703D01*
X38439Y-184286D01*
X38272Y-184786D01*
Y-185286D01*
X38439Y-185786D01*
X38856Y-186286D01*
X39356Y-186620D01*
X39939Y-186703D01*
X40522Y-186536D01*
X41106Y-186036D01*
G01X45289Y-181703D02*
Y-186703D01*
G01X44122Y-183370D02*
X46456D01*
G01X49639Y-184453D02*
X52306D01*
X52056Y-183870D01*
X51639Y-183536D01*
X51056Y-183370D01*
X50472Y-183453D01*
X49972Y-183703D01*
X49639Y-184286D01*
X49472Y-184786D01*
Y-185286D01*
X49639Y-185786D01*
X50056Y-186286D01*
X50556Y-186620D01*
X51139Y-186703D01*
X51722Y-186536D01*
X52306Y-186036D01*
G01X55322Y-186703D02*
Y-183370D01*
G01Y-184036D02*
X55739Y-183703D01*
X56156Y-183453D01*
X56739Y-183370D01*
X57156Y-183453D01*
X57656Y-183703D01*
G01X66022Y-186703D02*
X69356Y-185036D01*
X66022Y-183370D01*
G01X78889Y-186703D02*
Y-181703D01*
X77889Y-182703D01*
G01Y-186703D02*
X79889D01*
G01X85489D02*
Y-181703D01*
X82406Y-185286D01*
X86572D01*
G01X93189Y-186703D02*
Y-183370D01*
G01Y-184286D02*
X93439Y-183870D01*
X93856Y-183536D01*
X94439Y-183370D01*
X95022Y-183536D01*
X95439Y-183870D01*
X95689Y-184286D01*
Y-186703D01*
G01Y-184286D02*
X95939Y-183870D01*
X96356Y-183536D01*
X96939Y-183370D01*
X97522Y-183536D01*
X97939Y-183870D01*
X98189Y-184370D01*
Y-186703D01*
G01X101289Y-183370D02*
Y-186703D01*
G01Y-182036D02*
X101122Y-181953D01*
Y-181786D01*
X101289Y-181703D01*
X101456Y-181786D01*
Y-181953D01*
X101289Y-182036D01*
G01X106889Y-186703D02*
Y-181703D01*
G01X-163744Y-151453D02*
X-163244Y-151870D01*
X-162661Y-152120D01*
X-161911Y-152203D01*
X-161161Y-152036D01*
X-160578Y-151703D01*
X-160161Y-151120D01*
X-160078Y-150453D01*
X-160244Y-149786D01*
X-160661Y-149370D01*
X-161244Y-149036D01*
X-161828Y-148953D01*
X-162411Y-149036D01*
X-163161Y-149370D01*
X-162911Y-147203D01*
X-160661D01*
G01X-153211Y-152203D02*
Y-148870D01*
G01Y-149786D02*
X-152961Y-149370D01*
X-152544Y-149036D01*
X-151961Y-148870D01*
X-151378Y-149036D01*
X-150961Y-149370D01*
X-150711Y-149786D01*
Y-152203D01*
G01Y-149786D02*
X-150461Y-149370D01*
X-150044Y-149036D01*
X-149461Y-148870D01*
X-148878Y-149036D01*
X-148461Y-149370D01*
X-148211Y-149870D01*
Y-152203D01*
G01X-145111Y-148870D02*
Y-152203D01*
G01Y-147536D02*
X-145278Y-147453D01*
Y-147286D01*
X-145111Y-147203D01*
X-144944Y-147286D01*
Y-147453D01*
X-145111Y-147536D01*
G01X-139511Y-152203D02*
Y-147203D01*
G01X-126644Y-152203D02*
X-129978Y-150536D01*
X-126644Y-148870D01*
G01X-117111Y-147203D02*
Y-152203D01*
G01X-118278Y-148870D02*
X-115944D01*
G01X-112678Y-152203D02*
Y-148870D01*
G01Y-149536D02*
X-112261Y-149203D01*
X-111844Y-148953D01*
X-111261Y-148870D01*
X-110844Y-148953D01*
X-110344Y-149203D01*
G01X-104411Y-152203D02*
Y-148870D01*
G01Y-149453D02*
X-104744Y-149120D01*
X-105244Y-148953D01*
X-105828Y-148870D01*
X-106411Y-149036D01*
X-106911Y-149370D01*
X-107244Y-149870D01*
X-107411Y-150536D01*
X-107244Y-151203D01*
X-106911Y-151703D01*
X-106411Y-152036D01*
X-105828Y-152203D01*
X-105244Y-152120D01*
X-104744Y-151870D01*
X-104411Y-151536D01*
G01X-98978Y-149286D02*
X-99561Y-148953D01*
X-100061Y-148870D01*
X-100728Y-149036D01*
X-101228Y-149370D01*
X-101561Y-149953D01*
X-101644Y-150536D01*
X-101561Y-151120D01*
X-101228Y-151620D01*
X-100728Y-152036D01*
X-100061Y-152203D01*
X-99478Y-152036D01*
X-98978Y-151703D01*
G01X-95961Y-149953D02*
X-93294D01*
X-93544Y-149370D01*
X-93961Y-149036D01*
X-94544Y-148870D01*
X-95128Y-148953D01*
X-95628Y-149203D01*
X-95961Y-149786D01*
X-96128Y-150286D01*
Y-150786D01*
X-95961Y-151286D01*
X-95544Y-151786D01*
X-95044Y-152120D01*
X-94461Y-152203D01*
X-93878Y-152036D01*
X-93294Y-151536D01*
G01X-85594Y-148870D02*
X-84594Y-152203D01*
X-83511Y-148870D01*
X-82428Y-152203D01*
X-81428Y-148870D01*
G01X-77911D02*
Y-152203D01*
G01Y-147536D02*
X-78078Y-147453D01*
Y-147286D01*
X-77911Y-147203D01*
X-77744Y-147286D01*
Y-147453D01*
X-77911Y-147536D01*
G01X-70811Y-147203D02*
Y-152203D01*
G01Y-151453D02*
X-71144Y-151870D01*
X-71644Y-152120D01*
X-72228Y-152203D01*
X-72894Y-152036D01*
X-73394Y-151620D01*
X-73728Y-151120D01*
X-73811Y-150536D01*
X-73728Y-149953D01*
X-73394Y-149453D01*
X-72894Y-149036D01*
X-72228Y-148870D01*
X-71644Y-148953D01*
X-71228Y-149120D01*
X-70811Y-149453D01*
G01X-66711Y-147203D02*
Y-152203D01*
G01X-67878Y-148870D02*
X-65544D01*
G01X-62528Y-152203D02*
Y-147203D01*
G01Y-149620D02*
X-62111Y-149203D01*
X-61694Y-148953D01*
X-61028Y-148870D01*
X-60528Y-148953D01*
X-59944Y-149286D01*
X-59694Y-149786D01*
Y-152203D01*
G01X-48244D02*
X-51578Y-150536D01*
X-48244Y-148870D01*
G01X-45394Y-151286D02*
X-43228D01*
G01Y-149786D02*
X-45394D01*
G01X-33278Y-152203D02*
X-33111Y-151120D01*
X-32861Y-150203D01*
X-32528Y-149370D01*
X-32111Y-148453D01*
X-31444Y-147203D01*
X-34778D01*
G01X-24411Y-152203D02*
Y-148870D01*
G01Y-149786D02*
X-24161Y-149370D01*
X-23744Y-149036D01*
X-23161Y-148870D01*
X-22578Y-149036D01*
X-22161Y-149370D01*
X-21911Y-149786D01*
Y-152203D01*
G01Y-149786D02*
X-21661Y-149370D01*
X-21244Y-149036D01*
X-20661Y-148870D01*
X-20078Y-149036D01*
X-19661Y-149370D01*
X-19411Y-149870D01*
Y-152203D01*
G01X-16311Y-148870D02*
Y-152203D01*
G01Y-147536D02*
X-16478Y-147453D01*
Y-147286D01*
X-16311Y-147203D01*
X-16144Y-147286D01*
Y-147453D01*
X-16311Y-147536D01*
G01X-10711Y-152203D02*
Y-147203D01*
G01X-170411Y-158203D02*
X260089D01*
G01X-161911Y-132203D02*
Y-137203D01*
G01X-163078Y-133870D02*
X-160744D01*
G01X-157478Y-137203D02*
Y-133870D01*
G01Y-134536D02*
X-157061Y-134203D01*
X-156644Y-133953D01*
X-156061Y-133870D01*
X-155644Y-133953D01*
X-155144Y-134203D01*
G01X-149211Y-137203D02*
Y-133870D01*
G01Y-134453D02*
X-149544Y-134120D01*
X-150044Y-133953D01*
X-150628Y-133870D01*
X-151211Y-134036D01*
X-151711Y-134370D01*
X-152044Y-134870D01*
X-152211Y-135536D01*
X-152044Y-136203D01*
X-151711Y-136703D01*
X-151211Y-137036D01*
X-150628Y-137203D01*
X-150044Y-137120D01*
X-149544Y-136870D01*
X-149211Y-136536D01*
G01X-143778Y-134286D02*
X-144361Y-133953D01*
X-144861Y-133870D01*
X-145528Y-134036D01*
X-146028Y-134370D01*
X-146361Y-134953D01*
X-146444Y-135536D01*
X-146361Y-136120D01*
X-146028Y-136620D01*
X-145528Y-137036D01*
X-144861Y-137203D01*
X-144278Y-137036D01*
X-143778Y-136703D01*
G01X-140761Y-134953D02*
X-138094D01*
X-138344Y-134370D01*
X-138761Y-134036D01*
X-139344Y-133870D01*
X-139928Y-133953D01*
X-140428Y-134203D01*
X-140761Y-134786D01*
X-140928Y-135286D01*
Y-135786D01*
X-140761Y-136286D01*
X-140344Y-136786D01*
X-139844Y-137120D01*
X-139261Y-137203D01*
X-138678Y-137036D01*
X-138094Y-136536D01*
G01X-130394Y-133870D02*
X-129394Y-137203D01*
X-128311Y-133870D01*
X-127228Y-137203D01*
X-126228Y-133870D01*
G01X-122711D02*
Y-137203D01*
G01Y-132536D02*
X-122878Y-132453D01*
Y-132286D01*
X-122711Y-132203D01*
X-122544Y-132286D01*
Y-132453D01*
X-122711Y-132536D01*
G01X-115611Y-132203D02*
Y-137203D01*
G01Y-136453D02*
X-115944Y-136870D01*
X-116444Y-137120D01*
X-117028Y-137203D01*
X-117694Y-137036D01*
X-118194Y-136620D01*
X-118528Y-136120D01*
X-118611Y-135536D01*
X-118528Y-134953D01*
X-118194Y-134453D01*
X-117694Y-134036D01*
X-117028Y-133870D01*
X-116444Y-133953D01*
X-116028Y-134120D01*
X-115611Y-134453D01*
G01X-111511Y-132203D02*
Y-137203D01*
G01X-112678Y-133870D02*
X-110344D01*
G01X-107328Y-137203D02*
Y-132203D01*
G01Y-134620D02*
X-106911Y-134203D01*
X-106494Y-133953D01*
X-105828Y-133870D01*
X-105328Y-133953D01*
X-104744Y-134286D01*
X-104494Y-134786D01*
Y-137203D01*
G01X-93044D02*
X-96378Y-135536D01*
X-93044Y-133870D01*
G01X-90194Y-136286D02*
X-88028D01*
G01Y-134786D02*
X-90194D01*
G01X-79744Y-136453D02*
X-79244Y-136870D01*
X-78661Y-137120D01*
X-77911Y-137203D01*
X-77161Y-137036D01*
X-76578Y-136703D01*
X-76161Y-136120D01*
X-76078Y-135453D01*
X-76244Y-134786D01*
X-76661Y-134370D01*
X-77244Y-134036D01*
X-77828Y-133953D01*
X-78411Y-134036D01*
X-79161Y-134370D01*
X-78911Y-132203D01*
X-76661D01*
G01X-69211Y-137203D02*
Y-133870D01*
G01Y-134786D02*
X-68961Y-134370D01*
X-68544Y-134036D01*
X-67961Y-133870D01*
X-67378Y-134036D01*
X-66961Y-134370D01*
X-66711Y-134786D01*
Y-137203D01*
G01Y-134786D02*
X-66461Y-134370D01*
X-66044Y-134036D01*
X-65461Y-133870D01*
X-64878Y-134036D01*
X-64461Y-134370D01*
X-64211Y-134870D01*
Y-137203D01*
G01X-61111Y-133870D02*
Y-137203D01*
G01Y-132536D02*
X-61278Y-132453D01*
Y-132286D01*
X-61111Y-132203D01*
X-60944Y-132286D01*
Y-132453D01*
X-61111Y-132536D01*
G01X-55511Y-137203D02*
Y-132203D01*
G01X-163578Y-123703D02*
Y-118703D01*
X-161494D01*
X-160828Y-118953D01*
X-160411Y-119286D01*
X-160244Y-119953D01*
X-160411Y-120620D01*
X-160911Y-121036D01*
X-161494Y-121286D01*
X-163578D01*
G01X-161494D02*
X-160244Y-123703D01*
G01X-157561Y-121453D02*
X-154894D01*
X-155144Y-120870D01*
X-155561Y-120536D01*
X-156144Y-120370D01*
X-156728Y-120453D01*
X-157228Y-120703D01*
X-157561Y-121286D01*
X-157728Y-121786D01*
Y-122286D01*
X-157561Y-122786D01*
X-157144Y-123286D01*
X-156644Y-123620D01*
X-156061Y-123703D01*
X-155478Y-123536D01*
X-154894Y-123036D01*
G01X-150711Y-123703D02*
Y-118703D01*
G01X-143611Y-123703D02*
Y-120370D01*
G01Y-120953D02*
X-143944Y-120620D01*
X-144444Y-120453D01*
X-145028Y-120370D01*
X-145611Y-120536D01*
X-146111Y-120870D01*
X-146444Y-121370D01*
X-146611Y-122036D01*
X-146444Y-122703D01*
X-146111Y-123203D01*
X-145611Y-123536D01*
X-145028Y-123703D01*
X-144444Y-123620D01*
X-143944Y-123370D01*
X-143611Y-123036D01*
G01X-139511Y-118703D02*
Y-123703D01*
G01X-140678Y-120370D02*
X-138344D01*
G01X-133911D02*
Y-123703D01*
G01Y-119036D02*
X-134078Y-118953D01*
Y-118786D01*
X-133911Y-118703D01*
X-133744Y-118786D01*
Y-118953D01*
X-133911Y-119036D01*
G01X-129811Y-120370D02*
X-128311Y-123703D01*
X-126811Y-120370D01*
G01X-123961Y-121453D02*
X-121294D01*
X-121544Y-120870D01*
X-121961Y-120536D01*
X-122544Y-120370D01*
X-123128Y-120453D01*
X-123628Y-120703D01*
X-123961Y-121286D01*
X-124128Y-121786D01*
Y-122286D01*
X-123961Y-122786D01*
X-123544Y-123286D01*
X-123044Y-123620D01*
X-122461Y-123703D01*
X-121878Y-123536D01*
X-121294Y-123036D01*
G01X-113011Y-125370D02*
Y-120370D01*
G01Y-121120D02*
X-112594Y-120703D01*
X-112178Y-120453D01*
X-111511Y-120370D01*
X-110928Y-120453D01*
X-110344Y-120870D01*
X-110094Y-121453D01*
X-110011Y-122036D01*
X-110094Y-122620D01*
X-110344Y-123203D01*
X-110844Y-123536D01*
X-111511Y-123703D01*
X-112094Y-123620D01*
X-112678Y-123370D01*
X-113011Y-123036D01*
G01X-105911Y-123703D02*
X-106411Y-123620D01*
X-106911Y-123286D01*
X-107244Y-122703D01*
X-107411Y-122036D01*
X-107244Y-121370D01*
X-106911Y-120786D01*
X-106411Y-120453D01*
X-105911Y-120370D01*
X-105411Y-120453D01*
X-104911Y-120786D01*
X-104578Y-121370D01*
X-104494Y-122036D01*
X-104578Y-122703D01*
X-104911Y-123286D01*
X-105411Y-123620D01*
X-105911Y-123703D01*
G01X-101561Y-123120D02*
X-101144Y-123453D01*
X-100561Y-123703D01*
X-100061D01*
X-99561Y-123536D01*
X-99228Y-123286D01*
X-99061Y-122953D01*
X-99144Y-122453D01*
X-99478Y-122203D01*
X-100978Y-121703D01*
X-101311Y-121120D01*
X-101144Y-120703D01*
X-100811Y-120453D01*
X-100311Y-120370D01*
X-99811Y-120453D01*
X-99311Y-120703D01*
G01X-94711Y-120370D02*
Y-123703D01*
G01Y-119036D02*
X-94878Y-118953D01*
Y-118786D01*
X-94711Y-118703D01*
X-94544Y-118786D01*
Y-118953D01*
X-94711Y-119036D01*
G01X-89111Y-118703D02*
Y-123703D01*
G01X-90278Y-120370D02*
X-87944D01*
G01X-83511D02*
Y-123703D01*
G01Y-119036D02*
X-83678Y-118953D01*
Y-118786D01*
X-83511Y-118703D01*
X-83344Y-118786D01*
Y-118953D01*
X-83511Y-119036D01*
G01X-77911Y-123703D02*
X-78411Y-123620D01*
X-78911Y-123286D01*
X-79244Y-122703D01*
X-79411Y-122036D01*
X-79244Y-121370D01*
X-78911Y-120786D01*
X-78411Y-120453D01*
X-77911Y-120370D01*
X-77411Y-120453D01*
X-76911Y-120786D01*
X-76578Y-121370D01*
X-76494Y-122036D01*
X-76578Y-122703D01*
X-76911Y-123286D01*
X-77411Y-123620D01*
X-77911Y-123703D01*
G01X-73728D02*
Y-120370D01*
G01Y-121203D02*
X-73394Y-120786D01*
X-72894Y-120453D01*
X-72228Y-120370D01*
X-71644Y-120453D01*
X-71144Y-120786D01*
X-70894Y-121370D01*
Y-123703D01*
G01X-62611D02*
Y-118703D01*
G01Y-121203D02*
X-62194Y-120703D01*
X-61694Y-120453D01*
X-61194Y-120370D01*
X-60444Y-120536D01*
X-59944Y-120870D01*
X-59611Y-121453D01*
Y-122120D01*
X-59778Y-122786D01*
X-60111Y-123286D01*
X-60694Y-123620D01*
X-61194Y-123703D01*
X-61694Y-123620D01*
X-62194Y-123370D01*
X-62611Y-122953D01*
G01X-56761Y-121453D02*
X-54094D01*
X-54344Y-120870D01*
X-54761Y-120536D01*
X-55344Y-120370D01*
X-55928Y-120453D01*
X-56428Y-120703D01*
X-56761Y-121286D01*
X-56928Y-121786D01*
Y-122286D01*
X-56761Y-122786D01*
X-56344Y-123286D01*
X-55844Y-123620D01*
X-55261Y-123703D01*
X-54678Y-123536D01*
X-54094Y-123036D01*
G01X-49911Y-118703D02*
Y-123703D01*
G01X-51078Y-120370D02*
X-48744D01*
G01X-46394D02*
X-45394Y-123703D01*
X-44311Y-120370D01*
X-43228Y-123703D01*
X-42228Y-120370D01*
G01X-39961Y-121453D02*
X-37294D01*
X-37544Y-120870D01*
X-37961Y-120536D01*
X-38544Y-120370D01*
X-39128Y-120453D01*
X-39628Y-120703D01*
X-39961Y-121286D01*
X-40128Y-121786D01*
Y-122286D01*
X-39961Y-122786D01*
X-39544Y-123286D01*
X-39044Y-123620D01*
X-38461Y-123703D01*
X-37878Y-123536D01*
X-37294Y-123036D01*
G01X-34361Y-121453D02*
X-31694D01*
X-31944Y-120870D01*
X-32361Y-120536D01*
X-32944Y-120370D01*
X-33528Y-120453D01*
X-34028Y-120703D01*
X-34361Y-121286D01*
X-34528Y-121786D01*
Y-122286D01*
X-34361Y-122786D01*
X-33944Y-123286D01*
X-33444Y-123620D01*
X-32861Y-123703D01*
X-32278Y-123536D01*
X-31694Y-123036D01*
G01X-28928Y-123703D02*
Y-120370D01*
G01Y-121203D02*
X-28594Y-120786D01*
X-28094Y-120453D01*
X-27428Y-120370D01*
X-26844Y-120453D01*
X-26344Y-120786D01*
X-26094Y-121370D01*
Y-123703D01*
G01X-14811D02*
Y-120370D01*
G01Y-120953D02*
X-15144Y-120620D01*
X-15644Y-120453D01*
X-16228Y-120370D01*
X-16811Y-120536D01*
X-17311Y-120870D01*
X-17644Y-121370D01*
X-17811Y-122036D01*
X-17644Y-122703D01*
X-17311Y-123203D01*
X-16811Y-123536D01*
X-16228Y-123703D01*
X-15644Y-123620D01*
X-15144Y-123370D01*
X-14811Y-123036D01*
G01X-12128Y-123703D02*
Y-120370D01*
G01Y-121203D02*
X-11794Y-120786D01*
X-11294Y-120453D01*
X-10628Y-120370D01*
X-10044Y-120453D01*
X-9544Y-120786D01*
X-9294Y-121370D01*
Y-123703D01*
G01X-6861Y-125203D02*
X-6361Y-125370D01*
X-5694Y-125203D01*
X-5278Y-124870D01*
X-4944Y-124453D01*
X-4444Y-123120D01*
X-3361Y-120370D01*
G01X-6028D02*
X-4444Y-123120D01*
G01X4589Y-125370D02*
Y-120370D01*
G01Y-121120D02*
X5006Y-120703D01*
X5422Y-120453D01*
X6089Y-120370D01*
X6672Y-120453D01*
X7256Y-120870D01*
X7506Y-121453D01*
X7589Y-122036D01*
X7506Y-122620D01*
X7256Y-123203D01*
X6756Y-123536D01*
X6089Y-123703D01*
X5506Y-123620D01*
X4922Y-123370D01*
X4589Y-123036D01*
G01X13189Y-123703D02*
Y-120370D01*
G01Y-120953D02*
X12856Y-120620D01*
X12356Y-120453D01*
X11772Y-120370D01*
X11189Y-120536D01*
X10689Y-120870D01*
X10356Y-121370D01*
X10189Y-122036D01*
X10356Y-122703D01*
X10689Y-123203D01*
X11189Y-123536D01*
X11772Y-123703D01*
X12356Y-123620D01*
X12856Y-123370D01*
X13189Y-123036D01*
G01X18789Y-118703D02*
Y-123703D01*
G01Y-122953D02*
X18456Y-123370D01*
X17956Y-123620D01*
X17372Y-123703D01*
X16706Y-123536D01*
X16206Y-123120D01*
X15872Y-122620D01*
X15789Y-122036D01*
X15872Y-121453D01*
X16206Y-120953D01*
X16706Y-120536D01*
X17372Y-120370D01*
X17956Y-120453D01*
X18372Y-120620D01*
X18789Y-120953D01*
G01X28489Y-118703D02*
Y-123703D01*
G01X27322Y-120370D02*
X29656D01*
G01X34089Y-123703D02*
X33589Y-123620D01*
X33089Y-123286D01*
X32756Y-122703D01*
X32589Y-122036D01*
X32756Y-121370D01*
X33089Y-120786D01*
X33589Y-120453D01*
X34089Y-120370D01*
X34589Y-120453D01*
X35089Y-120786D01*
X35422Y-121370D01*
X35506Y-122036D01*
X35422Y-122703D01*
X35089Y-123286D01*
X34589Y-123620D01*
X34089Y-123703D01*
G01X43789Y-125370D02*
Y-120370D01*
G01Y-121120D02*
X44206Y-120703D01*
X44622Y-120453D01*
X45289Y-120370D01*
X45872Y-120453D01*
X46456Y-120870D01*
X46706Y-121453D01*
X46789Y-122036D01*
X46706Y-122620D01*
X46456Y-123203D01*
X45956Y-123536D01*
X45289Y-123703D01*
X44706Y-123620D01*
X44122Y-123370D01*
X43789Y-123036D01*
G01X52389Y-123703D02*
Y-120370D01*
G01Y-120953D02*
X52056Y-120620D01*
X51556Y-120453D01*
X50972Y-120370D01*
X50389Y-120536D01*
X49889Y-120870D01*
X49556Y-121370D01*
X49389Y-122036D01*
X49556Y-122703D01*
X49889Y-123203D01*
X50389Y-123536D01*
X50972Y-123703D01*
X51556Y-123620D01*
X52056Y-123370D01*
X52389Y-123036D01*
G01X57989Y-118703D02*
Y-123703D01*
G01Y-122953D02*
X57656Y-123370D01*
X57156Y-123620D01*
X56572Y-123703D01*
X55906Y-123536D01*
X55406Y-123120D01*
X55072Y-122620D01*
X54989Y-122036D01*
X55072Y-121453D01*
X55406Y-120953D01*
X55906Y-120536D01*
X56572Y-120370D01*
X57156Y-120453D01*
X57572Y-120620D01*
X57989Y-120953D01*
G01X-170411Y-143203D02*
X260089D01*
G01X-163661Y-108703D02*
Y-103703D01*
G01X-160161D02*
Y-108703D01*
G01Y-106203D02*
X-163661D01*
G01X-158144Y-108703D02*
Y-103703D01*
X-156478D01*
X-155811Y-103953D01*
X-155311Y-104286D01*
X-154894Y-104786D01*
X-154561Y-105370D01*
X-154478Y-106203D01*
X-154561Y-107036D01*
X-154894Y-107620D01*
X-155311Y-108120D01*
X-155811Y-108453D01*
X-156478Y-108703D01*
X-158144D01*
G01X-151711Y-103703D02*
X-149711D01*
G01X-150711D02*
Y-108703D01*
G01X-151711D02*
X-149711D01*
G01X-141178D02*
Y-103703D01*
X-139178D01*
X-138511Y-103953D01*
X-138011Y-104536D01*
X-137844Y-105203D01*
X-138011Y-105870D01*
X-138428Y-106370D01*
X-139178Y-106620D01*
X-141178D01*
G01X-132078Y-104120D02*
X-132578Y-103870D01*
X-133161Y-103703D01*
X-133828D01*
X-134578Y-103953D01*
X-135161Y-104370D01*
X-135578Y-104870D01*
X-135911Y-105703D01*
X-135994Y-106453D01*
X-135828Y-107203D01*
X-135578Y-107703D01*
X-135078Y-108203D01*
X-134494Y-108536D01*
X-133911Y-108703D01*
X-133328D01*
X-132744Y-108536D01*
X-132244Y-108286D01*
X-131828Y-107953D01*
G01X-127644Y-106036D02*
X-127311Y-105786D01*
X-127061Y-105370D01*
X-126894Y-104786D01*
X-127061Y-104286D01*
X-127394Y-103953D01*
X-127978Y-103703D01*
X-130228D01*
Y-108703D01*
X-127478D01*
X-126894Y-108370D01*
X-126561Y-107870D01*
X-126394Y-107286D01*
X-126561Y-106703D01*
X-127061Y-106203D01*
X-127644Y-106036D01*
X-130228D01*
G01X-122711Y-108870D02*
X-122878Y-108786D01*
Y-108620D01*
X-122711Y-108536D01*
X-122544Y-108620D01*
Y-108786D01*
X-122711Y-108870D01*
G01X-163161Y-92120D02*
X-162744Y-92453D01*
X-162161Y-92703D01*
X-161661D01*
X-161161Y-92536D01*
X-160828Y-92286D01*
X-160661Y-91953D01*
X-160744Y-91453D01*
X-161078Y-91203D01*
X-162578Y-90703D01*
X-162911Y-90120D01*
X-162744Y-89703D01*
X-162411Y-89453D01*
X-161911Y-89370D01*
X-161411Y-89453D01*
X-160911Y-89703D01*
G01X-157811Y-94370D02*
Y-89370D01*
G01Y-90120D02*
X-157394Y-89703D01*
X-156978Y-89453D01*
X-156311Y-89370D01*
X-155728Y-89453D01*
X-155144Y-89870D01*
X-154894Y-90453D01*
X-154811Y-91036D01*
X-154894Y-91620D01*
X-155144Y-92203D01*
X-155644Y-92536D01*
X-156311Y-92703D01*
X-156894Y-92620D01*
X-157478Y-92370D01*
X-157811Y-92036D01*
G01X-151961Y-90453D02*
X-149294D01*
X-149544Y-89870D01*
X-149961Y-89536D01*
X-150544Y-89370D01*
X-151128Y-89453D01*
X-151628Y-89703D01*
X-151961Y-90286D01*
X-152128Y-90786D01*
Y-91286D01*
X-151961Y-91786D01*
X-151544Y-92286D01*
X-151044Y-92620D01*
X-150461Y-92703D01*
X-149878Y-92536D01*
X-149294Y-92036D01*
G01X-143778Y-89786D02*
X-144361Y-89453D01*
X-144861Y-89370D01*
X-145528Y-89536D01*
X-146028Y-89870D01*
X-146361Y-90453D01*
X-146444Y-91036D01*
X-146361Y-91620D01*
X-146028Y-92120D01*
X-145528Y-92536D01*
X-144861Y-92703D01*
X-144278Y-92536D01*
X-143778Y-92203D01*
G01X-139511Y-89370D02*
Y-92703D01*
G01Y-88036D02*
X-139678Y-87953D01*
Y-87786D01*
X-139511Y-87703D01*
X-139344Y-87786D01*
Y-87953D01*
X-139511Y-88036D01*
G01X-134411Y-92703D02*
Y-88453D01*
X-134244Y-88036D01*
X-133911Y-87786D01*
X-133411Y-87703D01*
X-132911Y-87870D01*
X-132661Y-88286D01*
G01X-133661Y-89703D02*
X-135328D01*
G01X-128311Y-89370D02*
Y-92703D01*
G01Y-88036D02*
X-128478Y-87953D01*
Y-87786D01*
X-128311Y-87703D01*
X-128144Y-87786D01*
Y-87953D01*
X-128311Y-88036D01*
G01X-121378Y-89786D02*
X-121961Y-89453D01*
X-122461Y-89370D01*
X-123128Y-89536D01*
X-123628Y-89870D01*
X-123961Y-90453D01*
X-124044Y-91036D01*
X-123961Y-91620D01*
X-123628Y-92120D01*
X-123128Y-92536D01*
X-122461Y-92703D01*
X-121878Y-92536D01*
X-121378Y-92203D01*
G01X-115611Y-92703D02*
Y-89370D01*
G01Y-89953D02*
X-115944Y-89620D01*
X-116444Y-89453D01*
X-117028Y-89370D01*
X-117611Y-89536D01*
X-118111Y-89870D01*
X-118444Y-90370D01*
X-118611Y-91036D01*
X-118444Y-91703D01*
X-118111Y-92203D01*
X-117611Y-92536D01*
X-117028Y-92703D01*
X-116444Y-92620D01*
X-115944Y-92370D01*
X-115611Y-92036D01*
G01X-111511Y-87703D02*
Y-92703D01*
G01X-112678Y-89370D02*
X-110344D01*
G01X-105911D02*
Y-92703D01*
G01Y-88036D02*
X-106078Y-87953D01*
Y-87786D01*
X-105911Y-87703D01*
X-105744Y-87786D01*
Y-87953D01*
X-105911Y-88036D01*
G01X-100311Y-92703D02*
X-100811Y-92620D01*
X-101311Y-92286D01*
X-101644Y-91703D01*
X-101811Y-91036D01*
X-101644Y-90370D01*
X-101311Y-89786D01*
X-100811Y-89453D01*
X-100311Y-89370D01*
X-99811Y-89453D01*
X-99311Y-89786D01*
X-98978Y-90370D01*
X-98894Y-91036D01*
X-98978Y-91703D01*
X-99311Y-92286D01*
X-99811Y-92620D01*
X-100311Y-92703D01*
G01X-96128D02*
Y-89370D01*
G01Y-90203D02*
X-95794Y-89786D01*
X-95294Y-89453D01*
X-94628Y-89370D01*
X-94044Y-89453D01*
X-93544Y-89786D01*
X-93294Y-90370D01*
Y-92703D01*
G01X-89111Y-92870D02*
X-89278Y-92786D01*
Y-92620D01*
X-89111Y-92536D01*
X-88944Y-92620D01*
Y-92786D01*
X-89111Y-92870D01*
G01X-163661Y-83036D02*
X-162994Y-83453D01*
X-162244Y-83703D01*
X-161578D01*
X-160911Y-83453D01*
X-160411Y-83036D01*
X-160161Y-82453D01*
X-160328Y-81870D01*
X-160744Y-81370D01*
X-161494Y-81036D01*
X-162494Y-80870D01*
X-163078Y-80536D01*
X-163328Y-79953D01*
X-163161Y-79370D01*
X-162744Y-78953D01*
X-162161Y-78703D01*
X-161578D01*
X-160994Y-78870D01*
X-160494Y-79286D01*
G01X-157561Y-81453D02*
X-154894D01*
X-155144Y-80870D01*
X-155561Y-80536D01*
X-156144Y-80370D01*
X-156728Y-80453D01*
X-157228Y-80703D01*
X-157561Y-81286D01*
X-157728Y-81786D01*
Y-82286D01*
X-157561Y-82786D01*
X-157144Y-83286D01*
X-156644Y-83620D01*
X-156061Y-83703D01*
X-155478Y-83536D01*
X-154894Y-83036D01*
G01X-151878Y-83703D02*
Y-80370D01*
G01Y-81036D02*
X-151461Y-80703D01*
X-151044Y-80453D01*
X-150461Y-80370D01*
X-150044Y-80453D01*
X-149544Y-80703D01*
G01X-146611Y-80370D02*
X-145111Y-83703D01*
X-143611Y-80370D01*
G01X-140761Y-81453D02*
X-138094D01*
X-138344Y-80870D01*
X-138761Y-80536D01*
X-139344Y-80370D01*
X-139928Y-80453D01*
X-140428Y-80703D01*
X-140761Y-81286D01*
X-140928Y-81786D01*
Y-82286D01*
X-140761Y-82786D01*
X-140344Y-83286D01*
X-139844Y-83620D01*
X-139261Y-83703D01*
X-138678Y-83536D01*
X-138094Y-83036D01*
G01X-135078Y-83703D02*
Y-80370D01*
G01Y-81036D02*
X-134661Y-80703D01*
X-134244Y-80453D01*
X-133661Y-80370D01*
X-133244Y-80453D01*
X-132744Y-80703D01*
G01X-124378Y-83703D02*
Y-78703D01*
X-122378D01*
X-121711Y-78953D01*
X-121211Y-79536D01*
X-121044Y-80203D01*
X-121211Y-80870D01*
X-121628Y-81370D01*
X-122378Y-81620D01*
X-124378D01*
G01X-115278Y-79120D02*
X-115778Y-78870D01*
X-116361Y-78703D01*
X-117028D01*
X-117778Y-78953D01*
X-118361Y-79370D01*
X-118778Y-79870D01*
X-119111Y-80703D01*
X-119194Y-81453D01*
X-119028Y-82203D01*
X-118778Y-82703D01*
X-118278Y-83203D01*
X-117694Y-83536D01*
X-117111Y-83703D01*
X-116528D01*
X-115944Y-83536D01*
X-115444Y-83286D01*
X-115028Y-82953D01*
G01X-110844Y-81036D02*
X-110511Y-80786D01*
X-110261Y-80370D01*
X-110094Y-79786D01*
X-110261Y-79286D01*
X-110594Y-78953D01*
X-111178Y-78703D01*
X-113428D01*
Y-83703D01*
X-110678D01*
X-110094Y-83370D01*
X-109761Y-82870D01*
X-109594Y-82286D01*
X-109761Y-81703D01*
X-110261Y-81203D01*
X-110844Y-81036D01*
X-113428D01*
G01X-105911Y-83870D02*
X-106078Y-83786D01*
Y-83620D01*
X-105911Y-83536D01*
X-105744Y-83620D01*
Y-83786D01*
X-105911Y-83870D01*
G01Y-81620D02*
X-106078Y-81536D01*
Y-81370D01*
X-105911Y-81286D01*
X-105744Y-81370D01*
Y-81536D01*
X-105911Y-81620D01*
G01X-101894Y-83703D02*
Y-78703D01*
X-98728D01*
G01X-99894Y-81120D02*
X-101894D01*
G01X-94711Y-83703D02*
X-95211Y-83620D01*
X-95711Y-83286D01*
X-96044Y-82703D01*
X-96211Y-82036D01*
X-96044Y-81370D01*
X-95711Y-80786D01*
X-95211Y-80453D01*
X-94711Y-80370D01*
X-94211Y-80453D01*
X-93711Y-80786D01*
X-93378Y-81370D01*
X-93294Y-82036D01*
X-93378Y-82703D01*
X-93711Y-83286D01*
X-94211Y-83620D01*
X-94711Y-83703D01*
G01X-89111D02*
Y-78703D01*
G01X-83511Y-83703D02*
Y-78703D01*
G01X-77911Y-83703D02*
X-78411Y-83620D01*
X-78911Y-83286D01*
X-79244Y-82703D01*
X-79411Y-82036D01*
X-79244Y-81370D01*
X-78911Y-80786D01*
X-78411Y-80453D01*
X-77911Y-80370D01*
X-77411Y-80453D01*
X-76911Y-80786D01*
X-76578Y-81370D01*
X-76494Y-82036D01*
X-76578Y-82703D01*
X-76911Y-83286D01*
X-77411Y-83620D01*
X-77911Y-83703D01*
G01X-74394Y-80370D02*
X-73394Y-83703D01*
X-72311Y-80370D01*
X-71228Y-83703D01*
X-70228Y-80370D01*
G01X-62278Y-83703D02*
Y-80370D01*
G01Y-81036D02*
X-61861Y-80703D01*
X-61444Y-80453D01*
X-60861Y-80370D01*
X-60444Y-80453D01*
X-59944Y-80703D01*
G01X-55511Y-80370D02*
Y-83703D01*
G01Y-79036D02*
X-55678Y-78953D01*
Y-78786D01*
X-55511Y-78703D01*
X-55344Y-78786D01*
Y-78953D01*
X-55511Y-79036D01*
G01X-51078Y-84953D02*
X-50494Y-85286D01*
X-49828Y-85370D01*
X-49244Y-85286D01*
X-48744Y-84870D01*
X-48411Y-84286D01*
Y-80370D01*
G01Y-81036D02*
X-48744Y-80703D01*
X-49244Y-80453D01*
X-49828Y-80370D01*
X-50494Y-80536D01*
X-50911Y-80870D01*
X-51244Y-81453D01*
X-51411Y-82036D01*
X-51328Y-82536D01*
X-50994Y-83120D01*
X-50494Y-83536D01*
X-49828Y-83703D01*
X-49328Y-83620D01*
X-48744Y-83286D01*
X-48411Y-82953D01*
G01X-45728Y-83703D02*
Y-78703D01*
G01Y-81120D02*
X-45311Y-80703D01*
X-44894Y-80453D01*
X-44228Y-80370D01*
X-43728Y-80453D01*
X-43144Y-80786D01*
X-42894Y-81286D01*
Y-83703D01*
G01X-38711Y-78703D02*
Y-83703D01*
G01X-39878Y-80370D02*
X-37544D01*
G01X-28761Y-83120D02*
X-28344Y-83453D01*
X-27761Y-83703D01*
X-27261D01*
X-26761Y-83536D01*
X-26428Y-83286D01*
X-26261Y-82953D01*
X-26344Y-82453D01*
X-26678Y-82203D01*
X-28178Y-81703D01*
X-28511Y-81120D01*
X-28344Y-80703D01*
X-28011Y-80453D01*
X-27511Y-80370D01*
X-27011Y-80453D01*
X-26511Y-80703D01*
G01X-21911Y-80370D02*
Y-83703D01*
G01Y-79036D02*
X-22078Y-78953D01*
Y-78786D01*
X-21911Y-78703D01*
X-21744Y-78786D01*
Y-78953D01*
X-21911Y-79036D01*
G01X-14811Y-78703D02*
Y-83703D01*
G01Y-82953D02*
X-15144Y-83370D01*
X-15644Y-83620D01*
X-16228Y-83703D01*
X-16894Y-83536D01*
X-17394Y-83120D01*
X-17728Y-82620D01*
X-17811Y-82036D01*
X-17728Y-81453D01*
X-17394Y-80953D01*
X-16894Y-80536D01*
X-16228Y-80370D01*
X-15644Y-80453D01*
X-15228Y-80620D01*
X-14811Y-80953D01*
G01X-11961Y-81453D02*
X-9294D01*
X-9544Y-80870D01*
X-9961Y-80536D01*
X-10544Y-80370D01*
X-11128Y-80453D01*
X-11628Y-80703D01*
X-11961Y-81286D01*
X-12128Y-81786D01*
Y-82286D01*
X-11961Y-82786D01*
X-11544Y-83286D01*
X-11044Y-83620D01*
X-10461Y-83703D01*
X-9878Y-83536D01*
X-9294Y-83036D01*
G01X-761Y-83120D02*
X-344Y-83453D01*
X239Y-83703D01*
X739D01*
X1239Y-83536D01*
X1572Y-83286D01*
X1739Y-82953D01*
X1656Y-82453D01*
X1322Y-82203D01*
X-178Y-81703D01*
X-511Y-81120D01*
X-344Y-80703D01*
X-11Y-80453D01*
X489Y-80370D01*
X989Y-80453D01*
X1489Y-80703D01*
G01X4589Y-85370D02*
Y-80370D01*
G01Y-81120D02*
X5006Y-80703D01*
X5422Y-80453D01*
X6089Y-80370D01*
X6672Y-80453D01*
X7256Y-80870D01*
X7506Y-81453D01*
X7589Y-82036D01*
X7506Y-82620D01*
X7256Y-83203D01*
X6756Y-83536D01*
X6089Y-83703D01*
X5506Y-83620D01*
X4922Y-83370D01*
X4589Y-83036D01*
G01X10439Y-81453D02*
X13106D01*
X12856Y-80870D01*
X12439Y-80536D01*
X11856Y-80370D01*
X11272Y-80453D01*
X10772Y-80703D01*
X10439Y-81286D01*
X10272Y-81786D01*
Y-82286D01*
X10439Y-82786D01*
X10856Y-83286D01*
X11356Y-83620D01*
X11939Y-83703D01*
X12522Y-83536D01*
X13106Y-83036D01*
G01X18622Y-80786D02*
X18039Y-80453D01*
X17539Y-80370D01*
X16872Y-80536D01*
X16372Y-80870D01*
X16039Y-81453D01*
X15956Y-82036D01*
X16039Y-82620D01*
X16372Y-83120D01*
X16872Y-83536D01*
X17539Y-83703D01*
X18122Y-83536D01*
X18622Y-83203D01*
G01X28322Y-84620D02*
X28656Y-83536D01*
G01X34089Y-80370D02*
Y-83703D01*
G01Y-79036D02*
X33922Y-78953D01*
Y-78786D01*
X34089Y-78703D01*
X34256Y-78786D01*
Y-78953D01*
X34089Y-79036D01*
G01X39189Y-83703D02*
Y-79453D01*
X39356Y-79036D01*
X39689Y-78786D01*
X40189Y-78703D01*
X40689Y-78870D01*
X40939Y-79286D01*
G01X39939Y-80703D02*
X38272D01*
G01X49639Y-83120D02*
X50056Y-83453D01*
X50639Y-83703D01*
X51139D01*
X51639Y-83536D01*
X51972Y-83286D01*
X52139Y-82953D01*
X52056Y-82453D01*
X51722Y-82203D01*
X50222Y-81703D01*
X49889Y-81120D01*
X50056Y-80703D01*
X50389Y-80453D01*
X50889Y-80370D01*
X51389Y-80453D01*
X51889Y-80703D01*
G01X56489Y-78703D02*
Y-83703D01*
G01X55322Y-80370D02*
X57656D01*
G01X63589Y-83703D02*
Y-80370D01*
G01Y-80953D02*
X63256Y-80620D01*
X62756Y-80453D01*
X62172Y-80370D01*
X61589Y-80536D01*
X61089Y-80870D01*
X60756Y-81370D01*
X60589Y-82036D01*
X60756Y-82703D01*
X61089Y-83203D01*
X61589Y-83536D01*
X62172Y-83703D01*
X62756Y-83620D01*
X63256Y-83370D01*
X63589Y-83036D01*
G01X69022Y-80786D02*
X68439Y-80453D01*
X67939Y-80370D01*
X67272Y-80536D01*
X66772Y-80870D01*
X66439Y-81453D01*
X66356Y-82036D01*
X66439Y-82620D01*
X66772Y-83120D01*
X67272Y-83536D01*
X67939Y-83703D01*
X68522Y-83536D01*
X69022Y-83203D01*
G01X71872Y-83703D02*
Y-78703D01*
G01X74539Y-80370D02*
X71872Y-82286D01*
G01X72956Y-81536D02*
X74706Y-83703D01*
G01X83072Y-80370D02*
Y-82703D01*
X83406Y-83286D01*
X83906Y-83620D01*
X84489Y-83703D01*
X85072Y-83620D01*
X85572Y-83286D01*
X85906Y-82703D01*
G01Y-83703D02*
Y-80370D01*
G01X88589Y-85370D02*
Y-80370D01*
G01Y-81120D02*
X89006Y-80703D01*
X89422Y-80453D01*
X90089Y-80370D01*
X90672Y-80453D01*
X91256Y-80870D01*
X91506Y-81453D01*
X91589Y-82036D01*
X91506Y-82620D01*
X91256Y-83203D01*
X90756Y-83536D01*
X90089Y-83703D01*
X89506Y-83620D01*
X88922Y-83370D01*
X88589Y-83036D01*
G01X99206Y-80370D02*
X100206Y-83703D01*
X101289Y-80370D01*
X102372Y-83703D01*
X103372Y-80370D01*
G01X106889D02*
Y-83703D01*
G01Y-79036D02*
X106722Y-78953D01*
Y-78786D01*
X106889Y-78703D01*
X107056Y-78786D01*
Y-78953D01*
X106889Y-79036D01*
G01X112489Y-78703D02*
Y-83703D01*
G01X111322Y-80370D02*
X113656D01*
G01X116672Y-83703D02*
Y-78703D01*
G01Y-81120D02*
X117089Y-80703D01*
X117506Y-80453D01*
X118172Y-80370D01*
X118672Y-80453D01*
X119256Y-80786D01*
X119506Y-81286D01*
Y-83703D01*
G01X123689D02*
X123189Y-83620D01*
X122689Y-83286D01*
X122356Y-82703D01*
X122189Y-82036D01*
X122356Y-81370D01*
X122689Y-80786D01*
X123189Y-80453D01*
X123689Y-80370D01*
X124189Y-80453D01*
X124689Y-80786D01*
X125022Y-81370D01*
X125106Y-82036D01*
X125022Y-82703D01*
X124689Y-83286D01*
X124189Y-83620D01*
X123689Y-83703D01*
G01X127872Y-80370D02*
Y-82703D01*
X128206Y-83286D01*
X128706Y-83620D01*
X129289Y-83703D01*
X129872Y-83620D01*
X130372Y-83286D01*
X130706Y-82703D01*
G01Y-83703D02*
Y-80370D01*
G01X134889Y-78703D02*
Y-83703D01*
G01X133722Y-80370D02*
X136056D01*
G01X-170411Y-98203D02*
X260089D01*
G01X-161911Y-63703D02*
Y-68703D01*
G01X-163828Y-63703D02*
X-159994D01*
G01X-157478Y-68703D02*
Y-65370D01*
G01Y-66036D02*
X-157061Y-65703D01*
X-156644Y-65453D01*
X-156061Y-65370D01*
X-155644Y-65453D01*
X-155144Y-65703D01*
G01X-149211Y-68703D02*
Y-65370D01*
G01Y-65953D02*
X-149544Y-65620D01*
X-150044Y-65453D01*
X-150628Y-65370D01*
X-151211Y-65536D01*
X-151711Y-65870D01*
X-152044Y-66370D01*
X-152211Y-67036D01*
X-152044Y-67703D01*
X-151711Y-68203D01*
X-151211Y-68536D01*
X-150628Y-68703D01*
X-150044Y-68620D01*
X-149544Y-68370D01*
X-149211Y-68036D01*
G01X-143611Y-63703D02*
Y-68703D01*
G01Y-67953D02*
X-143944Y-68370D01*
X-144444Y-68620D01*
X-145028Y-68703D01*
X-145694Y-68536D01*
X-146194Y-68120D01*
X-146528Y-67620D01*
X-146611Y-67036D01*
X-146528Y-66453D01*
X-146194Y-65953D01*
X-145694Y-65536D01*
X-145028Y-65370D01*
X-144444Y-65453D01*
X-144028Y-65620D01*
X-143611Y-65953D01*
G01X-139511Y-65370D02*
Y-68703D01*
G01Y-64036D02*
X-139678Y-63953D01*
Y-63786D01*
X-139511Y-63703D01*
X-139344Y-63786D01*
Y-63953D01*
X-139511Y-64036D01*
G01X-133911Y-63703D02*
Y-68703D01*
G01X-135078Y-65370D02*
X-132744D01*
G01X-128311D02*
Y-68703D01*
G01Y-64036D02*
X-128478Y-63953D01*
Y-63786D01*
X-128311Y-63703D01*
X-128144Y-63786D01*
Y-63953D01*
X-128311Y-64036D01*
G01X-122711Y-68703D02*
X-123211Y-68620D01*
X-123711Y-68286D01*
X-124044Y-67703D01*
X-124211Y-67036D01*
X-124044Y-66370D01*
X-123711Y-65786D01*
X-123211Y-65453D01*
X-122711Y-65370D01*
X-122211Y-65453D01*
X-121711Y-65786D01*
X-121378Y-66370D01*
X-121294Y-67036D01*
X-121378Y-67703D01*
X-121711Y-68286D01*
X-122211Y-68620D01*
X-122711Y-68703D01*
G01X-118528D02*
Y-65370D01*
G01Y-66203D02*
X-118194Y-65786D01*
X-117694Y-65453D01*
X-117028Y-65370D01*
X-116444Y-65453D01*
X-115944Y-65786D01*
X-115694Y-66370D01*
Y-68703D01*
G01X-110011D02*
Y-65370D01*
G01Y-65953D02*
X-110344Y-65620D01*
X-110844Y-65453D01*
X-111428Y-65370D01*
X-112011Y-65536D01*
X-112511Y-65870D01*
X-112844Y-66370D01*
X-113011Y-67036D01*
X-112844Y-67703D01*
X-112511Y-68203D01*
X-112011Y-68536D01*
X-111428Y-68703D01*
X-110844Y-68620D01*
X-110344Y-68370D01*
X-110011Y-68036D01*
G01X-105911Y-68703D02*
Y-63703D01*
G01X-96378Y-68703D02*
Y-63703D01*
X-94378D01*
X-93711Y-63953D01*
X-93211Y-64536D01*
X-93044Y-65203D01*
X-93211Y-65870D01*
X-93628Y-66370D01*
X-94378Y-66620D01*
X-96378D01*
G01X-87278Y-64120D02*
X-87778Y-63870D01*
X-88361Y-63703D01*
X-89028D01*
X-89778Y-63953D01*
X-90361Y-64370D01*
X-90778Y-64870D01*
X-91111Y-65703D01*
X-91194Y-66453D01*
X-91028Y-67203D01*
X-90778Y-67703D01*
X-90278Y-68203D01*
X-89694Y-68536D01*
X-89111Y-68703D01*
X-88528D01*
X-87944Y-68536D01*
X-87444Y-68286D01*
X-87028Y-67953D01*
G01X-82844Y-66036D02*
X-82511Y-65786D01*
X-82261Y-65370D01*
X-82094Y-64786D01*
X-82261Y-64286D01*
X-82594Y-63953D01*
X-83178Y-63703D01*
X-85428D01*
Y-68703D01*
X-82678D01*
X-82094Y-68370D01*
X-81761Y-67870D01*
X-81594Y-67286D01*
X-81761Y-66703D01*
X-82261Y-66203D01*
X-82844Y-66036D01*
X-85428D01*
G01X-77911Y-68870D02*
X-78078Y-68786D01*
Y-68620D01*
X-77911Y-68536D01*
X-77744Y-68620D01*
Y-68786D01*
X-77911Y-68870D01*
G01X-170411Y-73203D02*
X260089D01*
G01X-171911Y3797D02*
X260089D01*
G01X-171911Y56797D02*
X260089D01*
G01X-164411Y140297D02*
Y135297D01*
G01X-165578Y138630D02*
X-163244D01*
G01X-158811Y135297D02*
X-159311Y135380D01*
X-159811Y135714D01*
X-160144Y136297D01*
X-160311Y136964D01*
X-160144Y137630D01*
X-159811Y138214D01*
X-159311Y138547D01*
X-158811Y138630D01*
X-158311Y138547D01*
X-157811Y138214D01*
X-157478Y137630D01*
X-157394Y136964D01*
X-157478Y136297D01*
X-157811Y135714D01*
X-158311Y135380D01*
X-158811Y135297D01*
G01X-153211D02*
Y140297D01*
G01X-148861Y137547D02*
X-146194D01*
X-146444Y138130D01*
X-146861Y138464D01*
X-147444Y138630D01*
X-148028Y138547D01*
X-148528Y138297D01*
X-148861Y137714D01*
X-149028Y137214D01*
Y136714D01*
X-148861Y136214D01*
X-148444Y135714D01*
X-147944Y135380D01*
X-147361Y135297D01*
X-146778Y135464D01*
X-146194Y135964D01*
G01X-143178Y135297D02*
Y138630D01*
G01Y137964D02*
X-142761Y138297D01*
X-142344Y138547D01*
X-141761Y138630D01*
X-141344Y138547D01*
X-140844Y138297D01*
G01X-134911Y135297D02*
Y138630D01*
G01Y138047D02*
X-135244Y138380D01*
X-135744Y138547D01*
X-136328Y138630D01*
X-136911Y138464D01*
X-137411Y138130D01*
X-137744Y137630D01*
X-137911Y136964D01*
X-137744Y136297D01*
X-137411Y135797D01*
X-136911Y135464D01*
X-136328Y135297D01*
X-135744Y135380D01*
X-135244Y135630D01*
X-134911Y135964D01*
G01X-132228Y135297D02*
Y138630D01*
G01Y137797D02*
X-131894Y138214D01*
X-131394Y138547D01*
X-130728Y138630D01*
X-130144Y138547D01*
X-129644Y138214D01*
X-129394Y137630D01*
Y135297D01*
G01X-123878Y138214D02*
X-124461Y138547D01*
X-124961Y138630D01*
X-125628Y138464D01*
X-126128Y138130D01*
X-126461Y137547D01*
X-126544Y136964D01*
X-126461Y136380D01*
X-126128Y135880D01*
X-125628Y135464D01*
X-124961Y135297D01*
X-124378Y135464D01*
X-123878Y135797D01*
G01X-120861Y137547D02*
X-118194D01*
X-118444Y138130D01*
X-118861Y138464D01*
X-119444Y138630D01*
X-120028Y138547D01*
X-120528Y138297D01*
X-120861Y137714D01*
X-121028Y137214D01*
Y136714D01*
X-120861Y136214D01*
X-120444Y135714D01*
X-119944Y135380D01*
X-119361Y135297D01*
X-118778Y135464D01*
X-118194Y135964D01*
G01X-108411Y140297D02*
Y135297D01*
G01X-109578Y138630D02*
X-107244D01*
G01X-101311Y135297D02*
Y138630D01*
G01Y138047D02*
X-101644Y138380D01*
X-102144Y138547D01*
X-102728Y138630D01*
X-103311Y138464D01*
X-103811Y138130D01*
X-104144Y137630D01*
X-104311Y136964D01*
X-104144Y136297D01*
X-103811Y135797D01*
X-103311Y135464D01*
X-102728Y135297D01*
X-102144Y135380D01*
X-101644Y135630D01*
X-101311Y135964D01*
G01X-98711Y135297D02*
Y140297D01*
G01Y137797D02*
X-98294Y138297D01*
X-97794Y138547D01*
X-97294Y138630D01*
X-96544Y138464D01*
X-96044Y138130D01*
X-95711Y137547D01*
Y136880D01*
X-95878Y136214D01*
X-96211Y135714D01*
X-96794Y135380D01*
X-97294Y135297D01*
X-97794Y135380D01*
X-98294Y135630D01*
X-98711Y136047D01*
G01X-91611Y135297D02*
Y140297D01*
G01X-87261Y137547D02*
X-84594D01*
X-84844Y138130D01*
X-85261Y138464D01*
X-85844Y138630D01*
X-86428Y138547D01*
X-86928Y138297D01*
X-87261Y137714D01*
X-87428Y137214D01*
Y136714D01*
X-87261Y136214D01*
X-86844Y135714D01*
X-86344Y135380D01*
X-85761Y135297D01*
X-85178Y135464D01*
X-84594Y135964D01*
G01X-80411Y135130D02*
X-80578Y135214D01*
Y135380D01*
X-80411Y135464D01*
X-80244Y135380D01*
Y135214D01*
X-80411Y135130D01*
G01X-165744Y146047D02*
X-165161Y145714D01*
X-164661Y145630D01*
X-163994Y145797D01*
X-163494Y146214D01*
X-163244Y146964D01*
Y150630D01*
G01Y151964D02*
X-163411Y152047D01*
Y152214D01*
X-163244Y152297D01*
X-163078Y152214D01*
Y152047D01*
X-163244Y151964D01*
G01X-160228Y150630D02*
Y148297D01*
X-159894Y147714D01*
X-159394Y147380D01*
X-158811Y147297D01*
X-158228Y147380D01*
X-157728Y147714D01*
X-157394Y148297D01*
G01Y147297D02*
Y150630D01*
G01X-154628Y147297D02*
Y150630D01*
G01Y149797D02*
X-154294Y150214D01*
X-153794Y150547D01*
X-153128Y150630D01*
X-152544Y150547D01*
X-152044Y150214D01*
X-151794Y149630D01*
Y147297D01*
G01X-146278Y150214D02*
X-146861Y150547D01*
X-147361Y150630D01*
X-148028Y150464D01*
X-148528Y150130D01*
X-148861Y149547D01*
X-148944Y148964D01*
X-148861Y148380D01*
X-148528Y147880D01*
X-148028Y147464D01*
X-147361Y147297D01*
X-146778Y147464D01*
X-146278Y147797D01*
G01X-142011Y152297D02*
Y147297D01*
G01X-143178Y150630D02*
X-140844D01*
G01X-136411D02*
Y147297D01*
G01Y151964D02*
X-136578Y152047D01*
Y152214D01*
X-136411Y152297D01*
X-136244Y152214D01*
Y152047D01*
X-136411Y151964D01*
G01X-130811Y147297D02*
X-131311Y147380D01*
X-131811Y147714D01*
X-132144Y148297D01*
X-132311Y148964D01*
X-132144Y149630D01*
X-131811Y150214D01*
X-131311Y150547D01*
X-130811Y150630D01*
X-130311Y150547D01*
X-129811Y150214D01*
X-129478Y149630D01*
X-129394Y148964D01*
X-129478Y148297D01*
X-129811Y147714D01*
X-130311Y147380D01*
X-130811Y147297D01*
G01X-126628D02*
Y150630D01*
G01Y149797D02*
X-126294Y150214D01*
X-125794Y150547D01*
X-125128Y150630D01*
X-124544Y150547D01*
X-124044Y150214D01*
X-123794Y149630D01*
Y147297D01*
G01X-115511D02*
Y152297D01*
G01Y149797D02*
X-115094Y150297D01*
X-114594Y150547D01*
X-114094Y150630D01*
X-113344Y150464D01*
X-112844Y150130D01*
X-112511Y149547D01*
Y148880D01*
X-112678Y148214D01*
X-113011Y147714D01*
X-113594Y147380D01*
X-114094Y147297D01*
X-114594Y147380D01*
X-115094Y147630D01*
X-115511Y148047D01*
G01X-109661Y149547D02*
X-106994D01*
X-107244Y150130D01*
X-107661Y150464D01*
X-108244Y150630D01*
X-108828Y150547D01*
X-109328Y150297D01*
X-109661Y149714D01*
X-109828Y149214D01*
Y148714D01*
X-109661Y148214D01*
X-109244Y147714D01*
X-108744Y147380D01*
X-108161Y147297D01*
X-107578Y147464D01*
X-106994Y147964D01*
G01X-102811Y147297D02*
Y152297D01*
G01X-97211Y147297D02*
X-97711Y147380D01*
X-98211Y147714D01*
X-98544Y148297D01*
X-98711Y148964D01*
X-98544Y149630D01*
X-98211Y150214D01*
X-97711Y150547D01*
X-97211Y150630D01*
X-96711Y150547D01*
X-96211Y150214D01*
X-95878Y149630D01*
X-95794Y148964D01*
X-95878Y148297D01*
X-96211Y147714D01*
X-96711Y147380D01*
X-97211Y147297D01*
G01X-93694Y150630D02*
X-92694Y147297D01*
X-91611Y150630D01*
X-90528Y147297D01*
X-89528Y150630D01*
G01X-80411Y152297D02*
Y147297D01*
G01X-81578Y150630D02*
X-79244D01*
G01X-76228Y147297D02*
Y152297D01*
G01Y149880D02*
X-75811Y150297D01*
X-75394Y150547D01*
X-74728Y150630D01*
X-74228Y150547D01*
X-73644Y150214D01*
X-73394Y149714D01*
Y147297D01*
G01X-70461Y149547D02*
X-67794D01*
X-68044Y150130D01*
X-68461Y150464D01*
X-69044Y150630D01*
X-69628Y150547D01*
X-70128Y150297D01*
X-70461Y149714D01*
X-70628Y149214D01*
Y148714D01*
X-70461Y148214D01*
X-70044Y147714D01*
X-69544Y147380D01*
X-68961Y147297D01*
X-68378Y147464D01*
X-67794Y147964D01*
G01X-60511Y147297D02*
Y150630D01*
G01Y149714D02*
X-60261Y150130D01*
X-59844Y150464D01*
X-59261Y150630D01*
X-58678Y150464D01*
X-58261Y150130D01*
X-58011Y149714D01*
Y147297D01*
G01Y149714D02*
X-57761Y150130D01*
X-57344Y150464D01*
X-56761Y150630D01*
X-56178Y150464D01*
X-55761Y150130D01*
X-55511Y149630D01*
Y147297D01*
G01X-52411Y150630D02*
Y147297D01*
G01Y151964D02*
X-52578Y152047D01*
Y152214D01*
X-52411Y152297D01*
X-52244Y152214D01*
Y152047D01*
X-52411Y151964D01*
G01X-48228Y147297D02*
Y150630D01*
G01Y149797D02*
X-47894Y150214D01*
X-47394Y150547D01*
X-46728Y150630D01*
X-46144Y150547D01*
X-45644Y150214D01*
X-45394Y149630D01*
Y147297D01*
G01X-34278Y150214D02*
X-34861Y150547D01*
X-35361Y150630D01*
X-36028Y150464D01*
X-36528Y150130D01*
X-36861Y149547D01*
X-36944Y148964D01*
X-36861Y148380D01*
X-36528Y147880D01*
X-36028Y147464D01*
X-35361Y147297D01*
X-34778Y147464D01*
X-34278Y147797D01*
G01X-30011Y147297D02*
X-30511Y147380D01*
X-31011Y147714D01*
X-31344Y148297D01*
X-31511Y148964D01*
X-31344Y149630D01*
X-31011Y150214D01*
X-30511Y150547D01*
X-30011Y150630D01*
X-29511Y150547D01*
X-29011Y150214D01*
X-28678Y149630D01*
X-28594Y148964D01*
X-28678Y148297D01*
X-29011Y147714D01*
X-29511Y147380D01*
X-30011Y147297D01*
G01X-25828D02*
Y150630D01*
G01Y149797D02*
X-25494Y150214D01*
X-24994Y150547D01*
X-24328Y150630D01*
X-23744Y150547D01*
X-23244Y150214D01*
X-22994Y149630D01*
Y147297D01*
G01X-17311Y152297D02*
Y147297D01*
G01Y148047D02*
X-17644Y147630D01*
X-18144Y147380D01*
X-18728Y147297D01*
X-19394Y147464D01*
X-19894Y147880D01*
X-20228Y148380D01*
X-20311Y148964D01*
X-20228Y149547D01*
X-19894Y150047D01*
X-19394Y150464D01*
X-18728Y150630D01*
X-18144Y150547D01*
X-17728Y150380D01*
X-17311Y150047D01*
G01X-14628Y150630D02*
Y148297D01*
X-14294Y147714D01*
X-13794Y147380D01*
X-13211Y147297D01*
X-12628Y147380D01*
X-12128Y147714D01*
X-11794Y148297D01*
G01Y147297D02*
Y150630D01*
G01X-6278Y150214D02*
X-6861Y150547D01*
X-7361Y150630D01*
X-8028Y150464D01*
X-8528Y150130D01*
X-8861Y149547D01*
X-8944Y148964D01*
X-8861Y148380D01*
X-8528Y147880D01*
X-8028Y147464D01*
X-7361Y147297D01*
X-6778Y147464D01*
X-6278Y147797D01*
G01X-2011Y152297D02*
Y147297D01*
G01X-3178Y150630D02*
X-844D01*
G01X3589Y147297D02*
X3089Y147380D01*
X2589Y147714D01*
X2256Y148297D01*
X2089Y148964D01*
X2256Y149630D01*
X2589Y150214D01*
X3089Y150547D01*
X3589Y150630D01*
X4089Y150547D01*
X4589Y150214D01*
X4922Y149630D01*
X5006Y148964D01*
X4922Y148297D01*
X4589Y147714D01*
X4089Y147380D01*
X3589Y147297D01*
G01X8022D02*
Y150630D01*
G01Y149964D02*
X8439Y150297D01*
X8856Y150547D01*
X9439Y150630D01*
X9856Y150547D01*
X10356Y150297D01*
G01X18306Y150630D02*
X19306Y147297D01*
X20389Y150630D01*
X21472Y147297D01*
X22472Y150630D01*
G01X25989D02*
Y147297D01*
G01Y151964D02*
X25822Y152047D01*
Y152214D01*
X25989Y152297D01*
X26156Y152214D01*
Y152047D01*
X25989Y151964D01*
G01X33089Y152297D02*
Y147297D01*
G01Y148047D02*
X32756Y147630D01*
X32256Y147380D01*
X31672Y147297D01*
X31006Y147464D01*
X30506Y147880D01*
X30172Y148380D01*
X30089Y148964D01*
X30172Y149547D01*
X30506Y150047D01*
X31006Y150464D01*
X31672Y150630D01*
X32256Y150547D01*
X32672Y150380D01*
X33089Y150047D01*
G01X37189Y152297D02*
Y147297D01*
G01X36022Y150630D02*
X38356D01*
G01X41372Y147297D02*
Y152297D01*
G01Y149880D02*
X41789Y150297D01*
X42206Y150547D01*
X42872Y150630D01*
X43372Y150547D01*
X43956Y150214D01*
X44206Y149714D01*
Y147297D01*
G01X52739Y147880D02*
X53156Y147547D01*
X53739Y147297D01*
X54239D01*
X54739Y147464D01*
X55072Y147714D01*
X55239Y148047D01*
X55156Y148547D01*
X54822Y148797D01*
X53322Y149297D01*
X52989Y149880D01*
X53156Y150297D01*
X53489Y150547D01*
X53989Y150630D01*
X54489Y150547D01*
X54989Y150297D01*
G01X58089Y145630D02*
Y150630D01*
G01Y149880D02*
X58506Y150297D01*
X58922Y150547D01*
X59589Y150630D01*
X60172Y150547D01*
X60756Y150130D01*
X61006Y149547D01*
X61089Y148964D01*
X61006Y148380D01*
X60756Y147797D01*
X60256Y147464D01*
X59589Y147297D01*
X59006Y147380D01*
X58422Y147630D01*
X58089Y147964D01*
G01X63939Y149547D02*
X66606D01*
X66356Y150130D01*
X65939Y150464D01*
X65356Y150630D01*
X64772Y150547D01*
X64272Y150297D01*
X63939Y149714D01*
X63772Y149214D01*
Y148714D01*
X63939Y148214D01*
X64356Y147714D01*
X64856Y147380D01*
X65439Y147297D01*
X66022Y147464D01*
X66606Y147964D01*
G01X72122Y150214D02*
X71539Y150547D01*
X71039Y150630D01*
X70372Y150464D01*
X69872Y150130D01*
X69539Y149547D01*
X69456Y148964D01*
X69539Y148380D01*
X69872Y147880D01*
X70372Y147464D01*
X71039Y147297D01*
X71622Y147464D01*
X72122Y147797D01*
G01X76389Y150630D02*
Y147297D01*
G01Y151964D02*
X76222Y152047D01*
Y152214D01*
X76389Y152297D01*
X76556Y152214D01*
Y152047D01*
X76389Y151964D01*
G01X81489Y147297D02*
Y151547D01*
X81656Y151964D01*
X81989Y152214D01*
X82489Y152297D01*
X82989Y152130D01*
X83239Y151714D01*
G01X82239Y150297D02*
X80572D01*
G01X87589Y150630D02*
Y147297D01*
G01Y151964D02*
X87422Y152047D01*
Y152214D01*
X87589Y152297D01*
X87756Y152214D01*
Y152047D01*
X87589Y151964D01*
G01X91939Y149547D02*
X94606D01*
X94356Y150130D01*
X93939Y150464D01*
X93356Y150630D01*
X92772Y150547D01*
X92272Y150297D01*
X91939Y149714D01*
X91772Y149214D01*
Y148714D01*
X91939Y148214D01*
X92356Y147714D01*
X92856Y147380D01*
X93439Y147297D01*
X94022Y147464D01*
X94606Y147964D01*
G01X100289Y152297D02*
Y147297D01*
G01Y148047D02*
X99956Y147630D01*
X99456Y147380D01*
X98872Y147297D01*
X98206Y147464D01*
X97706Y147880D01*
X97372Y148380D01*
X97289Y148964D01*
X97372Y149547D01*
X97706Y150047D01*
X98206Y150464D01*
X98872Y150630D01*
X99456Y150547D01*
X99872Y150380D01*
X100289Y150047D01*
G01X109989Y147297D02*
X109489Y147380D01*
X108989Y147714D01*
X108656Y148297D01*
X108489Y148964D01*
X108656Y149630D01*
X108989Y150214D01*
X109489Y150547D01*
X109989Y150630D01*
X110489Y150547D01*
X110989Y150214D01*
X111322Y149630D01*
X111406Y148964D01*
X111322Y148297D01*
X110989Y147714D01*
X110489Y147380D01*
X109989Y147297D01*
G01X114172D02*
Y150630D01*
G01Y149797D02*
X114506Y150214D01*
X115006Y150547D01*
X115672Y150630D01*
X116256Y150547D01*
X116756Y150214D01*
X117006Y149630D01*
Y147297D01*
G01X126789Y152297D02*
Y147297D01*
G01X125622Y150630D02*
X127956D01*
G01X130972Y147297D02*
Y152297D01*
G01Y149880D02*
X131389Y150297D01*
X131806Y150547D01*
X132472Y150630D01*
X132972Y150547D01*
X133556Y150214D01*
X133806Y149714D01*
Y147297D01*
G01X136739Y149547D02*
X139406D01*
X139156Y150130D01*
X138739Y150464D01*
X138156Y150630D01*
X137572Y150547D01*
X137072Y150297D01*
X136739Y149714D01*
X136572Y149214D01*
Y148714D01*
X136739Y148214D01*
X137156Y147714D01*
X137656Y147380D01*
X138239Y147297D01*
X138822Y147464D01*
X139406Y147964D01*
G01X-166161Y157797D02*
Y162797D01*
G01X-162661D02*
Y157797D01*
G01Y160297D02*
X-166161D01*
G01X-158811Y157797D02*
X-159311Y157880D01*
X-159811Y158214D01*
X-160144Y158797D01*
X-160311Y159464D01*
X-160144Y160130D01*
X-159811Y160714D01*
X-159311Y161047D01*
X-158811Y161130D01*
X-158311Y161047D01*
X-157811Y160714D01*
X-157478Y160130D01*
X-157394Y159464D01*
X-157478Y158797D01*
X-157811Y158214D01*
X-158311Y157880D01*
X-158811Y157797D01*
G01X-155294Y161130D02*
X-154294Y157797D01*
X-153211Y161130D01*
X-152128Y157797D01*
X-151128Y161130D01*
G01X-148861Y160047D02*
X-146194D01*
X-146444Y160630D01*
X-146861Y160964D01*
X-147444Y161130D01*
X-148028Y161047D01*
X-148528Y160797D01*
X-148861Y160214D01*
X-149028Y159714D01*
Y159214D01*
X-148861Y158714D01*
X-148444Y158214D01*
X-147944Y157880D01*
X-147361Y157797D01*
X-146778Y157964D01*
X-146194Y158464D01*
G01X-143511Y161130D02*
X-142011Y157797D01*
X-140511Y161130D01*
G01X-137661Y160047D02*
X-134994D01*
X-135244Y160630D01*
X-135661Y160964D01*
X-136244Y161130D01*
X-136828Y161047D01*
X-137328Y160797D01*
X-137661Y160214D01*
X-137828Y159714D01*
Y159214D01*
X-137661Y158714D01*
X-137244Y158214D01*
X-136744Y157880D01*
X-136161Y157797D01*
X-135578Y157964D01*
X-134994Y158464D01*
G01X-131978Y157797D02*
Y161130D01*
G01Y160464D02*
X-131561Y160797D01*
X-131144Y161047D01*
X-130561Y161130D01*
X-130144Y161047D01*
X-129644Y160797D01*
G01X-125378Y156880D02*
X-125044Y157964D01*
G01X-119611Y162797D02*
Y157797D01*
G01X-120778Y161130D02*
X-118444D01*
G01X-115428Y157797D02*
Y162797D01*
G01Y160380D02*
X-115011Y160797D01*
X-114594Y161047D01*
X-113928Y161130D01*
X-113428Y161047D01*
X-112844Y160714D01*
X-112594Y160214D01*
Y157797D01*
G01X-109661Y160047D02*
X-106994D01*
X-107244Y160630D01*
X-107661Y160964D01*
X-108244Y161130D01*
X-108828Y161047D01*
X-109328Y160797D01*
X-109661Y160214D01*
X-109828Y159714D01*
Y159214D01*
X-109661Y158714D01*
X-109244Y158214D01*
X-108744Y157880D01*
X-108161Y157797D01*
X-107578Y157964D01*
X-106994Y158464D01*
G01X-97211Y162797D02*
Y157797D01*
G01X-98378Y161130D02*
X-96044D01*
G01X-90111Y157797D02*
Y161130D01*
G01Y160547D02*
X-90444Y160880D01*
X-90944Y161047D01*
X-91528Y161130D01*
X-92111Y160964D01*
X-92611Y160630D01*
X-92944Y160130D01*
X-93111Y159464D01*
X-92944Y158797D01*
X-92611Y158297D01*
X-92111Y157964D01*
X-91528Y157797D01*
X-90944Y157880D01*
X-90444Y158130D01*
X-90111Y158464D01*
G01X-87428Y157797D02*
Y161130D01*
G01Y160297D02*
X-87094Y160714D01*
X-86594Y161047D01*
X-85928Y161130D01*
X-85344Y161047D01*
X-84844Y160714D01*
X-84594Y160130D01*
Y157797D01*
G01X-81578Y156547D02*
X-80994Y156214D01*
X-80328Y156130D01*
X-79744Y156214D01*
X-79244Y156630D01*
X-78911Y157214D01*
Y161130D01*
G01Y160464D02*
X-79244Y160797D01*
X-79744Y161047D01*
X-80328Y161130D01*
X-80994Y160964D01*
X-81411Y160630D01*
X-81744Y160047D01*
X-81911Y159464D01*
X-81828Y158964D01*
X-81494Y158380D01*
X-80994Y157964D01*
X-80328Y157797D01*
X-79828Y157880D01*
X-79244Y158214D01*
X-78911Y158547D01*
G01X-76061Y160047D02*
X-73394D01*
X-73644Y160630D01*
X-74061Y160964D01*
X-74644Y161130D01*
X-75228Y161047D01*
X-75728Y160797D01*
X-76061Y160214D01*
X-76228Y159714D01*
Y159214D01*
X-76061Y158714D01*
X-75644Y158214D01*
X-75144Y157880D01*
X-74561Y157797D01*
X-73978Y157964D01*
X-73394Y158464D01*
G01X-70628Y157797D02*
Y161130D01*
G01Y160297D02*
X-70294Y160714D01*
X-69794Y161047D01*
X-69128Y161130D01*
X-68544Y161047D01*
X-68044Y160714D01*
X-67794Y160130D01*
Y157797D01*
G01X-62278Y160714D02*
X-62861Y161047D01*
X-63361Y161130D01*
X-64028Y160964D01*
X-64528Y160630D01*
X-64861Y160047D01*
X-64944Y159464D01*
X-64861Y158880D01*
X-64528Y158380D01*
X-64028Y157964D01*
X-63361Y157797D01*
X-62778Y157964D01*
X-62278Y158297D01*
G01X-59761Y156297D02*
X-59261Y156130D01*
X-58594Y156297D01*
X-58178Y156630D01*
X-57844Y157047D01*
X-57344Y158380D01*
X-56261Y161130D01*
G01X-58928D02*
X-57344Y158380D01*
G01X-48061D02*
X-47644Y158047D01*
X-47061Y157797D01*
X-46561D01*
X-46061Y157964D01*
X-45728Y158214D01*
X-45561Y158547D01*
X-45644Y159047D01*
X-45978Y159297D01*
X-47478Y159797D01*
X-47811Y160380D01*
X-47644Y160797D01*
X-47311Y161047D01*
X-46811Y161130D01*
X-46311Y161047D01*
X-45811Y160797D01*
G01X-42628Y157797D02*
Y162797D01*
G01Y160380D02*
X-42211Y160797D01*
X-41794Y161047D01*
X-41128Y161130D01*
X-40628Y161047D01*
X-40044Y160714D01*
X-39794Y160214D01*
Y157797D01*
G01X-35611D02*
X-36111Y157880D01*
X-36611Y158214D01*
X-36944Y158797D01*
X-37111Y159464D01*
X-36944Y160130D01*
X-36611Y160714D01*
X-36111Y161047D01*
X-35611Y161130D01*
X-35111Y161047D01*
X-34611Y160714D01*
X-34278Y160130D01*
X-34194Y159464D01*
X-34278Y158797D01*
X-34611Y158214D01*
X-35111Y157880D01*
X-35611Y157797D01*
G01X-31428Y161130D02*
Y158797D01*
X-31094Y158214D01*
X-30594Y157880D01*
X-30011Y157797D01*
X-29428Y157880D01*
X-28928Y158214D01*
X-28594Y158797D01*
G01Y157797D02*
Y161130D01*
G01X-24411Y157797D02*
Y162797D01*
G01X-17311D02*
Y157797D01*
G01Y158547D02*
X-17644Y158130D01*
X-18144Y157880D01*
X-18728Y157797D01*
X-19394Y157964D01*
X-19894Y158380D01*
X-20228Y158880D01*
X-20311Y159464D01*
X-20228Y160047D01*
X-19894Y160547D01*
X-19394Y160964D01*
X-18728Y161130D01*
X-18144Y161047D01*
X-17728Y160880D01*
X-17311Y160547D01*
G01X-9028Y157797D02*
Y161130D01*
G01Y160297D02*
X-8694Y160714D01*
X-8194Y161047D01*
X-7528Y161130D01*
X-6944Y161047D01*
X-6444Y160714D01*
X-6194Y160130D01*
Y157797D01*
G01X-2011D02*
X-2511Y157880D01*
X-3011Y158214D01*
X-3344Y158797D01*
X-3511Y159464D01*
X-3344Y160130D01*
X-3011Y160714D01*
X-2511Y161047D01*
X-2011Y161130D01*
X-1511Y161047D01*
X-1011Y160714D01*
X-678Y160130D01*
X-594Y159464D01*
X-678Y158797D01*
X-1011Y158214D01*
X-1511Y157880D01*
X-2011Y157797D01*
G01X3589Y162797D02*
Y157797D01*
G01X2422Y161130D02*
X4756D01*
G01X13622Y157797D02*
Y161130D01*
G01Y160464D02*
X14039Y160797D01*
X14456Y161047D01*
X15039Y161130D01*
X15456Y161047D01*
X15956Y160797D01*
G01X19139Y160047D02*
X21806D01*
X21556Y160630D01*
X21139Y160964D01*
X20556Y161130D01*
X19972Y161047D01*
X19472Y160797D01*
X19139Y160214D01*
X18972Y159714D01*
Y159214D01*
X19139Y158714D01*
X19556Y158214D01*
X20056Y157880D01*
X20639Y157797D01*
X21222Y157964D01*
X21806Y158464D01*
G01X27489Y162797D02*
Y157797D01*
G01Y158547D02*
X27156Y158130D01*
X26656Y157880D01*
X26072Y157797D01*
X25406Y157964D01*
X24906Y158380D01*
X24572Y158880D01*
X24489Y159464D01*
X24572Y160047D01*
X24906Y160547D01*
X25406Y160964D01*
X26072Y161130D01*
X26656Y161047D01*
X27072Y160880D01*
X27489Y160547D01*
G01X30172Y161130D02*
Y158797D01*
X30506Y158214D01*
X31006Y157880D01*
X31589Y157797D01*
X32172Y157880D01*
X32672Y158214D01*
X33006Y158797D01*
G01Y157797D02*
Y161130D01*
G01X38522Y160714D02*
X37939Y161047D01*
X37439Y161130D01*
X36772Y160964D01*
X36272Y160630D01*
X35939Y160047D01*
X35856Y159464D01*
X35939Y158880D01*
X36272Y158380D01*
X36772Y157964D01*
X37439Y157797D01*
X38022Y157964D01*
X38522Y158297D01*
G01X41539Y160047D02*
X44206D01*
X43956Y160630D01*
X43539Y160964D01*
X42956Y161130D01*
X42372Y161047D01*
X41872Y160797D01*
X41539Y160214D01*
X41372Y159714D01*
Y159214D01*
X41539Y158714D01*
X41956Y158214D01*
X42456Y157880D01*
X43039Y157797D01*
X43622Y157964D01*
X44206Y158464D01*
G01X53989Y162797D02*
Y157797D01*
G01X52822Y161130D02*
X55156D01*
G01X58172Y157797D02*
Y162797D01*
G01Y160380D02*
X58589Y160797D01*
X59006Y161047D01*
X59672Y161130D01*
X60172Y161047D01*
X60756Y160714D01*
X61006Y160214D01*
Y157797D01*
G01X63939Y160047D02*
X66606D01*
X66356Y160630D01*
X65939Y160964D01*
X65356Y161130D01*
X64772Y161047D01*
X64272Y160797D01*
X63939Y160214D01*
X63772Y159714D01*
Y159214D01*
X63939Y158714D01*
X64356Y158214D01*
X64856Y157880D01*
X65439Y157797D01*
X66022Y157964D01*
X66606Y158464D01*
G01X76389Y157797D02*
Y162797D01*
G01X83489Y157797D02*
Y161130D01*
G01Y160547D02*
X83156Y160880D01*
X82656Y161047D01*
X82072Y161130D01*
X81489Y160964D01*
X80989Y160630D01*
X80656Y160130D01*
X80489Y159464D01*
X80656Y158797D01*
X80989Y158297D01*
X81489Y157964D01*
X82072Y157797D01*
X82656Y157880D01*
X83156Y158130D01*
X83489Y158464D01*
G01X86172Y157797D02*
Y161130D01*
G01Y160297D02*
X86506Y160714D01*
X87006Y161047D01*
X87672Y161130D01*
X88256Y161047D01*
X88756Y160714D01*
X89006Y160130D01*
Y157797D01*
G01X94689Y162797D02*
Y157797D01*
G01Y158547D02*
X94356Y158130D01*
X93856Y157880D01*
X93272Y157797D01*
X92606Y157964D01*
X92106Y158380D01*
X91772Y158880D01*
X91689Y159464D01*
X91772Y160047D01*
X92106Y160547D01*
X92606Y160964D01*
X93272Y161130D01*
X93856Y161047D01*
X94272Y160880D01*
X94689Y160547D01*
G01X97289Y157630D02*
X100289Y162797D01*
G01X105722Y160714D02*
X105139Y161047D01*
X104639Y161130D01*
X103972Y160964D01*
X103472Y160630D01*
X103139Y160047D01*
X103056Y159464D01*
X103139Y158880D01*
X103472Y158380D01*
X103972Y157964D01*
X104639Y157797D01*
X105222Y157964D01*
X105722Y158297D01*
G01X109989Y157797D02*
X109489Y157880D01*
X108989Y158214D01*
X108656Y158797D01*
X108489Y159464D01*
X108656Y160130D01*
X108989Y160714D01*
X109489Y161047D01*
X109989Y161130D01*
X110489Y161047D01*
X110989Y160714D01*
X111322Y160130D01*
X111406Y159464D01*
X111322Y158797D01*
X110989Y158214D01*
X110489Y157880D01*
X109989Y157797D01*
G01X114172D02*
Y161130D01*
G01Y160297D02*
X114506Y160714D01*
X115006Y161047D01*
X115672Y161130D01*
X116256Y161047D01*
X116756Y160714D01*
X117006Y160130D01*
Y157797D01*
G01X122689Y162797D02*
Y157797D01*
G01Y158547D02*
X122356Y158130D01*
X121856Y157880D01*
X121272Y157797D01*
X120606Y157964D01*
X120106Y158380D01*
X119772Y158880D01*
X119689Y159464D01*
X119772Y160047D01*
X120106Y160547D01*
X120606Y160964D01*
X121272Y161130D01*
X121856Y161047D01*
X122272Y160880D01*
X122689Y160547D01*
G01X125372Y161130D02*
Y158797D01*
X125706Y158214D01*
X126206Y157880D01*
X126789Y157797D01*
X127372Y157880D01*
X127872Y158214D01*
X128206Y158797D01*
G01Y157797D02*
Y161130D01*
G01X133722Y160714D02*
X133139Y161047D01*
X132639Y161130D01*
X131972Y160964D01*
X131472Y160630D01*
X131139Y160047D01*
X131056Y159464D01*
X131139Y158880D01*
X131472Y158380D01*
X131972Y157964D01*
X132639Y157797D01*
X133222Y157964D01*
X133722Y158297D01*
G01X137989Y162797D02*
Y157797D01*
G01X136822Y161130D02*
X139156D01*
G01X143589Y157797D02*
X143089Y157880D01*
X142589Y158214D01*
X142256Y158797D01*
X142089Y159464D01*
X142256Y160130D01*
X142589Y160714D01*
X143089Y161047D01*
X143589Y161130D01*
X144089Y161047D01*
X144589Y160714D01*
X144922Y160130D01*
X145006Y159464D01*
X144922Y158797D01*
X144589Y158214D01*
X144089Y157880D01*
X143589Y157797D01*
G01X148022D02*
Y161130D01*
G01Y160464D02*
X148439Y160797D01*
X148856Y161047D01*
X149439Y161130D01*
X149856Y161047D01*
X150356Y160797D01*
G01X-162911Y168297D02*
Y171630D01*
G01Y171047D02*
X-163244Y171380D01*
X-163744Y171547D01*
X-164328Y171630D01*
X-164911Y171464D01*
X-165411Y171130D01*
X-165744Y170630D01*
X-165911Y169964D01*
X-165744Y169297D01*
X-165411Y168797D01*
X-164911Y168464D01*
X-164328Y168297D01*
X-163744Y168380D01*
X-163244Y168630D01*
X-162911Y168964D01*
G01X-157478Y171214D02*
X-158061Y171547D01*
X-158561Y171630D01*
X-159228Y171464D01*
X-159728Y171130D01*
X-160061Y170547D01*
X-160144Y169964D01*
X-160061Y169380D01*
X-159728Y168880D01*
X-159228Y168464D01*
X-158561Y168297D01*
X-157978Y168464D01*
X-157478Y168797D01*
G01X-151878Y171214D02*
X-152461Y171547D01*
X-152961Y171630D01*
X-153628Y171464D01*
X-154128Y171130D01*
X-154461Y170547D01*
X-154544Y169964D01*
X-154461Y169380D01*
X-154128Y168880D01*
X-153628Y168464D01*
X-152961Y168297D01*
X-152378Y168464D01*
X-151878Y168797D01*
G01X-148861Y170547D02*
X-146194D01*
X-146444Y171130D01*
X-146861Y171464D01*
X-147444Y171630D01*
X-148028Y171547D01*
X-148528Y171297D01*
X-148861Y170714D01*
X-149028Y170214D01*
Y169714D01*
X-148861Y169214D01*
X-148444Y168714D01*
X-147944Y168380D01*
X-147361Y168297D01*
X-146778Y168464D01*
X-146194Y168964D01*
G01X-143511Y166630D02*
Y171630D01*
G01Y170880D02*
X-143094Y171297D01*
X-142678Y171547D01*
X-142011Y171630D01*
X-141428Y171547D01*
X-140844Y171130D01*
X-140594Y170547D01*
X-140511Y169964D01*
X-140594Y169380D01*
X-140844Y168797D01*
X-141344Y168464D01*
X-142011Y168297D01*
X-142594Y168380D01*
X-143178Y168630D01*
X-143511Y168964D01*
G01X-136411Y173297D02*
Y168297D01*
G01X-137578Y171630D02*
X-135244D01*
G01X-129311Y168297D02*
Y171630D01*
G01Y171047D02*
X-129644Y171380D01*
X-130144Y171547D01*
X-130728Y171630D01*
X-131311Y171464D01*
X-131811Y171130D01*
X-132144Y170630D01*
X-132311Y169964D01*
X-132144Y169297D01*
X-131811Y168797D01*
X-131311Y168464D01*
X-130728Y168297D01*
X-130144Y168380D01*
X-129644Y168630D01*
X-129311Y168964D01*
G01X-126711Y168297D02*
Y173297D01*
G01Y170797D02*
X-126294Y171297D01*
X-125794Y171547D01*
X-125294Y171630D01*
X-124544Y171464D01*
X-124044Y171130D01*
X-123711Y170547D01*
Y169880D01*
X-123878Y169214D01*
X-124211Y168714D01*
X-124794Y168380D01*
X-125294Y168297D01*
X-125794Y168380D01*
X-126294Y168630D01*
X-126711Y169047D01*
G01X-119611Y168297D02*
Y173297D01*
G01X-115261Y170547D02*
X-112594D01*
X-112844Y171130D01*
X-113261Y171464D01*
X-113844Y171630D01*
X-114428Y171547D01*
X-114928Y171297D01*
X-115261Y170714D01*
X-115428Y170214D01*
Y169714D01*
X-115261Y169214D01*
X-114844Y168714D01*
X-114344Y168380D01*
X-113761Y168297D01*
X-113178Y168464D01*
X-112594Y168964D01*
G01X-108411Y168130D02*
X-108578Y168214D01*
Y168380D01*
X-108411Y168464D01*
X-108244Y168380D01*
Y168214D01*
X-108411Y168130D01*
G01X-171911Y163297D02*
Y445297D01*
G01X-164411Y183797D02*
Y178797D01*
G01X-166328Y183797D02*
X-162494D01*
G01X-160228Y178797D02*
Y183797D01*
G01Y181380D02*
X-159811Y181797D01*
X-159394Y182047D01*
X-158728Y182130D01*
X-158228Y182047D01*
X-157644Y181714D01*
X-157394Y181214D01*
Y178797D01*
G01X-154461Y181047D02*
X-151794D01*
X-152044Y181630D01*
X-152461Y181964D01*
X-153044Y182130D01*
X-153628Y182047D01*
X-154128Y181797D01*
X-154461Y181214D01*
X-154628Y180714D01*
Y180214D01*
X-154461Y179714D01*
X-154044Y179214D01*
X-153544Y178880D01*
X-152961Y178797D01*
X-152378Y178964D01*
X-151794Y179464D01*
G01X-143511Y178797D02*
Y183797D01*
G01Y181297D02*
X-143094Y181797D01*
X-142594Y182047D01*
X-142094Y182130D01*
X-141344Y181964D01*
X-140844Y181630D01*
X-140511Y181047D01*
Y180380D01*
X-140678Y179714D01*
X-141011Y179214D01*
X-141594Y178880D01*
X-142094Y178797D01*
X-142594Y178880D01*
X-143094Y179130D01*
X-143511Y179547D01*
G01X-137578Y178797D02*
Y182130D01*
G01Y181464D02*
X-137161Y181797D01*
X-136744Y182047D01*
X-136161Y182130D01*
X-135744Y182047D01*
X-135244Y181797D01*
G01X-132061Y181047D02*
X-129394D01*
X-129644Y181630D01*
X-130061Y181964D01*
X-130644Y182130D01*
X-131228Y182047D01*
X-131728Y181797D01*
X-132061Y181214D01*
X-132228Y180714D01*
Y180214D01*
X-132061Y179714D01*
X-131644Y179214D01*
X-131144Y178880D01*
X-130561Y178797D01*
X-129978Y178964D01*
X-129394Y179464D01*
G01X-123711Y178797D02*
Y182130D01*
G01Y181547D02*
X-124044Y181880D01*
X-124544Y182047D01*
X-125128Y182130D01*
X-125711Y181964D01*
X-126211Y181630D01*
X-126544Y181130D01*
X-126711Y180464D01*
X-126544Y179797D01*
X-126211Y179297D01*
X-125711Y178964D01*
X-125128Y178797D01*
X-124544Y178880D01*
X-124044Y179130D01*
X-123711Y179464D01*
G01X-121028Y178797D02*
Y183797D01*
G01X-118361Y182130D02*
X-121028Y180214D01*
G01X-119944Y180964D02*
X-118194Y178797D01*
G01X-114011D02*
X-114511Y178880D01*
X-115011Y179214D01*
X-115344Y179797D01*
X-115511Y180464D01*
X-115344Y181130D01*
X-115011Y181714D01*
X-114511Y182047D01*
X-114011Y182130D01*
X-113511Y182047D01*
X-113011Y181714D01*
X-112678Y181130D01*
X-112594Y180464D01*
X-112678Y179797D01*
X-113011Y179214D01*
X-113511Y178880D01*
X-114011Y178797D01*
G01X-109828Y182130D02*
Y179797D01*
X-109494Y179214D01*
X-108994Y178880D01*
X-108411Y178797D01*
X-107828Y178880D01*
X-107328Y179214D01*
X-106994Y179797D01*
G01Y178797D02*
Y182130D01*
G01X-102811Y183797D02*
Y178797D01*
G01X-103978Y182130D02*
X-101644D01*
G01X-91611D02*
Y178797D01*
G01Y183464D02*
X-91778Y183547D01*
Y183714D01*
X-91611Y183797D01*
X-91444Y183714D01*
Y183547D01*
X-91611Y183464D01*
G01X-87261Y179380D02*
X-86844Y179047D01*
X-86261Y178797D01*
X-85761D01*
X-85261Y178964D01*
X-84928Y179214D01*
X-84761Y179547D01*
X-84844Y180047D01*
X-85178Y180297D01*
X-86678Y180797D01*
X-87011Y181380D01*
X-86844Y181797D01*
X-86511Y182047D01*
X-86011Y182130D01*
X-85511Y182047D01*
X-85011Y181797D01*
G01X-76228Y178797D02*
Y182130D01*
G01Y181297D02*
X-75894Y181714D01*
X-75394Y182047D01*
X-74728Y182130D01*
X-74144Y182047D01*
X-73644Y181714D01*
X-73394Y181130D01*
Y178797D01*
G01X-69211D02*
X-69711Y178880D01*
X-70211Y179214D01*
X-70544Y179797D01*
X-70711Y180464D01*
X-70544Y181130D01*
X-70211Y181714D01*
X-69711Y182047D01*
X-69211Y182130D01*
X-68711Y182047D01*
X-68211Y181714D01*
X-67878Y181130D01*
X-67794Y180464D01*
X-67878Y179797D01*
X-68211Y179214D01*
X-68711Y178880D01*
X-69211Y178797D01*
G01X-63611Y183797D02*
Y178797D01*
G01X-64778Y182130D02*
X-62444D01*
G01X-50911Y178797D02*
Y182130D01*
G01Y181547D02*
X-51244Y181880D01*
X-51744Y182047D01*
X-52328Y182130D01*
X-52911Y181964D01*
X-53411Y181630D01*
X-53744Y181130D01*
X-53911Y180464D01*
X-53744Y179797D01*
X-53411Y179297D01*
X-52911Y178964D01*
X-52328Y178797D01*
X-51744Y178880D01*
X-51244Y179130D01*
X-50911Y179464D01*
G01X-46811Y178797D02*
Y183797D01*
G01X-41211Y178797D02*
Y183797D01*
G01X-35611Y178797D02*
X-36111Y178880D01*
X-36611Y179214D01*
X-36944Y179797D01*
X-37111Y180464D01*
X-36944Y181130D01*
X-36611Y181714D01*
X-36111Y182047D01*
X-35611Y182130D01*
X-35111Y182047D01*
X-34611Y181714D01*
X-34278Y181130D01*
X-34194Y180464D01*
X-34278Y179797D01*
X-34611Y179214D01*
X-35111Y178880D01*
X-35611Y178797D01*
G01X-32094Y182130D02*
X-31094Y178797D01*
X-30011Y182130D01*
X-28928Y178797D01*
X-27928Y182130D01*
G01X-25661Y181047D02*
X-22994D01*
X-23244Y181630D01*
X-23661Y181964D01*
X-24244Y182130D01*
X-24828Y182047D01*
X-25328Y181797D01*
X-25661Y181214D01*
X-25828Y180714D01*
Y180214D01*
X-25661Y179714D01*
X-25244Y179214D01*
X-24744Y178880D01*
X-24161Y178797D01*
X-23578Y178964D01*
X-22994Y179464D01*
G01X-17311Y183797D02*
Y178797D01*
G01Y179547D02*
X-17644Y179130D01*
X-18144Y178880D01*
X-18728Y178797D01*
X-19394Y178964D01*
X-19894Y179380D01*
X-20228Y179880D01*
X-20311Y180464D01*
X-20228Y181047D01*
X-19894Y181547D01*
X-19394Y181964D01*
X-18728Y182130D01*
X-18144Y182047D01*
X-17728Y181880D01*
X-17311Y181547D01*
G01X-13378Y177880D02*
X-13044Y178964D01*
G01X2089Y178797D02*
Y183797D01*
G01Y181297D02*
X2506Y181797D01*
X3006Y182047D01*
X3506Y182130D01*
X4256Y181964D01*
X4756Y181630D01*
X5089Y181047D01*
Y180380D01*
X4922Y179714D01*
X4589Y179214D01*
X4006Y178880D01*
X3506Y178797D01*
X3006Y178880D01*
X2506Y179130D01*
X2089Y179547D01*
G01X7772Y182130D02*
Y179797D01*
X8106Y179214D01*
X8606Y178880D01*
X9189Y178797D01*
X9772Y178880D01*
X10272Y179214D01*
X10606Y179797D01*
G01Y178797D02*
Y182130D01*
G01X14789Y183797D02*
Y178797D01*
G01X13622Y182130D02*
X15956D01*
G01X27489Y178797D02*
Y182130D01*
G01Y181547D02*
X27156Y181880D01*
X26656Y182047D01*
X26072Y182130D01*
X25489Y181964D01*
X24989Y181630D01*
X24656Y181130D01*
X24489Y180464D01*
X24656Y179797D01*
X24989Y179297D01*
X25489Y178964D01*
X26072Y178797D01*
X26656Y178880D01*
X27156Y179130D01*
X27489Y179464D01*
G01X30172Y178797D02*
Y182130D01*
G01Y181297D02*
X30506Y181714D01*
X31006Y182047D01*
X31672Y182130D01*
X32256Y182047D01*
X32756Y181714D01*
X33006Y181130D01*
Y178797D01*
G01X35772D02*
Y182130D01*
G01Y181297D02*
X36106Y181714D01*
X36606Y182047D01*
X37272Y182130D01*
X37856Y182047D01*
X38356Y181714D01*
X38606Y181130D01*
Y178797D01*
G01X41372Y182130D02*
Y179797D01*
X41706Y179214D01*
X42206Y178880D01*
X42789Y178797D01*
X43372Y178880D01*
X43872Y179214D01*
X44206Y179797D01*
G01Y178797D02*
Y182130D01*
G01X49889Y178797D02*
Y182130D01*
G01Y181547D02*
X49556Y181880D01*
X49056Y182047D01*
X48472Y182130D01*
X47889Y181964D01*
X47389Y181630D01*
X47056Y181130D01*
X46889Y180464D01*
X47056Y179797D01*
X47389Y179297D01*
X47889Y178964D01*
X48472Y178797D01*
X49056Y178880D01*
X49556Y179130D01*
X49889Y179464D01*
G01X53989Y178797D02*
Y183797D01*
G01X64022Y178797D02*
Y182130D01*
G01Y181464D02*
X64439Y181797D01*
X64856Y182047D01*
X65439Y182130D01*
X65856Y182047D01*
X66356Y181797D01*
G01X70789Y182130D02*
Y178797D01*
G01Y183464D02*
X70622Y183547D01*
Y183714D01*
X70789Y183797D01*
X70956Y183714D01*
Y183547D01*
X70789Y183464D01*
G01X74972Y178797D02*
Y182130D01*
G01Y181297D02*
X75306Y181714D01*
X75806Y182047D01*
X76472Y182130D01*
X77056Y182047D01*
X77556Y181714D01*
X77806Y181130D01*
Y178797D01*
G01X80822Y177547D02*
X81406Y177214D01*
X82072Y177130D01*
X82656Y177214D01*
X83156Y177630D01*
X83489Y178214D01*
Y182130D01*
G01Y181464D02*
X83156Y181797D01*
X82656Y182047D01*
X82072Y182130D01*
X81406Y181964D01*
X80989Y181630D01*
X80656Y181047D01*
X80489Y180464D01*
X80572Y179964D01*
X80906Y179380D01*
X81406Y178964D01*
X82072Y178797D01*
X82572Y178880D01*
X83156Y179214D01*
X83489Y179547D01*
G01X93189Y183797D02*
Y178797D01*
G01X92022Y182130D02*
X94356D01*
G01X100289Y178797D02*
Y182130D01*
G01Y181547D02*
X99956Y181880D01*
X99456Y182047D01*
X98872Y182130D01*
X98289Y181964D01*
X97789Y181630D01*
X97456Y181130D01*
X97289Y180464D01*
X97456Y179797D01*
X97789Y179297D01*
X98289Y178964D01*
X98872Y178797D01*
X99456Y178880D01*
X99956Y179130D01*
X100289Y179464D01*
G01X102972Y178797D02*
Y182130D01*
G01Y181297D02*
X103306Y181714D01*
X103806Y182047D01*
X104472Y182130D01*
X105056Y182047D01*
X105556Y181714D01*
X105806Y181130D01*
Y178797D01*
G01X108822Y177547D02*
X109406Y177214D01*
X110072Y177130D01*
X110656Y177214D01*
X111156Y177630D01*
X111489Y178214D01*
Y182130D01*
G01Y181464D02*
X111156Y181797D01*
X110656Y182047D01*
X110072Y182130D01*
X109406Y181964D01*
X108989Y181630D01*
X108656Y181047D01*
X108489Y180464D01*
X108572Y179964D01*
X108906Y179380D01*
X109406Y178964D01*
X110072Y178797D01*
X110572Y178880D01*
X111156Y179214D01*
X111489Y179547D01*
G01X114339Y181047D02*
X117006D01*
X116756Y181630D01*
X116339Y181964D01*
X115756Y182130D01*
X115172Y182047D01*
X114672Y181797D01*
X114339Y181214D01*
X114172Y180714D01*
Y180214D01*
X114339Y179714D01*
X114756Y179214D01*
X115256Y178880D01*
X115839Y178797D01*
X116422Y178964D01*
X117006Y179464D01*
G01X119772Y178797D02*
Y182130D01*
G01Y181297D02*
X120106Y181714D01*
X120606Y182047D01*
X121272Y182130D01*
X121856Y182047D01*
X122356Y181714D01*
X122606Y181130D01*
Y178797D01*
G01X128122Y181714D02*
X127539Y182047D01*
X127039Y182130D01*
X126372Y181964D01*
X125872Y181630D01*
X125539Y181047D01*
X125456Y180464D01*
X125539Y179880D01*
X125872Y179380D01*
X126372Y178964D01*
X127039Y178797D01*
X127622Y178964D01*
X128122Y179297D01*
G01X130639Y177297D02*
X131139Y177130D01*
X131806Y177297D01*
X132222Y177630D01*
X132556Y178047D01*
X133056Y179380D01*
X134139Y182130D01*
G01X131472D02*
X133056Y179380D01*
G01X143589Y182130D02*
Y178797D01*
G01Y183464D02*
X143422Y183547D01*
Y183714D01*
X143589Y183797D01*
X143756Y183714D01*
Y183547D01*
X143589Y183464D01*
G01X147939Y179380D02*
X148356Y179047D01*
X148939Y178797D01*
X149439D01*
X149939Y178964D01*
X150272Y179214D01*
X150439Y179547D01*
X150356Y180047D01*
X150022Y180297D01*
X148522Y180797D01*
X148189Y181380D01*
X148356Y181797D01*
X148689Y182047D01*
X149189Y182130D01*
X149689Y182047D01*
X150189Y181797D01*
G01X-161411Y203797D02*
Y198797D01*
G01Y199547D02*
X-161744Y199130D01*
X-162244Y198880D01*
X-162828Y198797D01*
X-163494Y198964D01*
X-163994Y199380D01*
X-164328Y199880D01*
X-164411Y200464D01*
X-164328Y201047D01*
X-163994Y201547D01*
X-163494Y201964D01*
X-162828Y202130D01*
X-162244Y202047D01*
X-161828Y201880D01*
X-161411Y201547D01*
G01X-158561Y201047D02*
X-155894D01*
X-156144Y201630D01*
X-156561Y201964D01*
X-157144Y202130D01*
X-157728Y202047D01*
X-158228Y201797D01*
X-158561Y201214D01*
X-158728Y200714D01*
Y200214D01*
X-158561Y199714D01*
X-158144Y199214D01*
X-157644Y198880D01*
X-157061Y198797D01*
X-156478Y198964D01*
X-155894Y199464D01*
G01X-153211Y197130D02*
Y202130D01*
G01Y201380D02*
X-152794Y201797D01*
X-152378Y202047D01*
X-151711Y202130D01*
X-151128Y202047D01*
X-150544Y201630D01*
X-150294Y201047D01*
X-150211Y200464D01*
X-150294Y199880D01*
X-150544Y199297D01*
X-151044Y198964D01*
X-151711Y198797D01*
X-152294Y198880D01*
X-152878Y199130D01*
X-153211Y199464D01*
G01X-146111Y203797D02*
Y198797D01*
G01X-147278Y202130D02*
X-144944D01*
G01X-141928Y198797D02*
Y203797D01*
G01Y201380D02*
X-141511Y201797D01*
X-141094Y202047D01*
X-140428Y202130D01*
X-139928Y202047D01*
X-139344Y201714D01*
X-139094Y201214D01*
Y198797D01*
G01X-129311Y203797D02*
Y198797D01*
G01X-130478Y202130D02*
X-128144D01*
G01X-123711Y198797D02*
X-124211Y198880D01*
X-124711Y199214D01*
X-125044Y199797D01*
X-125211Y200464D01*
X-125044Y201130D01*
X-124711Y201714D01*
X-124211Y202047D01*
X-123711Y202130D01*
X-123211Y202047D01*
X-122711Y201714D01*
X-122378Y201130D01*
X-122294Y200464D01*
X-122378Y199797D01*
X-122711Y199214D01*
X-123211Y198880D01*
X-123711Y198797D01*
G01X-118111D02*
Y203797D01*
G01X-113761Y201047D02*
X-111094D01*
X-111344Y201630D01*
X-111761Y201964D01*
X-112344Y202130D01*
X-112928Y202047D01*
X-113428Y201797D01*
X-113761Y201214D01*
X-113928Y200714D01*
Y200214D01*
X-113761Y199714D01*
X-113344Y199214D01*
X-112844Y198880D01*
X-112261Y198797D01*
X-111678Y198964D01*
X-111094Y199464D01*
G01X-108078Y198797D02*
Y202130D01*
G01Y201464D02*
X-107661Y201797D01*
X-107244Y202047D01*
X-106661Y202130D01*
X-106244Y202047D01*
X-105744Y201797D01*
G01X-99811Y198797D02*
Y202130D01*
G01Y201547D02*
X-100144Y201880D01*
X-100644Y202047D01*
X-101228Y202130D01*
X-101811Y201964D01*
X-102311Y201630D01*
X-102644Y201130D01*
X-102811Y200464D01*
X-102644Y199797D01*
X-102311Y199297D01*
X-101811Y198964D01*
X-101228Y198797D01*
X-100644Y198880D01*
X-100144Y199130D01*
X-99811Y199464D01*
G01X-97128Y198797D02*
Y202130D01*
G01Y201297D02*
X-96794Y201714D01*
X-96294Y202047D01*
X-95628Y202130D01*
X-95044Y202047D01*
X-94544Y201714D01*
X-94294Y201130D01*
Y198797D01*
G01X-88778Y201714D02*
X-89361Y202047D01*
X-89861Y202130D01*
X-90528Y201964D01*
X-91028Y201630D01*
X-91361Y201047D01*
X-91444Y200464D01*
X-91361Y199880D01*
X-91028Y199380D01*
X-90528Y198964D01*
X-89861Y198797D01*
X-89278Y198964D01*
X-88778Y199297D01*
G01X-85761Y201047D02*
X-83094D01*
X-83344Y201630D01*
X-83761Y201964D01*
X-84344Y202130D01*
X-84928Y202047D01*
X-85428Y201797D01*
X-85761Y201214D01*
X-85928Y200714D01*
Y200214D01*
X-85761Y199714D01*
X-85344Y199214D01*
X-84844Y198880D01*
X-84261Y198797D01*
X-83678Y198964D01*
X-83094Y199464D01*
G01X-163661Y219797D02*
Y224797D01*
G01X-160161D02*
Y219797D01*
G01Y222297D02*
X-163661D01*
G01X-156311Y219797D02*
X-156811Y219880D01*
X-157311Y220214D01*
X-157644Y220797D01*
X-157811Y221464D01*
X-157644Y222130D01*
X-157311Y222714D01*
X-156811Y223047D01*
X-156311Y223130D01*
X-155811Y223047D01*
X-155311Y222714D01*
X-154978Y222130D01*
X-154894Y221464D01*
X-154978Y220797D01*
X-155311Y220214D01*
X-155811Y219880D01*
X-156311Y219797D01*
G01X-150711D02*
Y224797D01*
G01X-146361Y222047D02*
X-143694D01*
X-143944Y222630D01*
X-144361Y222964D01*
X-144944Y223130D01*
X-145528Y223047D01*
X-146028Y222797D01*
X-146361Y222214D01*
X-146528Y221714D01*
Y221214D01*
X-146361Y220714D01*
X-145944Y220214D01*
X-145444Y219880D01*
X-144861Y219797D01*
X-144278Y219964D01*
X-143694Y220464D01*
G01X-136411Y224797D02*
X-135244Y219797D01*
X-133911Y224797D01*
X-132578Y219797D01*
X-131411Y224797D01*
G01X-126811Y219797D02*
Y223130D01*
G01Y222547D02*
X-127144Y222880D01*
X-127644Y223047D01*
X-128228Y223130D01*
X-128811Y222964D01*
X-129311Y222630D01*
X-129644Y222130D01*
X-129811Y221464D01*
X-129644Y220797D01*
X-129311Y220297D01*
X-128811Y219964D01*
X-128228Y219797D01*
X-127644Y219880D01*
X-127144Y220130D01*
X-126811Y220464D01*
G01X-122711Y219797D02*
Y224797D01*
G01X-117111Y219797D02*
Y224797D01*
G01X-107578Y219797D02*
Y224797D01*
X-105494D01*
X-104828Y224547D01*
X-104411Y224214D01*
X-104244Y223547D01*
X-104411Y222880D01*
X-104911Y222464D01*
X-105494Y222214D01*
X-107578D01*
G01X-105494D02*
X-104244Y219797D01*
G01X-100311D02*
X-100811Y219880D01*
X-101311Y220214D01*
X-101644Y220797D01*
X-101811Y221464D01*
X-101644Y222130D01*
X-101311Y222714D01*
X-100811Y223047D01*
X-100311Y223130D01*
X-99811Y223047D01*
X-99311Y222714D01*
X-98978Y222130D01*
X-98894Y221464D01*
X-98978Y220797D01*
X-99311Y220214D01*
X-99811Y219880D01*
X-100311Y219797D01*
G01X-96128Y223130D02*
Y220797D01*
X-95794Y220214D01*
X-95294Y219880D01*
X-94711Y219797D01*
X-94128Y219880D01*
X-93628Y220214D01*
X-93294Y220797D01*
G01Y219797D02*
Y223130D01*
G01X-90278Y218547D02*
X-89694Y218214D01*
X-89028Y218130D01*
X-88444Y218214D01*
X-87944Y218630D01*
X-87611Y219214D01*
Y223130D01*
G01Y222464D02*
X-87944Y222797D01*
X-88444Y223047D01*
X-89028Y223130D01*
X-89694Y222964D01*
X-90111Y222630D01*
X-90444Y222047D01*
X-90611Y221464D01*
X-90528Y220964D01*
X-90194Y220380D01*
X-89694Y219964D01*
X-89028Y219797D01*
X-88528Y219880D01*
X-87944Y220214D01*
X-87611Y220547D01*
G01X-84928Y219797D02*
Y224797D01*
G01Y222380D02*
X-84511Y222797D01*
X-84094Y223047D01*
X-83428Y223130D01*
X-82928Y223047D01*
X-82344Y222714D01*
X-82094Y222214D01*
Y219797D01*
G01X-79328D02*
Y223130D01*
G01Y222297D02*
X-78994Y222714D01*
X-78494Y223047D01*
X-77828Y223130D01*
X-77244Y223047D01*
X-76744Y222714D01*
X-76494Y222130D01*
Y219797D01*
G01X-73561Y222047D02*
X-70894D01*
X-71144Y222630D01*
X-71561Y222964D01*
X-72144Y223130D01*
X-72728Y223047D01*
X-73228Y222797D01*
X-73561Y222214D01*
X-73728Y221714D01*
Y221214D01*
X-73561Y220714D01*
X-73144Y220214D01*
X-72644Y219880D01*
X-72061Y219797D01*
X-71478Y219964D01*
X-70894Y220464D01*
G01X-67961Y220380D02*
X-67544Y220047D01*
X-66961Y219797D01*
X-66461D01*
X-65961Y219964D01*
X-65628Y220214D01*
X-65461Y220547D01*
X-65544Y221047D01*
X-65878Y221297D01*
X-67378Y221797D01*
X-67711Y222380D01*
X-67544Y222797D01*
X-67211Y223047D01*
X-66711Y223130D01*
X-66211Y223047D01*
X-65711Y222797D01*
G01X-62361Y220380D02*
X-61944Y220047D01*
X-61361Y219797D01*
X-60861D01*
X-60361Y219964D01*
X-60028Y220214D01*
X-59861Y220547D01*
X-59944Y221047D01*
X-60278Y221297D01*
X-61778Y221797D01*
X-62111Y222380D01*
X-61944Y222797D01*
X-61611Y223047D01*
X-61111Y223130D01*
X-60611Y223047D01*
X-60111Y222797D01*
G01X-161911Y236297D02*
X-162578Y236380D01*
X-163161Y236714D01*
X-163661Y237214D01*
X-163994Y237797D01*
X-164161Y238464D01*
Y239130D01*
X-163994Y239797D01*
X-163661Y240380D01*
X-163161Y240880D01*
X-162578Y241214D01*
X-161911Y241297D01*
X-161244Y241214D01*
X-160661Y240880D01*
X-160161Y240380D01*
X-159828Y239797D01*
X-159661Y239130D01*
Y238464D01*
X-159828Y237797D01*
X-160161Y237214D01*
X-160661Y236714D01*
X-161244Y236380D01*
X-161911Y236297D01*
G01X-156311Y241297D02*
Y236297D01*
G01X-157478Y239630D02*
X-155144D01*
G01X-152128Y236297D02*
Y241297D01*
G01Y238880D02*
X-151711Y239297D01*
X-151294Y239547D01*
X-150628Y239630D01*
X-150128Y239547D01*
X-149544Y239214D01*
X-149294Y238714D01*
Y236297D01*
G01X-146361Y238547D02*
X-143694D01*
X-143944Y239130D01*
X-144361Y239464D01*
X-144944Y239630D01*
X-145528Y239547D01*
X-146028Y239297D01*
X-146361Y238714D01*
X-146528Y238214D01*
Y237714D01*
X-146361Y237214D01*
X-145944Y236714D01*
X-145444Y236380D01*
X-144861Y236297D01*
X-144278Y236464D01*
X-143694Y236964D01*
G01X-140678Y236297D02*
Y239630D01*
G01Y238964D02*
X-140261Y239297D01*
X-139844Y239547D01*
X-139261Y239630D01*
X-138844Y239547D01*
X-138344Y239297D01*
G01X-135161Y236880D02*
X-134744Y236547D01*
X-134161Y236297D01*
X-133661D01*
X-133161Y236464D01*
X-132828Y236714D01*
X-132661Y237047D01*
X-132744Y237547D01*
X-133078Y237797D01*
X-134578Y238297D01*
X-134911Y238880D01*
X-134744Y239297D01*
X-134411Y239547D01*
X-133911Y239630D01*
X-133411Y239547D01*
X-132911Y239297D01*
G01X-123128Y234630D02*
X-123961Y235464D01*
X-124378Y236297D01*
Y239630D01*
X-123961Y240464D01*
X-123128Y241297D01*
G01X-117111Y236297D02*
Y241297D01*
G01X-111511Y239630D02*
Y236297D01*
G01Y240964D02*
X-111678Y241047D01*
Y241214D01*
X-111511Y241297D01*
X-111344Y241214D01*
Y241047D01*
X-111511Y240964D01*
G01X-107328Y236297D02*
Y241297D01*
G01X-104661Y239630D02*
X-107328Y237714D01*
G01X-106244Y238464D02*
X-104494Y236297D01*
G01X-101561Y238547D02*
X-98894D01*
X-99144Y239130D01*
X-99561Y239464D01*
X-100144Y239630D01*
X-100728Y239547D01*
X-101228Y239297D01*
X-101561Y238714D01*
X-101728Y238214D01*
Y237714D01*
X-101561Y237214D01*
X-101144Y236714D01*
X-100644Y236380D01*
X-100061Y236297D01*
X-99478Y236464D01*
X-98894Y236964D01*
G01X-90361Y238547D02*
X-87694D01*
X-87944Y239130D01*
X-88361Y239464D01*
X-88944Y239630D01*
X-89528Y239547D01*
X-90028Y239297D01*
X-90361Y238714D01*
X-90528Y238214D01*
Y237714D01*
X-90361Y237214D01*
X-89944Y236714D01*
X-89444Y236380D01*
X-88861Y236297D01*
X-88278Y236464D01*
X-87694Y236964D01*
G01X-83511Y236297D02*
Y241297D01*
G01X-77911Y236297D02*
Y241297D01*
G01X-72311Y239630D02*
Y236297D01*
G01Y240964D02*
X-72478Y241047D01*
Y241214D01*
X-72311Y241297D01*
X-72144Y241214D01*
Y241047D01*
X-72311Y240964D01*
G01X-68211Y234630D02*
Y239630D01*
G01Y238880D02*
X-67794Y239297D01*
X-67378Y239547D01*
X-66711Y239630D01*
X-66128Y239547D01*
X-65544Y239130D01*
X-65294Y238547D01*
X-65211Y237964D01*
X-65294Y237380D01*
X-65544Y236797D01*
X-66044Y236464D01*
X-66711Y236297D01*
X-67294Y236380D01*
X-67878Y236630D01*
X-68211Y236964D01*
G01X-62361Y236880D02*
X-61944Y236547D01*
X-61361Y236297D01*
X-60861D01*
X-60361Y236464D01*
X-60028Y236714D01*
X-59861Y237047D01*
X-59944Y237547D01*
X-60278Y237797D01*
X-61778Y238297D01*
X-62111Y238880D01*
X-61944Y239297D01*
X-61611Y239547D01*
X-61111Y239630D01*
X-60611Y239547D01*
X-60111Y239297D01*
G01X-56761Y238547D02*
X-54094D01*
X-54344Y239130D01*
X-54761Y239464D01*
X-55344Y239630D01*
X-55928Y239547D01*
X-56428Y239297D01*
X-56761Y238714D01*
X-56928Y238214D01*
Y237714D01*
X-56761Y237214D01*
X-56344Y236714D01*
X-55844Y236380D01*
X-55261Y236297D01*
X-54678Y236464D01*
X-54094Y236964D01*
G01X-42811Y236297D02*
Y239630D01*
G01Y239047D02*
X-43144Y239380D01*
X-43644Y239547D01*
X-44228Y239630D01*
X-44811Y239464D01*
X-45311Y239130D01*
X-45644Y238630D01*
X-45811Y237964D01*
X-45644Y237297D01*
X-45311Y236797D01*
X-44811Y236464D01*
X-44228Y236297D01*
X-43644Y236380D01*
X-43144Y236630D01*
X-42811Y236964D01*
G01X-40128Y236297D02*
Y239630D01*
G01Y238797D02*
X-39794Y239214D01*
X-39294Y239547D01*
X-38628Y239630D01*
X-38044Y239547D01*
X-37544Y239214D01*
X-37294Y238630D01*
Y236297D01*
G01X-31611Y241297D02*
Y236297D01*
G01Y237047D02*
X-31944Y236630D01*
X-32444Y236380D01*
X-33028Y236297D01*
X-33694Y236464D01*
X-34194Y236880D01*
X-34528Y237380D01*
X-34611Y237964D01*
X-34528Y238547D01*
X-34194Y239047D01*
X-33694Y239464D01*
X-33028Y239630D01*
X-32444Y239547D01*
X-32028Y239380D01*
X-31611Y239047D01*
G01X-21911Y236297D02*
X-22411Y236380D01*
X-22911Y236714D01*
X-23244Y237297D01*
X-23411Y237964D01*
X-23244Y238630D01*
X-22911Y239214D01*
X-22411Y239547D01*
X-21911Y239630D01*
X-21411Y239547D01*
X-20911Y239214D01*
X-20578Y238630D01*
X-20494Y237964D01*
X-20578Y237297D01*
X-20911Y236714D01*
X-21411Y236380D01*
X-21911Y236297D01*
G01X-16311Y241297D02*
Y236297D01*
G01X-17478Y239630D02*
X-15144D01*
G01X-12128Y236297D02*
Y241297D01*
G01Y238880D02*
X-11711Y239297D01*
X-11294Y239547D01*
X-10628Y239630D01*
X-10128Y239547D01*
X-9544Y239214D01*
X-9294Y238714D01*
Y236297D01*
G01X-6361Y238547D02*
X-3694D01*
X-3944Y239130D01*
X-4361Y239464D01*
X-4944Y239630D01*
X-5528Y239547D01*
X-6028Y239297D01*
X-6361Y238714D01*
X-6528Y238214D01*
Y237714D01*
X-6361Y237214D01*
X-5944Y236714D01*
X-5444Y236380D01*
X-4861Y236297D01*
X-4278Y236464D01*
X-3694Y236964D01*
G01X-678Y236297D02*
Y239630D01*
G01Y238964D02*
X-261Y239297D01*
X156Y239547D01*
X739Y239630D01*
X1156Y239547D01*
X1656Y239297D01*
G01X4839Y236880D02*
X5256Y236547D01*
X5839Y236297D01*
X6339D01*
X6839Y236464D01*
X7172Y236714D01*
X7339Y237047D01*
X7256Y237547D01*
X6922Y237797D01*
X5422Y238297D01*
X5089Y238880D01*
X5256Y239297D01*
X5589Y239547D01*
X6089Y239630D01*
X6589Y239547D01*
X7089Y239297D01*
G01X12106Y234630D02*
X12939Y235464D01*
X13356Y236297D01*
Y239630D01*
X12939Y240464D01*
X12106Y241297D01*
G01X-163578Y251297D02*
Y256297D01*
X-161578D01*
X-160911Y256047D01*
X-160411Y255464D01*
X-160244Y254797D01*
X-160411Y254130D01*
X-160828Y253630D01*
X-161578Y253380D01*
X-163578D01*
G01X-156311Y256297D02*
Y251297D01*
G01X-158228Y256297D02*
X-154394D01*
G01X-152461Y251297D02*
Y256297D01*
G01X-148961D02*
Y251297D01*
G01Y253797D02*
X-152461D01*
G01X-146611Y251130D02*
X-143611Y256297D01*
G01X-141428Y251297D02*
Y256297D01*
X-137594Y251297D01*
Y256297D01*
G01X-135578Y251297D02*
Y256297D01*
X-133578D01*
X-132911Y256047D01*
X-132411Y255464D01*
X-132244Y254797D01*
X-132411Y254130D01*
X-132828Y253630D01*
X-133578Y253380D01*
X-135578D01*
G01X-128311Y256297D02*
Y251297D01*
G01X-130228Y256297D02*
X-126394D01*
G01X-124461Y251297D02*
Y256297D01*
G01X-120961D02*
Y251297D01*
G01Y253797D02*
X-124461D01*
G01X-113178Y251297D02*
X-109844Y252964D01*
X-113178Y254630D01*
G01X-106994Y252214D02*
X-104828D01*
G01Y253714D02*
X-106994D01*
G01X-102144Y252047D02*
X-101644Y251630D01*
X-101061Y251380D01*
X-100311Y251297D01*
X-99561Y251464D01*
X-98978Y251797D01*
X-98561Y252380D01*
X-98478Y253047D01*
X-98644Y253714D01*
X-99061Y254130D01*
X-99644Y254464D01*
X-100228Y254547D01*
X-100811Y254464D01*
X-101561Y254130D01*
X-101311Y256297D01*
X-99061D01*
G01X-91611Y251297D02*
Y254630D01*
G01Y253714D02*
X-91361Y254130D01*
X-90944Y254464D01*
X-90361Y254630D01*
X-89778Y254464D01*
X-89361Y254130D01*
X-89111Y253714D01*
Y251297D01*
G01Y253714D02*
X-88861Y254130D01*
X-88444Y254464D01*
X-87861Y254630D01*
X-87278Y254464D01*
X-86861Y254130D01*
X-86611Y253630D01*
Y251297D01*
G01X-86011D02*
Y254630D01*
G01Y253714D02*
X-85761Y254130D01*
X-85344Y254464D01*
X-84761Y254630D01*
X-84178Y254464D01*
X-83761Y254130D01*
X-83511Y253714D01*
Y251297D01*
G01Y253714D02*
X-83261Y254130D01*
X-82844Y254464D01*
X-82261Y254630D01*
X-81678Y254464D01*
X-81261Y254130D01*
X-81011Y253630D01*
Y251297D01*
G01X-171911Y245297D02*
X260089D01*
G01X-171911Y260297D02*
X260089D01*
G01X-163828Y264797D02*
Y269797D01*
X-159994Y264797D01*
Y269797D01*
G01X-157978Y264797D02*
Y269797D01*
X-155978D01*
X-155311Y269547D01*
X-154811Y268964D01*
X-154644Y268297D01*
X-154811Y267630D01*
X-155228Y267130D01*
X-155978Y266880D01*
X-157978D01*
G01X-150711Y269797D02*
Y264797D01*
G01X-152628Y269797D02*
X-148794D01*
G01X-146861Y264797D02*
Y269797D01*
G01X-143361D02*
Y264797D01*
G01Y267297D02*
X-146861D01*
G01X-135661Y265464D02*
X-134994Y265047D01*
X-134244Y264797D01*
X-133578D01*
X-132911Y265047D01*
X-132411Y265464D01*
X-132161Y266047D01*
X-132328Y266630D01*
X-132744Y267130D01*
X-133494Y267464D01*
X-134494Y267630D01*
X-135078Y267964D01*
X-135328Y268547D01*
X-135161Y269130D01*
X-134744Y269547D01*
X-134161Y269797D01*
X-133578D01*
X-132994Y269630D01*
X-132494Y269214D01*
G01X-128311Y268130D02*
Y264797D01*
G01Y269464D02*
X-128478Y269547D01*
Y269714D01*
X-128311Y269797D01*
X-128144Y269714D01*
Y269547D01*
X-128311Y269464D01*
G01X-123961Y268130D02*
X-121461D01*
X-123961Y264797D01*
X-121461D01*
G01X-118361Y267047D02*
X-115694D01*
X-115944Y267630D01*
X-116361Y267964D01*
X-116944Y268130D01*
X-117528Y268047D01*
X-118028Y267797D01*
X-118361Y267214D01*
X-118528Y266714D01*
Y266214D01*
X-118361Y265714D01*
X-117944Y265214D01*
X-117444Y264880D01*
X-116861Y264797D01*
X-116278Y264964D01*
X-115694Y265464D01*
G01X-107744Y265797D02*
X-107244Y265214D01*
X-106578Y264880D01*
X-105828Y264797D01*
X-105161Y264880D01*
X-104494Y265297D01*
X-104078Y265797D01*
X-103994Y266297D01*
X-104161Y266880D01*
X-104744Y267297D01*
X-105328Y267464D01*
X-106078D01*
G01X-105328D02*
X-104828Y267714D01*
X-104411Y268130D01*
X-104244Y268630D01*
X-104411Y269130D01*
X-104828Y269547D01*
X-105578Y269797D01*
X-106328Y269714D01*
X-107078Y269380D01*
G01X-100311Y264630D02*
X-100478Y264714D01*
Y264880D01*
X-100311Y264964D01*
X-100144Y264880D01*
Y264714D01*
X-100311Y264630D01*
G01X-96544Y265547D02*
X-96044Y265130D01*
X-95461Y264880D01*
X-94711Y264797D01*
X-93961Y264964D01*
X-93378Y265297D01*
X-92961Y265880D01*
X-92878Y266547D01*
X-93044Y267214D01*
X-93461Y267630D01*
X-94044Y267964D01*
X-94628Y268047D01*
X-95211Y267964D01*
X-95961Y267630D01*
X-95711Y269797D01*
X-93461D01*
G01X-90944Y265547D02*
X-90444Y265130D01*
X-89861Y264880D01*
X-89111Y264797D01*
X-88361Y264964D01*
X-87778Y265297D01*
X-87361Y265880D01*
X-87278Y266547D01*
X-87444Y267214D01*
X-87861Y267630D01*
X-88444Y267964D01*
X-89028Y268047D01*
X-89611Y267964D01*
X-90361Y267630D01*
X-90111Y269797D01*
X-87861D01*
G01X-86011Y264797D02*
Y268130D01*
G01Y267214D02*
X-85761Y267630D01*
X-85344Y267964D01*
X-84761Y268130D01*
X-84178Y267964D01*
X-83761Y267630D01*
X-83511Y267214D01*
Y264797D01*
G01Y267214D02*
X-83261Y267630D01*
X-82844Y267964D01*
X-82261Y268130D01*
X-81678Y267964D01*
X-81261Y267630D01*
X-81011Y267130D01*
Y264797D01*
G01X-80411D02*
Y268130D01*
G01Y267214D02*
X-80161Y267630D01*
X-79744Y267964D01*
X-79161Y268130D01*
X-78578Y267964D01*
X-78161Y267630D01*
X-77911Y267214D01*
Y264797D01*
G01Y267214D02*
X-77661Y267630D01*
X-77244Y267964D01*
X-76661Y268130D01*
X-76078Y267964D01*
X-75661Y267630D01*
X-75411Y267130D01*
Y264797D01*
G01X-163828Y279797D02*
Y284797D01*
X-159994Y279797D01*
Y284797D01*
G01X-157978Y279797D02*
Y284797D01*
X-155978D01*
X-155311Y284547D01*
X-154811Y283964D01*
X-154644Y283297D01*
X-154811Y282630D01*
X-155228Y282130D01*
X-155978Y281880D01*
X-157978D01*
G01X-150711Y284797D02*
Y279797D01*
G01X-152628Y284797D02*
X-148794D01*
G01X-146861Y279797D02*
Y284797D01*
G01X-143361D02*
Y279797D01*
G01Y282297D02*
X-146861D01*
G01X-135661Y280464D02*
X-134994Y280047D01*
X-134244Y279797D01*
X-133578D01*
X-132911Y280047D01*
X-132411Y280464D01*
X-132161Y281047D01*
X-132328Y281630D01*
X-132744Y282130D01*
X-133494Y282464D01*
X-134494Y282630D01*
X-135078Y282964D01*
X-135328Y283547D01*
X-135161Y284130D01*
X-134744Y284547D01*
X-134161Y284797D01*
X-133578D01*
X-132994Y284630D01*
X-132494Y284214D01*
G01X-128311Y283130D02*
Y279797D01*
G01Y284464D02*
X-128478Y284547D01*
Y284714D01*
X-128311Y284797D01*
X-128144Y284714D01*
Y284547D01*
X-128311Y284464D01*
G01X-123961Y283130D02*
X-121461D01*
X-123961Y279797D01*
X-121461D01*
G01X-118361Y282047D02*
X-115694D01*
X-115944Y282630D01*
X-116361Y282964D01*
X-116944Y283130D01*
X-117528Y283047D01*
X-118028Y282797D01*
X-118361Y282214D01*
X-118528Y281714D01*
Y281214D01*
X-118361Y280714D01*
X-117944Y280214D01*
X-117444Y279880D01*
X-116861Y279797D01*
X-116278Y279964D01*
X-115694Y280464D01*
G01X-109844Y279797D02*
X-113178Y281464D01*
X-109844Y283130D01*
G01X-102144Y280547D02*
X-101644Y280130D01*
X-101061Y279880D01*
X-100311Y279797D01*
X-99561Y279964D01*
X-98978Y280297D01*
X-98561Y280880D01*
X-98478Y281547D01*
X-98644Y282214D01*
X-99061Y282630D01*
X-99644Y282964D01*
X-100228Y283047D01*
X-100811Y282964D01*
X-101561Y282630D01*
X-101311Y284797D01*
X-99061D01*
G01X-97211Y279797D02*
Y283130D01*
G01Y282214D02*
X-96961Y282630D01*
X-96544Y282964D01*
X-95961Y283130D01*
X-95378Y282964D01*
X-94961Y282630D01*
X-94711Y282214D01*
Y279797D01*
G01Y282214D02*
X-94461Y282630D01*
X-94044Y282964D01*
X-93461Y283130D01*
X-92878Y282964D01*
X-92461Y282630D01*
X-92211Y282130D01*
Y279797D01*
G01X-91611D02*
Y283130D01*
G01Y282214D02*
X-91361Y282630D01*
X-90944Y282964D01*
X-90361Y283130D01*
X-89778Y282964D01*
X-89361Y282630D01*
X-89111Y282214D01*
Y279797D01*
G01Y282214D02*
X-88861Y282630D01*
X-88444Y282964D01*
X-87861Y283130D01*
X-87278Y282964D01*
X-86861Y282630D01*
X-86611Y282130D01*
Y279797D01*
G01X-171911Y275297D02*
X260089D01*
G01X-163744Y301297D02*
Y297714D01*
X-163411Y296964D01*
X-162744Y296464D01*
X-161911Y296297D01*
X-161078Y296464D01*
X-160411Y296964D01*
X-160078Y297714D01*
Y301297D01*
G01X-157728Y296297D02*
Y299630D01*
G01Y298797D02*
X-157394Y299214D01*
X-156894Y299547D01*
X-156228Y299630D01*
X-155644Y299547D01*
X-155144Y299214D01*
X-154894Y298630D01*
Y296297D01*
G01X-151794Y297964D02*
X-149628D01*
G01X-146611Y294630D02*
Y299630D01*
G01Y298880D02*
X-146194Y299297D01*
X-145778Y299547D01*
X-145111Y299630D01*
X-144528Y299547D01*
X-143944Y299130D01*
X-143694Y298547D01*
X-143611Y297964D01*
X-143694Y297380D01*
X-143944Y296797D01*
X-144444Y296464D01*
X-145111Y296297D01*
X-145694Y296380D01*
X-146278Y296630D01*
X-146611Y296964D01*
G01X-139511Y296297D02*
Y301297D01*
G01X-135328Y299630D02*
Y297297D01*
X-134994Y296714D01*
X-134494Y296380D01*
X-133911Y296297D01*
X-133328Y296380D01*
X-132828Y296714D01*
X-132494Y297297D01*
G01Y296297D02*
Y299630D01*
G01X-129478Y295047D02*
X-128894Y294714D01*
X-128228Y294630D01*
X-127644Y294714D01*
X-127144Y295130D01*
X-126811Y295714D01*
Y299630D01*
G01Y298964D02*
X-127144Y299297D01*
X-127644Y299547D01*
X-128228Y299630D01*
X-128894Y299464D01*
X-129311Y299130D01*
X-129644Y298547D01*
X-129811Y297964D01*
X-129728Y297464D01*
X-129394Y296880D01*
X-128894Y296464D01*
X-128228Y296297D01*
X-127728Y296380D01*
X-127144Y296714D01*
X-126811Y297047D01*
G01X-123878Y295047D02*
X-123294Y294714D01*
X-122628Y294630D01*
X-122044Y294714D01*
X-121544Y295130D01*
X-121211Y295714D01*
Y299630D01*
G01Y298964D02*
X-121544Y299297D01*
X-122044Y299547D01*
X-122628Y299630D01*
X-123294Y299464D01*
X-123711Y299130D01*
X-124044Y298547D01*
X-124211Y297964D01*
X-124128Y297464D01*
X-123794Y296880D01*
X-123294Y296464D01*
X-122628Y296297D01*
X-122128Y296380D01*
X-121544Y296714D01*
X-121211Y297047D01*
G01X-118361Y298547D02*
X-115694D01*
X-115944Y299130D01*
X-116361Y299464D01*
X-116944Y299630D01*
X-117528Y299547D01*
X-118028Y299297D01*
X-118361Y298714D01*
X-118528Y298214D01*
Y297714D01*
X-118361Y297214D01*
X-117944Y296714D01*
X-117444Y296380D01*
X-116861Y296297D01*
X-116278Y296464D01*
X-115694Y296964D01*
G01X-110011Y301297D02*
Y296297D01*
G01Y297047D02*
X-110344Y296630D01*
X-110844Y296380D01*
X-111428Y296297D01*
X-112094Y296464D01*
X-112594Y296880D01*
X-112928Y297380D01*
X-113011Y297964D01*
X-112928Y298547D01*
X-112594Y299047D01*
X-112094Y299464D01*
X-111428Y299630D01*
X-110844Y299547D01*
X-110428Y299380D01*
X-110011Y299047D01*
G01X-101978Y296297D02*
Y301297D01*
X-99978D01*
X-99311Y301047D01*
X-98811Y300464D01*
X-98644Y299797D01*
X-98811Y299130D01*
X-99228Y298630D01*
X-99978Y298380D01*
X-101978D01*
G01X-94711Y301297D02*
Y296297D01*
G01X-96628Y301297D02*
X-92794D01*
G01X-90861Y296297D02*
Y301297D01*
G01X-87361D02*
Y296297D01*
G01Y298797D02*
X-90861D01*
G01X-78328Y294630D02*
X-79161Y295464D01*
X-79578Y296297D01*
Y299630D01*
X-79161Y300464D01*
X-78328Y301297D01*
G01X-74061Y296297D02*
Y301297D01*
G01X-70561D02*
Y296297D01*
G01Y298797D02*
X-74061D01*
G01X-66711Y296297D02*
X-67211Y296380D01*
X-67711Y296714D01*
X-68044Y297297D01*
X-68211Y297964D01*
X-68044Y298630D01*
X-67711Y299214D01*
X-67211Y299547D01*
X-66711Y299630D01*
X-66211Y299547D01*
X-65711Y299214D01*
X-65378Y298630D01*
X-65294Y297964D01*
X-65378Y297297D01*
X-65711Y296714D01*
X-66211Y296380D01*
X-66711Y296297D01*
G01X-61111D02*
Y301297D01*
G01X-56761Y298547D02*
X-54094D01*
X-54344Y299130D01*
X-54761Y299464D01*
X-55344Y299630D01*
X-55928Y299547D01*
X-56428Y299297D01*
X-56761Y298714D01*
X-56928Y298214D01*
Y297714D01*
X-56761Y297214D01*
X-56344Y296714D01*
X-55844Y296380D01*
X-55261Y296297D01*
X-54678Y296464D01*
X-54094Y296964D01*
G01X-46061D02*
X-45394Y296547D01*
X-44644Y296297D01*
X-43978D01*
X-43311Y296547D01*
X-42811Y296964D01*
X-42561Y297547D01*
X-42728Y298130D01*
X-43144Y298630D01*
X-43894Y298964D01*
X-44894Y299130D01*
X-45478Y299464D01*
X-45728Y300047D01*
X-45561Y300630D01*
X-45144Y301047D01*
X-44561Y301297D01*
X-43978D01*
X-43394Y301130D01*
X-42894Y300714D01*
G01X-38711Y299630D02*
Y296297D01*
G01Y300964D02*
X-38878Y301047D01*
Y301214D01*
X-38711Y301297D01*
X-38544Y301214D01*
Y301047D01*
X-38711Y300964D01*
G01X-34361Y299630D02*
X-31861D01*
X-34361Y296297D01*
X-31861D01*
G01X-28761Y298547D02*
X-26094D01*
X-26344Y299130D01*
X-26761Y299464D01*
X-27344Y299630D01*
X-27928Y299547D01*
X-28428Y299297D01*
X-28761Y298714D01*
X-28928Y298214D01*
Y297714D01*
X-28761Y297214D01*
X-28344Y296714D01*
X-27844Y296380D01*
X-27261Y296297D01*
X-26678Y296464D01*
X-26094Y296964D01*
G01X-20244Y296297D02*
X-23578Y297964D01*
X-20244Y299630D01*
G01X-16311Y296297D02*
Y301297D01*
X-17311Y300297D01*
G01Y296297D02*
X-15311D01*
G01X-12128Y296880D02*
X-11544Y296464D01*
X-10878Y296297D01*
X-10211Y296464D01*
X-9628Y296964D01*
X-9211Y297714D01*
X-9044Y298464D01*
Y299380D01*
X-9211Y300130D01*
X-9628Y300797D01*
X-10128Y301130D01*
X-10711Y301297D01*
X-11378Y301130D01*
X-11878Y300797D01*
X-12211Y300297D01*
X-12378Y299630D01*
X-12211Y299047D01*
X-11794Y298464D01*
X-11294Y298130D01*
X-10711Y298047D01*
X-10044Y298214D01*
X-9544Y298630D01*
X-9044Y299380D01*
G01X-5278Y296297D02*
X-5111Y297380D01*
X-4861Y298297D01*
X-4528Y299130D01*
X-4111Y300047D01*
X-3444Y301297D01*
X-6778D01*
G01X-2011Y296297D02*
Y299630D01*
G01Y298714D02*
X-1761Y299130D01*
X-1344Y299464D01*
X-761Y299630D01*
X-178Y299464D01*
X239Y299130D01*
X489Y298714D01*
Y296297D01*
G01Y298714D02*
X739Y299130D01*
X1156Y299464D01*
X1739Y299630D01*
X2322Y299464D01*
X2739Y299130D01*
X2989Y298630D01*
Y296297D01*
G01X6089Y299630D02*
Y296297D01*
G01Y300964D02*
X5922Y301047D01*
Y301214D01*
X6089Y301297D01*
X6256Y301214D01*
Y301047D01*
X6089Y300964D01*
G01X11689Y296297D02*
Y301297D01*
G01X20806Y299630D02*
X21806Y296297D01*
X22889Y299630D01*
X23972Y296297D01*
X24972Y299630D01*
G01X28489D02*
Y296297D01*
G01Y300964D02*
X28322Y301047D01*
Y301214D01*
X28489Y301297D01*
X28656Y301214D01*
Y301047D01*
X28489Y300964D01*
G01X34089Y301297D02*
Y296297D01*
G01X32922Y299630D02*
X35256D01*
G01X38272Y296297D02*
Y301297D01*
G01Y298880D02*
X38689Y299297D01*
X39106Y299547D01*
X39772Y299630D01*
X40272Y299547D01*
X40856Y299214D01*
X41106Y298714D01*
Y296297D01*
G01X49139D02*
Y301297D01*
G01X52639D02*
Y296297D01*
G01Y298797D02*
X49139D01*
G01X54406Y296297D02*
X56489Y301297D01*
X58572Y296297D01*
G01X57822Y298047D02*
X55156D01*
G01X60339Y296964D02*
X61006Y296547D01*
X61756Y296297D01*
X62422D01*
X63089Y296547D01*
X63589Y296964D01*
X63839Y297547D01*
X63672Y298130D01*
X63256Y298630D01*
X62506Y298964D01*
X61506Y299130D01*
X60922Y299464D01*
X60672Y300047D01*
X60839Y300630D01*
X61256Y301047D01*
X61839Y301297D01*
X62422D01*
X63006Y301130D01*
X63506Y300714D01*
G01X66022Y301297D02*
Y296297D01*
X69356D01*
G01X77389Y294630D02*
Y299630D01*
G01Y298880D02*
X77806Y299297D01*
X78222Y299547D01*
X78889Y299630D01*
X79472Y299547D01*
X80056Y299130D01*
X80306Y298547D01*
X80389Y297964D01*
X80306Y297380D01*
X80056Y296797D01*
X79556Y296464D01*
X78889Y296297D01*
X78306Y296380D01*
X77722Y296630D01*
X77389Y296964D01*
G01X83322Y296297D02*
Y299630D01*
G01Y298964D02*
X83739Y299297D01*
X84156Y299547D01*
X84739Y299630D01*
X85156Y299547D01*
X85656Y299297D01*
G01X90089Y296297D02*
X89589Y296380D01*
X89089Y296714D01*
X88756Y297297D01*
X88589Y297964D01*
X88756Y298630D01*
X89089Y299214D01*
X89589Y299547D01*
X90089Y299630D01*
X90589Y299547D01*
X91089Y299214D01*
X91422Y298630D01*
X91506Y297964D01*
X91422Y297297D01*
X91089Y296714D01*
X90589Y296380D01*
X90089Y296297D01*
G01X97189Y301297D02*
Y296297D01*
G01Y297047D02*
X96856Y296630D01*
X96356Y296380D01*
X95772Y296297D01*
X95106Y296464D01*
X94606Y296880D01*
X94272Y297380D01*
X94189Y297964D01*
X94272Y298547D01*
X94606Y299047D01*
X95106Y299464D01*
X95772Y299630D01*
X96356Y299547D01*
X96772Y299380D01*
X97189Y299047D01*
G01X99872Y299630D02*
Y297297D01*
X100206Y296714D01*
X100706Y296380D01*
X101289Y296297D01*
X101872Y296380D01*
X102372Y296714D01*
X102706Y297297D01*
G01Y296297D02*
Y299630D01*
G01X108222Y299214D02*
X107639Y299547D01*
X107139Y299630D01*
X106472Y299464D01*
X105972Y299130D01*
X105639Y298547D01*
X105556Y297964D01*
X105639Y297380D01*
X105972Y296880D01*
X106472Y296464D01*
X107139Y296297D01*
X107722Y296464D01*
X108222Y296797D01*
G01X112489Y301297D02*
Y296297D01*
G01X111322Y299630D02*
X113656D01*
G01X116839Y296880D02*
X117256Y296547D01*
X117839Y296297D01*
X118339D01*
X118839Y296464D01*
X119172Y296714D01*
X119339Y297047D01*
X119256Y297547D01*
X118922Y297797D01*
X117422Y298297D01*
X117089Y298880D01*
X117256Y299297D01*
X117589Y299547D01*
X118089Y299630D01*
X118589Y299547D01*
X119089Y299297D01*
G01X124106Y294630D02*
X124939Y295464D01*
X125356Y296297D01*
Y299630D01*
X124939Y300464D01*
X124106Y301297D01*
G01X-171911Y290297D02*
X260089D01*
G01X-171911Y305297D02*
X260089D01*
G01X-163744Y316297D02*
Y312714D01*
X-163411Y311964D01*
X-162744Y311464D01*
X-161911Y311297D01*
X-161078Y311464D01*
X-160411Y311964D01*
X-160078Y312714D01*
Y316297D01*
G01X-157728Y311297D02*
Y314630D01*
G01Y313797D02*
X-157394Y314214D01*
X-156894Y314547D01*
X-156228Y314630D01*
X-155644Y314547D01*
X-155144Y314214D01*
X-154894Y313630D01*
Y311297D01*
G01X-151794Y312964D02*
X-149628D01*
G01X-146611Y309630D02*
Y314630D01*
G01Y313880D02*
X-146194Y314297D01*
X-145778Y314547D01*
X-145111Y314630D01*
X-144528Y314547D01*
X-143944Y314130D01*
X-143694Y313547D01*
X-143611Y312964D01*
X-143694Y312380D01*
X-143944Y311797D01*
X-144444Y311464D01*
X-145111Y311297D01*
X-145694Y311380D01*
X-146278Y311630D01*
X-146611Y311964D01*
G01X-139511Y311297D02*
Y316297D01*
G01X-135328Y314630D02*
Y312297D01*
X-134994Y311714D01*
X-134494Y311380D01*
X-133911Y311297D01*
X-133328Y311380D01*
X-132828Y311714D01*
X-132494Y312297D01*
G01Y311297D02*
Y314630D01*
G01X-129478Y310047D02*
X-128894Y309714D01*
X-128228Y309630D01*
X-127644Y309714D01*
X-127144Y310130D01*
X-126811Y310714D01*
Y314630D01*
G01Y313964D02*
X-127144Y314297D01*
X-127644Y314547D01*
X-128228Y314630D01*
X-128894Y314464D01*
X-129311Y314130D01*
X-129644Y313547D01*
X-129811Y312964D01*
X-129728Y312464D01*
X-129394Y311880D01*
X-128894Y311464D01*
X-128228Y311297D01*
X-127728Y311380D01*
X-127144Y311714D01*
X-126811Y312047D01*
G01X-123878Y310047D02*
X-123294Y309714D01*
X-122628Y309630D01*
X-122044Y309714D01*
X-121544Y310130D01*
X-121211Y310714D01*
Y314630D01*
G01Y313964D02*
X-121544Y314297D01*
X-122044Y314547D01*
X-122628Y314630D01*
X-123294Y314464D01*
X-123711Y314130D01*
X-124044Y313547D01*
X-124211Y312964D01*
X-124128Y312464D01*
X-123794Y311880D01*
X-123294Y311464D01*
X-122628Y311297D01*
X-122128Y311380D01*
X-121544Y311714D01*
X-121211Y312047D01*
G01X-118361Y313547D02*
X-115694D01*
X-115944Y314130D01*
X-116361Y314464D01*
X-116944Y314630D01*
X-117528Y314547D01*
X-118028Y314297D01*
X-118361Y313714D01*
X-118528Y313214D01*
Y312714D01*
X-118361Y312214D01*
X-117944Y311714D01*
X-117444Y311380D01*
X-116861Y311297D01*
X-116278Y311464D01*
X-115694Y311964D01*
G01X-110011Y316297D02*
Y311297D01*
G01Y312047D02*
X-110344Y311630D01*
X-110844Y311380D01*
X-111428Y311297D01*
X-112094Y311464D01*
X-112594Y311880D01*
X-112928Y312380D01*
X-113011Y312964D01*
X-112928Y313547D01*
X-112594Y314047D01*
X-112094Y314464D01*
X-111428Y314630D01*
X-110844Y314547D01*
X-110428Y314380D01*
X-110011Y314047D01*
G01X-101978Y311297D02*
Y316297D01*
X-99978D01*
X-99311Y316047D01*
X-98811Y315464D01*
X-98644Y314797D01*
X-98811Y314130D01*
X-99228Y313630D01*
X-99978Y313380D01*
X-101978D01*
G01X-94711Y316297D02*
Y311297D01*
G01X-96628Y316297D02*
X-92794D01*
G01X-90861Y311297D02*
Y316297D01*
G01X-87361D02*
Y311297D01*
G01Y313797D02*
X-90861D01*
G01X-78328Y309630D02*
X-79161Y310464D01*
X-79578Y311297D01*
Y314630D01*
X-79161Y315464D01*
X-78328Y316297D01*
G01X-74061Y311297D02*
Y316297D01*
G01X-70561D02*
Y311297D01*
G01Y313797D02*
X-74061D01*
G01X-66711Y311297D02*
X-67211Y311380D01*
X-67711Y311714D01*
X-68044Y312297D01*
X-68211Y312964D01*
X-68044Y313630D01*
X-67711Y314214D01*
X-67211Y314547D01*
X-66711Y314630D01*
X-66211Y314547D01*
X-65711Y314214D01*
X-65378Y313630D01*
X-65294Y312964D01*
X-65378Y312297D01*
X-65711Y311714D01*
X-66211Y311380D01*
X-66711Y311297D01*
G01X-61111D02*
Y316297D01*
G01X-56761Y313547D02*
X-54094D01*
X-54344Y314130D01*
X-54761Y314464D01*
X-55344Y314630D01*
X-55928Y314547D01*
X-56428Y314297D01*
X-56761Y313714D01*
X-56928Y313214D01*
Y312714D01*
X-56761Y312214D01*
X-56344Y311714D01*
X-55844Y311380D01*
X-55261Y311297D01*
X-54678Y311464D01*
X-54094Y311964D01*
G01X-46061D02*
X-45394Y311547D01*
X-44644Y311297D01*
X-43978D01*
X-43311Y311547D01*
X-42811Y311964D01*
X-42561Y312547D01*
X-42728Y313130D01*
X-43144Y313630D01*
X-43894Y313964D01*
X-44894Y314130D01*
X-45478Y314464D01*
X-45728Y315047D01*
X-45561Y315630D01*
X-45144Y316047D01*
X-44561Y316297D01*
X-43978D01*
X-43394Y316130D01*
X-42894Y315714D01*
G01X-38711Y314630D02*
Y311297D01*
G01Y315964D02*
X-38878Y316047D01*
Y316214D01*
X-38711Y316297D01*
X-38544Y316214D01*
Y316047D01*
X-38711Y315964D01*
G01X-34361Y314630D02*
X-31861D01*
X-34361Y311297D01*
X-31861D01*
G01X-28761Y313547D02*
X-26094D01*
X-26344Y314130D01*
X-26761Y314464D01*
X-27344Y314630D01*
X-27928Y314547D01*
X-28428Y314297D01*
X-28761Y313714D01*
X-28928Y313214D01*
Y312714D01*
X-28761Y312214D01*
X-28344Y311714D01*
X-27844Y311380D01*
X-27261Y311297D01*
X-26678Y311464D01*
X-26094Y311964D01*
G01X-20244Y311297D02*
X-23578Y312964D01*
X-20244Y314630D01*
G01X-16311Y311297D02*
Y316297D01*
X-17311Y315297D01*
G01Y311297D02*
X-15311D01*
G01X-12128Y311880D02*
X-11544Y311464D01*
X-10878Y311297D01*
X-10211Y311464D01*
X-9628Y311964D01*
X-9211Y312714D01*
X-9044Y313464D01*
Y314380D01*
X-9211Y315130D01*
X-9628Y315797D01*
X-10128Y316130D01*
X-10711Y316297D01*
X-11378Y316130D01*
X-11878Y315797D01*
X-12211Y315297D01*
X-12378Y314630D01*
X-12211Y314047D01*
X-11794Y313464D01*
X-11294Y313130D01*
X-10711Y313047D01*
X-10044Y313214D01*
X-9544Y313630D01*
X-9044Y314380D01*
G01X-5278Y311297D02*
X-5111Y312380D01*
X-4861Y313297D01*
X-4528Y314130D01*
X-4111Y315047D01*
X-3444Y316297D01*
X-6778D01*
G01X-2011Y311297D02*
Y314630D01*
G01Y313714D02*
X-1761Y314130D01*
X-1344Y314464D01*
X-761Y314630D01*
X-178Y314464D01*
X239Y314130D01*
X489Y313714D01*
Y311297D01*
G01Y313714D02*
X739Y314130D01*
X1156Y314464D01*
X1739Y314630D01*
X2322Y314464D01*
X2739Y314130D01*
X2989Y313630D01*
Y311297D01*
G01X6089Y314630D02*
Y311297D01*
G01Y315964D02*
X5922Y316047D01*
Y316214D01*
X6089Y316297D01*
X6256Y316214D01*
Y316047D01*
X6089Y315964D01*
G01X11689Y311297D02*
Y316297D01*
G01X20806Y314630D02*
X21806Y311297D01*
X22889Y314630D01*
X23972Y311297D01*
X24972Y314630D01*
G01X28489D02*
Y311297D01*
G01Y315964D02*
X28322Y316047D01*
Y316214D01*
X28489Y316297D01*
X28656Y316214D01*
Y316047D01*
X28489Y315964D01*
G01X34089Y316297D02*
Y311297D01*
G01X32922Y314630D02*
X35256D01*
G01X38272Y311297D02*
Y316297D01*
G01Y313880D02*
X38689Y314297D01*
X39106Y314547D01*
X39772Y314630D01*
X40272Y314547D01*
X40856Y314214D01*
X41106Y313714D01*
Y311297D01*
G01X49472D02*
Y314630D01*
G01Y313797D02*
X49806Y314214D01*
X50306Y314547D01*
X50972Y314630D01*
X51556Y314547D01*
X52056Y314214D01*
X52306Y313630D01*
Y311297D01*
G01X56489D02*
X55989Y311380D01*
X55489Y311714D01*
X55156Y312297D01*
X54989Y312964D01*
X55156Y313630D01*
X55489Y314214D01*
X55989Y314547D01*
X56489Y314630D01*
X56989Y314547D01*
X57489Y314214D01*
X57822Y313630D01*
X57906Y312964D01*
X57822Y312297D01*
X57489Y311714D01*
X56989Y311380D01*
X56489Y311297D01*
G01X60672D02*
Y314630D01*
G01Y313797D02*
X61006Y314214D01*
X61506Y314547D01*
X62172Y314630D01*
X62756Y314547D01*
X63256Y314214D01*
X63506Y313630D01*
Y311297D01*
G01X66606Y312964D02*
X68772D01*
G01X71539Y311297D02*
Y316297D01*
G01X75039D02*
Y311297D01*
G01Y313797D02*
X71539D01*
G01X76806Y311297D02*
X78889Y316297D01*
X80972Y311297D01*
G01X80222Y313047D02*
X77556D01*
G01X82739Y311964D02*
X83406Y311547D01*
X84156Y311297D01*
X84822D01*
X85489Y311547D01*
X85989Y311964D01*
X86239Y312547D01*
X86072Y313130D01*
X85656Y313630D01*
X84906Y313964D01*
X83906Y314130D01*
X83322Y314464D01*
X83072Y315047D01*
X83239Y315630D01*
X83656Y316047D01*
X84239Y316297D01*
X84822D01*
X85406Y316130D01*
X85906Y315714D01*
G01X88422Y316297D02*
Y311297D01*
X91756D01*
G01X99789Y309630D02*
Y314630D01*
G01Y313880D02*
X100206Y314297D01*
X100622Y314547D01*
X101289Y314630D01*
X101872Y314547D01*
X102456Y314130D01*
X102706Y313547D01*
X102789Y312964D01*
X102706Y312380D01*
X102456Y311797D01*
X101956Y311464D01*
X101289Y311297D01*
X100706Y311380D01*
X100122Y311630D01*
X99789Y311964D01*
G01X105722Y311297D02*
Y314630D01*
G01Y313964D02*
X106139Y314297D01*
X106556Y314547D01*
X107139Y314630D01*
X107556Y314547D01*
X108056Y314297D01*
G01X112489Y311297D02*
X111989Y311380D01*
X111489Y311714D01*
X111156Y312297D01*
X110989Y312964D01*
X111156Y313630D01*
X111489Y314214D01*
X111989Y314547D01*
X112489Y314630D01*
X112989Y314547D01*
X113489Y314214D01*
X113822Y313630D01*
X113906Y312964D01*
X113822Y312297D01*
X113489Y311714D01*
X112989Y311380D01*
X112489Y311297D01*
G01X119589Y316297D02*
Y311297D01*
G01Y312047D02*
X119256Y311630D01*
X118756Y311380D01*
X118172Y311297D01*
X117506Y311464D01*
X117006Y311880D01*
X116672Y312380D01*
X116589Y312964D01*
X116672Y313547D01*
X117006Y314047D01*
X117506Y314464D01*
X118172Y314630D01*
X118756Y314547D01*
X119172Y314380D01*
X119589Y314047D01*
G01X122272Y314630D02*
Y312297D01*
X122606Y311714D01*
X123106Y311380D01*
X123689Y311297D01*
X124272Y311380D01*
X124772Y311714D01*
X125106Y312297D01*
G01Y311297D02*
Y314630D01*
G01X130622Y314214D02*
X130039Y314547D01*
X129539Y314630D01*
X128872Y314464D01*
X128372Y314130D01*
X128039Y313547D01*
X127956Y312964D01*
X128039Y312380D01*
X128372Y311880D01*
X128872Y311464D01*
X129539Y311297D01*
X130122Y311464D01*
X130622Y311797D01*
G01X134889Y316297D02*
Y311297D01*
G01X133722Y314630D02*
X136056D01*
G01X139239Y311880D02*
X139656Y311547D01*
X140239Y311297D01*
X140739D01*
X141239Y311464D01*
X141572Y311714D01*
X141739Y312047D01*
X141656Y312547D01*
X141322Y312797D01*
X139822Y313297D01*
X139489Y313880D01*
X139656Y314297D01*
X139989Y314547D01*
X140489Y314630D01*
X140989Y314547D01*
X141489Y314297D01*
G01X146506Y309630D02*
X147339Y310464D01*
X147756Y311297D01*
Y314630D01*
X147339Y315464D01*
X146506Y316297D01*
G01X-163578Y326297D02*
Y331297D01*
X-161578D01*
X-160911Y331047D01*
X-160411Y330464D01*
X-160244Y329797D01*
X-160411Y329130D01*
X-160828Y328630D01*
X-161578Y328380D01*
X-163578D01*
G01X-156311Y326297D02*
Y331297D01*
G01X-152128Y329630D02*
Y327297D01*
X-151794Y326714D01*
X-151294Y326380D01*
X-150711Y326297D01*
X-150128Y326380D01*
X-149628Y326714D01*
X-149294Y327297D01*
G01Y326297D02*
Y329630D01*
G01X-146278Y325047D02*
X-145694Y324714D01*
X-145028Y324630D01*
X-144444Y324714D01*
X-143944Y325130D01*
X-143611Y325714D01*
Y329630D01*
G01Y328964D02*
X-143944Y329297D01*
X-144444Y329547D01*
X-145028Y329630D01*
X-145694Y329464D01*
X-146111Y329130D01*
X-146444Y328547D01*
X-146611Y327964D01*
X-146528Y327464D01*
X-146194Y326880D01*
X-145694Y326464D01*
X-145028Y326297D01*
X-144528Y326380D01*
X-143944Y326714D01*
X-143611Y327047D01*
G01X-140678Y325047D02*
X-140094Y324714D01*
X-139428Y324630D01*
X-138844Y324714D01*
X-138344Y325130D01*
X-138011Y325714D01*
Y329630D01*
G01Y328964D02*
X-138344Y329297D01*
X-138844Y329547D01*
X-139428Y329630D01*
X-140094Y329464D01*
X-140511Y329130D01*
X-140844Y328547D01*
X-141011Y327964D01*
X-140928Y327464D01*
X-140594Y326880D01*
X-140094Y326464D01*
X-139428Y326297D01*
X-138928Y326380D01*
X-138344Y326714D01*
X-138011Y327047D01*
G01X-135161Y328547D02*
X-132494D01*
X-132744Y329130D01*
X-133161Y329464D01*
X-133744Y329630D01*
X-134328Y329547D01*
X-134828Y329297D01*
X-135161Y328714D01*
X-135328Y328214D01*
Y327714D01*
X-135161Y327214D01*
X-134744Y326714D01*
X-134244Y326380D01*
X-133661Y326297D01*
X-133078Y326464D01*
X-132494Y326964D01*
G01X-126811Y331297D02*
Y326297D01*
G01Y327047D02*
X-127144Y326630D01*
X-127644Y326380D01*
X-128228Y326297D01*
X-128894Y326464D01*
X-129394Y326880D01*
X-129728Y327380D01*
X-129811Y327964D01*
X-129728Y328547D01*
X-129394Y329047D01*
X-128894Y329464D01*
X-128228Y329630D01*
X-127644Y329547D01*
X-127228Y329380D01*
X-126811Y329047D01*
G01X-118778Y326297D02*
Y331297D01*
X-116778D01*
X-116111Y331047D01*
X-115611Y330464D01*
X-115444Y329797D01*
X-115611Y329130D01*
X-116028Y328630D01*
X-116778Y328380D01*
X-118778D01*
G01X-111511Y331297D02*
Y326297D01*
G01X-113428Y331297D02*
X-109594D01*
G01X-107661Y326297D02*
Y331297D01*
G01X-104161D02*
Y326297D01*
G01Y328797D02*
X-107661D01*
G01X-100728Y324630D02*
X-101561Y325464D01*
X-101978Y326297D01*
Y329630D01*
X-101561Y330464D01*
X-100728Y331297D01*
G01X-96128Y326297D02*
Y331297D01*
G01Y328880D02*
X-95711Y329297D01*
X-95294Y329547D01*
X-94628Y329630D01*
X-94128Y329547D01*
X-93544Y329214D01*
X-93294Y328714D01*
Y326297D01*
G01X-89111D02*
X-89611Y326380D01*
X-90111Y326714D01*
X-90444Y327297D01*
X-90611Y327964D01*
X-90444Y328630D01*
X-90111Y329214D01*
X-89611Y329547D01*
X-89111Y329630D01*
X-88611Y329547D01*
X-88111Y329214D01*
X-87778Y328630D01*
X-87694Y327964D01*
X-87778Y327297D01*
X-88111Y326714D01*
X-88611Y326380D01*
X-89111Y326297D01*
G01X-83511D02*
Y331297D01*
G01X-79161Y328547D02*
X-76494D01*
X-76744Y329130D01*
X-77161Y329464D01*
X-77744Y329630D01*
X-78328Y329547D01*
X-78828Y329297D01*
X-79161Y328714D01*
X-79328Y328214D01*
Y327714D01*
X-79161Y327214D01*
X-78744Y326714D01*
X-78244Y326380D01*
X-77661Y326297D01*
X-77078Y326464D01*
X-76494Y326964D01*
G01X-67961Y326880D02*
X-67544Y326547D01*
X-66961Y326297D01*
X-66461D01*
X-65961Y326464D01*
X-65628Y326714D01*
X-65461Y327047D01*
X-65544Y327547D01*
X-65878Y327797D01*
X-67378Y328297D01*
X-67711Y328880D01*
X-67544Y329297D01*
X-67211Y329547D01*
X-66711Y329630D01*
X-66211Y329547D01*
X-65711Y329297D01*
G01X-61111Y329630D02*
Y326297D01*
G01Y330964D02*
X-61278Y331047D01*
Y331214D01*
X-61111Y331297D01*
X-60944Y331214D01*
Y331047D01*
X-61111Y330964D01*
G01X-56761Y329630D02*
X-54261D01*
X-56761Y326297D01*
X-54261D01*
G01X-51161Y328547D02*
X-48494D01*
X-48744Y329130D01*
X-49161Y329464D01*
X-49744Y329630D01*
X-50328Y329547D01*
X-50828Y329297D01*
X-51161Y328714D01*
X-51328Y328214D01*
Y327714D01*
X-51161Y327214D01*
X-50744Y326714D01*
X-50244Y326380D01*
X-49661Y326297D01*
X-49078Y326464D01*
X-48494Y326964D01*
G01X-45978Y326297D02*
X-42644Y327964D01*
X-45978Y329630D01*
G01X-39794Y327214D02*
X-37628D01*
G01Y328714D02*
X-39794D01*
G01X-33111Y326297D02*
Y331297D01*
X-34111Y330297D01*
G01Y326297D02*
X-32111D01*
G01X-29094Y328380D02*
X-28511Y328964D01*
X-28011Y329297D01*
X-27344Y329464D01*
X-26761Y329297D01*
X-26344Y328964D01*
X-26011Y328464D01*
X-25928Y327880D01*
X-26011Y327380D01*
X-26344Y326880D01*
X-26844Y326464D01*
X-27428Y326297D01*
X-28094Y326464D01*
X-28678Y326964D01*
X-29011Y327714D01*
X-29094Y328547D01*
X-28928Y329630D01*
X-28678Y330214D01*
X-28261Y330797D01*
X-27678Y331214D01*
X-27094Y331297D01*
X-26511Y331130D01*
X-26094Y330714D01*
G01X-18811Y326297D02*
Y329630D01*
G01Y328714D02*
X-18561Y329130D01*
X-18144Y329464D01*
X-17561Y329630D01*
X-16978Y329464D01*
X-16561Y329130D01*
X-16311Y328714D01*
Y326297D01*
G01Y328714D02*
X-16061Y329130D01*
X-15644Y329464D01*
X-15061Y329630D01*
X-14478Y329464D01*
X-14061Y329130D01*
X-13811Y328630D01*
Y326297D01*
G01X-10711Y329630D02*
Y326297D01*
G01Y330964D02*
X-10878Y331047D01*
Y331214D01*
X-10711Y331297D01*
X-10544Y331214D01*
Y331047D01*
X-10711Y330964D01*
G01X-5111Y326297D02*
Y331297D01*
G01X906Y324630D02*
X1739Y325464D01*
X2156Y326297D01*
Y329630D01*
X1739Y330464D01*
X906Y331297D01*
G01X-171911Y320297D02*
X260089D01*
G01X-163994Y354797D02*
X-161911Y359797D01*
X-159828Y354797D01*
G01X-160578Y356547D02*
X-163244D01*
G01X-157728Y354797D02*
Y358130D01*
G01Y357297D02*
X-157394Y357714D01*
X-156894Y358047D01*
X-156228Y358130D01*
X-155644Y358047D01*
X-155144Y357714D01*
X-154894Y357130D01*
Y354797D01*
G01X-152461Y353297D02*
X-151961Y353130D01*
X-151294Y353297D01*
X-150878Y353630D01*
X-150544Y354047D01*
X-150044Y355380D01*
X-148961Y358130D01*
G01X-151628D02*
X-150044Y355380D01*
G01X-140928Y354797D02*
Y359797D01*
G01Y357380D02*
X-140511Y357797D01*
X-140094Y358047D01*
X-139428Y358130D01*
X-138928Y358047D01*
X-138344Y357714D01*
X-138094Y357214D01*
Y354797D01*
G01X-133911D02*
X-134411Y354880D01*
X-134911Y355214D01*
X-135244Y355797D01*
X-135411Y356464D01*
X-135244Y357130D01*
X-134911Y357714D01*
X-134411Y358047D01*
X-133911Y358130D01*
X-133411Y358047D01*
X-132911Y357714D01*
X-132578Y357130D01*
X-132494Y356464D01*
X-132578Y355797D01*
X-132911Y355214D01*
X-133411Y354880D01*
X-133911Y354797D01*
G01X-128311D02*
Y359797D01*
G01X-123961Y357047D02*
X-121294D01*
X-121544Y357630D01*
X-121961Y357964D01*
X-122544Y358130D01*
X-123128Y358047D01*
X-123628Y357797D01*
X-123961Y357214D01*
X-124128Y356714D01*
Y356214D01*
X-123961Y355714D01*
X-123544Y355214D01*
X-123044Y354880D01*
X-122461Y354797D01*
X-121878Y354964D01*
X-121294Y355464D01*
G01X-111511Y359797D02*
Y354797D01*
G01X-112678Y358130D02*
X-110344D01*
G01X-105911Y354797D02*
X-106411Y354880D01*
X-106911Y355214D01*
X-107244Y355797D01*
X-107411Y356464D01*
X-107244Y357130D01*
X-106911Y357714D01*
X-106411Y358047D01*
X-105911Y358130D01*
X-105411Y358047D01*
X-104911Y357714D01*
X-104578Y357130D01*
X-104494Y356464D01*
X-104578Y355797D01*
X-104911Y355214D01*
X-105411Y354880D01*
X-105911Y354797D01*
G01X-96128D02*
Y359797D01*
G01Y357380D02*
X-95711Y357797D01*
X-95294Y358047D01*
X-94628Y358130D01*
X-94128Y358047D01*
X-93544Y357714D01*
X-93294Y357214D01*
Y354797D01*
G01X-89111D02*
X-89611Y354880D01*
X-90111Y355214D01*
X-90444Y355797D01*
X-90611Y356464D01*
X-90444Y357130D01*
X-90111Y357714D01*
X-89611Y358047D01*
X-89111Y358130D01*
X-88611Y358047D01*
X-88111Y357714D01*
X-87778Y357130D01*
X-87694Y356464D01*
X-87778Y355797D01*
X-88111Y355214D01*
X-88611Y354880D01*
X-89111Y354797D01*
G01X-83511D02*
Y359797D01*
G01X-79161Y357047D02*
X-76494D01*
X-76744Y357630D01*
X-77161Y357964D01*
X-77744Y358130D01*
X-78328Y358047D01*
X-78828Y357797D01*
X-79161Y357214D01*
X-79328Y356714D01*
Y356214D01*
X-79161Y355714D01*
X-78744Y355214D01*
X-78244Y354880D01*
X-77661Y354797D01*
X-77078Y354964D01*
X-76494Y355464D01*
G01X-163578Y341297D02*
Y346297D01*
X-161578D01*
X-160911Y346047D01*
X-160411Y345464D01*
X-160244Y344797D01*
X-160411Y344130D01*
X-160828Y343630D01*
X-161578Y343380D01*
X-163578D01*
G01X-156311Y341297D02*
Y346297D01*
G01X-152128Y344630D02*
Y342297D01*
X-151794Y341714D01*
X-151294Y341380D01*
X-150711Y341297D01*
X-150128Y341380D01*
X-149628Y341714D01*
X-149294Y342297D01*
G01Y341297D02*
Y344630D01*
G01X-146278Y340047D02*
X-145694Y339714D01*
X-145028Y339630D01*
X-144444Y339714D01*
X-143944Y340130D01*
X-143611Y340714D01*
Y344630D01*
G01Y343964D02*
X-143944Y344297D01*
X-144444Y344547D01*
X-145028Y344630D01*
X-145694Y344464D01*
X-146111Y344130D01*
X-146444Y343547D01*
X-146611Y342964D01*
X-146528Y342464D01*
X-146194Y341880D01*
X-145694Y341464D01*
X-145028Y341297D01*
X-144528Y341380D01*
X-143944Y341714D01*
X-143611Y342047D01*
G01X-140678Y340047D02*
X-140094Y339714D01*
X-139428Y339630D01*
X-138844Y339714D01*
X-138344Y340130D01*
X-138011Y340714D01*
Y344630D01*
G01Y343964D02*
X-138344Y344297D01*
X-138844Y344547D01*
X-139428Y344630D01*
X-140094Y344464D01*
X-140511Y344130D01*
X-140844Y343547D01*
X-141011Y342964D01*
X-140928Y342464D01*
X-140594Y341880D01*
X-140094Y341464D01*
X-139428Y341297D01*
X-138928Y341380D01*
X-138344Y341714D01*
X-138011Y342047D01*
G01X-135161Y343547D02*
X-132494D01*
X-132744Y344130D01*
X-133161Y344464D01*
X-133744Y344630D01*
X-134328Y344547D01*
X-134828Y344297D01*
X-135161Y343714D01*
X-135328Y343214D01*
Y342714D01*
X-135161Y342214D01*
X-134744Y341714D01*
X-134244Y341380D01*
X-133661Y341297D01*
X-133078Y341464D01*
X-132494Y341964D01*
G01X-126811Y346297D02*
Y341297D01*
G01Y342047D02*
X-127144Y341630D01*
X-127644Y341380D01*
X-128228Y341297D01*
X-128894Y341464D01*
X-129394Y341880D01*
X-129728Y342380D01*
X-129811Y342964D01*
X-129728Y343547D01*
X-129394Y344047D01*
X-128894Y344464D01*
X-128228Y344630D01*
X-127644Y344547D01*
X-127228Y344380D01*
X-126811Y344047D01*
G01X-119194Y346297D02*
X-117111Y341297D01*
X-115028Y346297D01*
G01X-111511Y344630D02*
Y341297D01*
G01Y345964D02*
X-111678Y346047D01*
Y346214D01*
X-111511Y346297D01*
X-111344Y346214D01*
Y346047D01*
X-111511Y345964D01*
G01X-104411Y341297D02*
Y344630D01*
G01Y344047D02*
X-104744Y344380D01*
X-105244Y344547D01*
X-105828Y344630D01*
X-106411Y344464D01*
X-106911Y344130D01*
X-107244Y343630D01*
X-107411Y342964D01*
X-107244Y342297D01*
X-106911Y341797D01*
X-106411Y341464D01*
X-105828Y341297D01*
X-105244Y341380D01*
X-104744Y341630D01*
X-104411Y341964D01*
G01X-100728Y339630D02*
X-101561Y340464D01*
X-101978Y341297D01*
Y344630D01*
X-101561Y345464D01*
X-100728Y346297D01*
G01X-96128Y341297D02*
Y346297D01*
G01Y343880D02*
X-95711Y344297D01*
X-95294Y344547D01*
X-94628Y344630D01*
X-94128Y344547D01*
X-93544Y344214D01*
X-93294Y343714D01*
Y341297D01*
G01X-89111D02*
X-89611Y341380D01*
X-90111Y341714D01*
X-90444Y342297D01*
X-90611Y342964D01*
X-90444Y343630D01*
X-90111Y344214D01*
X-89611Y344547D01*
X-89111Y344630D01*
X-88611Y344547D01*
X-88111Y344214D01*
X-87778Y343630D01*
X-87694Y342964D01*
X-87778Y342297D01*
X-88111Y341714D01*
X-88611Y341380D01*
X-89111Y341297D01*
G01X-83511D02*
Y346297D01*
G01X-79161Y343547D02*
X-76494D01*
X-76744Y344130D01*
X-77161Y344464D01*
X-77744Y344630D01*
X-78328Y344547D01*
X-78828Y344297D01*
X-79161Y343714D01*
X-79328Y343214D01*
Y342714D01*
X-79161Y342214D01*
X-78744Y341714D01*
X-78244Y341380D01*
X-77661Y341297D01*
X-77078Y341464D01*
X-76494Y341964D01*
G01X-67961Y341880D02*
X-67544Y341547D01*
X-66961Y341297D01*
X-66461D01*
X-65961Y341464D01*
X-65628Y341714D01*
X-65461Y342047D01*
X-65544Y342547D01*
X-65878Y342797D01*
X-67378Y343297D01*
X-67711Y343880D01*
X-67544Y344297D01*
X-67211Y344547D01*
X-66711Y344630D01*
X-66211Y344547D01*
X-65711Y344297D01*
G01X-61111Y344630D02*
Y341297D01*
G01Y345964D02*
X-61278Y346047D01*
Y346214D01*
X-61111Y346297D01*
X-60944Y346214D01*
Y346047D01*
X-61111Y345964D01*
G01X-56761Y344630D02*
X-54261D01*
X-56761Y341297D01*
X-54261D01*
G01X-51161Y343547D02*
X-48494D01*
X-48744Y344130D01*
X-49161Y344464D01*
X-49744Y344630D01*
X-50328Y344547D01*
X-50828Y344297D01*
X-51161Y343714D01*
X-51328Y343214D01*
Y342714D01*
X-51161Y342214D01*
X-50744Y341714D01*
X-50244Y341380D01*
X-49661Y341297D01*
X-49078Y341464D01*
X-48494Y341964D01*
G01X-42644Y341297D02*
X-45978Y342964D01*
X-42644Y344630D01*
G01X-38711Y341297D02*
Y346297D01*
X-39711Y345297D01*
G01Y341297D02*
X-37711D01*
G01X-34694Y343380D02*
X-34111Y343964D01*
X-33611Y344297D01*
X-32944Y344464D01*
X-32361Y344297D01*
X-31944Y343964D01*
X-31611Y343464D01*
X-31528Y342880D01*
X-31611Y342380D01*
X-31944Y341880D01*
X-32444Y341464D01*
X-33028Y341297D01*
X-33694Y341464D01*
X-34278Y341964D01*
X-34611Y342714D01*
X-34694Y343547D01*
X-34528Y344630D01*
X-34278Y345214D01*
X-33861Y345797D01*
X-33278Y346214D01*
X-32694Y346297D01*
X-32111Y346130D01*
X-31694Y345714D01*
G01X-24411Y341297D02*
Y344630D01*
G01Y343714D02*
X-24161Y344130D01*
X-23744Y344464D01*
X-23161Y344630D01*
X-22578Y344464D01*
X-22161Y344130D01*
X-21911Y343714D01*
Y341297D01*
G01Y343714D02*
X-21661Y344130D01*
X-21244Y344464D01*
X-20661Y344630D01*
X-20078Y344464D01*
X-19661Y344130D01*
X-19411Y343630D01*
Y341297D01*
G01X-16311Y344630D02*
Y341297D01*
G01Y345964D02*
X-16478Y346047D01*
Y346214D01*
X-16311Y346297D01*
X-16144Y346214D01*
Y346047D01*
X-16311Y345964D01*
G01X-10711Y341297D02*
Y346297D01*
G01X-4694Y339630D02*
X-3861Y340464D01*
X-3444Y341297D01*
Y344630D01*
X-3861Y345464D01*
X-4694Y346297D01*
G01X-171911Y335297D02*
X260089D01*
G01X-161411Y375297D02*
Y370297D01*
G01X-163328Y375297D02*
X-159494D01*
G01X-157228Y370297D02*
Y375297D01*
G01Y372880D02*
X-156811Y373297D01*
X-156394Y373547D01*
X-155728Y373630D01*
X-155228Y373547D01*
X-154644Y373214D01*
X-154394Y372714D01*
Y370297D01*
G01X-151461Y372547D02*
X-148794D01*
X-149044Y373130D01*
X-149461Y373464D01*
X-150044Y373630D01*
X-150628Y373547D01*
X-151128Y373297D01*
X-151461Y372714D01*
X-151628Y372214D01*
Y371714D01*
X-151461Y371214D01*
X-151044Y370714D01*
X-150544Y370380D01*
X-149961Y370297D01*
X-149378Y370464D01*
X-148794Y370964D01*
G01X-145778Y370297D02*
Y373630D01*
G01Y372964D02*
X-145361Y373297D01*
X-144944Y373547D01*
X-144361Y373630D01*
X-143944Y373547D01*
X-143444Y373297D01*
G01X-141511Y370297D02*
Y373630D01*
G01Y372714D02*
X-141261Y373130D01*
X-140844Y373464D01*
X-140261Y373630D01*
X-139678Y373464D01*
X-139261Y373130D01*
X-139011Y372714D01*
Y370297D01*
G01Y372714D02*
X-138761Y373130D01*
X-138344Y373464D01*
X-137761Y373630D01*
X-137178Y373464D01*
X-136761Y373130D01*
X-136511Y372630D01*
Y370297D01*
G01X-131911D02*
Y373630D01*
G01Y373047D02*
X-132244Y373380D01*
X-132744Y373547D01*
X-133328Y373630D01*
X-133911Y373464D01*
X-134411Y373130D01*
X-134744Y372630D01*
X-134911Y371964D01*
X-134744Y371297D01*
X-134411Y370797D01*
X-133911Y370464D01*
X-133328Y370297D01*
X-132744Y370380D01*
X-132244Y370630D01*
X-131911Y370964D01*
G01X-127811Y370297D02*
Y375297D01*
G01X-118111Y368630D02*
Y373630D01*
G01Y372880D02*
X-117694Y373297D01*
X-117278Y373547D01*
X-116611Y373630D01*
X-116028Y373547D01*
X-115444Y373130D01*
X-115194Y372547D01*
X-115111Y371964D01*
X-115194Y371380D01*
X-115444Y370797D01*
X-115944Y370464D01*
X-116611Y370297D01*
X-117194Y370380D01*
X-117778Y370630D01*
X-118111Y370964D01*
G01X-109511Y370297D02*
Y373630D01*
G01Y373047D02*
X-109844Y373380D01*
X-110344Y373547D01*
X-110928Y373630D01*
X-111511Y373464D01*
X-112011Y373130D01*
X-112344Y372630D01*
X-112511Y371964D01*
X-112344Y371297D01*
X-112011Y370797D01*
X-111511Y370464D01*
X-110928Y370297D01*
X-110344Y370380D01*
X-109844Y370630D01*
X-109511Y370964D01*
G01X-103911Y375297D02*
Y370297D01*
G01Y371047D02*
X-104244Y370630D01*
X-104744Y370380D01*
X-105328Y370297D01*
X-105994Y370464D01*
X-106494Y370880D01*
X-106828Y371380D01*
X-106911Y371964D01*
X-106828Y372547D01*
X-106494Y373047D01*
X-105994Y373464D01*
X-105328Y373630D01*
X-104744Y373547D01*
X-104328Y373380D01*
X-103911Y373047D01*
G01X-92878Y373214D02*
X-93461Y373547D01*
X-93961Y373630D01*
X-94628Y373464D01*
X-95128Y373130D01*
X-95461Y372547D01*
X-95544Y371964D01*
X-95461Y371380D01*
X-95128Y370880D01*
X-94628Y370464D01*
X-93961Y370297D01*
X-93378Y370464D01*
X-92878Y370797D01*
G01X-87111Y370297D02*
Y373630D01*
G01Y373047D02*
X-87444Y373380D01*
X-87944Y373547D01*
X-88528Y373630D01*
X-89111Y373464D01*
X-89611Y373130D01*
X-89944Y372630D01*
X-90111Y371964D01*
X-89944Y371297D01*
X-89611Y370797D01*
X-89111Y370464D01*
X-88528Y370297D01*
X-87944Y370380D01*
X-87444Y370630D01*
X-87111Y370964D01*
G01X-84428Y370297D02*
Y373630D01*
G01Y372797D02*
X-84094Y373214D01*
X-83594Y373547D01*
X-82928Y373630D01*
X-82344Y373547D01*
X-81844Y373214D01*
X-81594Y372630D01*
Y370297D01*
G01X-70478Y373214D02*
X-71061Y373547D01*
X-71561Y373630D01*
X-72228Y373464D01*
X-72728Y373130D01*
X-73061Y372547D01*
X-73144Y371964D01*
X-73061Y371380D01*
X-72728Y370880D01*
X-72228Y370464D01*
X-71561Y370297D01*
X-70978Y370464D01*
X-70478Y370797D01*
G01X-67628Y370297D02*
Y375297D01*
G01Y372880D02*
X-67211Y373297D01*
X-66794Y373547D01*
X-66128Y373630D01*
X-65628Y373547D01*
X-65044Y373214D01*
X-64794Y372714D01*
Y370297D01*
G01X-59111D02*
Y373630D01*
G01Y373047D02*
X-59444Y373380D01*
X-59944Y373547D01*
X-60528Y373630D01*
X-61111Y373464D01*
X-61611Y373130D01*
X-61944Y372630D01*
X-62111Y371964D01*
X-61944Y371297D01*
X-61611Y370797D01*
X-61111Y370464D01*
X-60528Y370297D01*
X-59944Y370380D01*
X-59444Y370630D01*
X-59111Y370964D01*
G01X-56428Y370297D02*
Y373630D01*
G01Y372797D02*
X-56094Y373214D01*
X-55594Y373547D01*
X-54928Y373630D01*
X-54344Y373547D01*
X-53844Y373214D01*
X-53594Y372630D01*
Y370297D01*
G01X-50578Y369047D02*
X-49994Y368714D01*
X-49328Y368630D01*
X-48744Y368714D01*
X-48244Y369130D01*
X-47911Y369714D01*
Y373630D01*
G01Y372964D02*
X-48244Y373297D01*
X-48744Y373547D01*
X-49328Y373630D01*
X-49994Y373464D01*
X-50411Y373130D01*
X-50744Y372547D01*
X-50911Y371964D01*
X-50828Y371464D01*
X-50494Y370880D01*
X-49994Y370464D01*
X-49328Y370297D01*
X-48828Y370380D01*
X-48244Y370714D01*
X-47911Y371047D01*
G01X-45061Y372547D02*
X-42394D01*
X-42644Y373130D01*
X-43061Y373464D01*
X-43644Y373630D01*
X-44228Y373547D01*
X-44728Y373297D01*
X-45061Y372714D01*
X-45228Y372214D01*
Y371714D01*
X-45061Y371214D01*
X-44644Y370714D01*
X-44144Y370380D01*
X-43561Y370297D01*
X-42978Y370464D01*
X-42394Y370964D01*
G01X-32611Y373630D02*
Y370297D01*
G01Y374964D02*
X-32778Y375047D01*
Y375214D01*
X-32611Y375297D01*
X-32444Y375214D01*
Y375047D01*
X-32611Y374964D01*
G01X-28428Y370297D02*
Y373630D01*
G01Y372797D02*
X-28094Y373214D01*
X-27594Y373547D01*
X-26928Y373630D01*
X-26344Y373547D01*
X-25844Y373214D01*
X-25594Y372630D01*
Y370297D01*
G01X-21411Y375297D02*
Y370297D01*
G01X-22578Y373630D02*
X-20244D01*
G01X-15811Y370297D02*
X-16311Y370380D01*
X-16811Y370714D01*
X-17144Y371297D01*
X-17311Y371964D01*
X-17144Y372630D01*
X-16811Y373214D01*
X-16311Y373547D01*
X-15811Y373630D01*
X-15311Y373547D01*
X-14811Y373214D01*
X-14478Y372630D01*
X-14394Y371964D01*
X-14478Y371297D01*
X-14811Y370714D01*
X-15311Y370380D01*
X-15811Y370297D01*
G01X-5111D02*
Y374547D01*
X-4944Y374964D01*
X-4611Y375214D01*
X-4111Y375297D01*
X-3611Y375130D01*
X-3361Y374714D01*
G01X-4361Y373297D02*
X-6028D01*
G01X-428Y373630D02*
Y371297D01*
X-94Y370714D01*
X406Y370380D01*
X989Y370297D01*
X1572Y370380D01*
X2072Y370714D01*
X2406Y371297D01*
G01Y370297D02*
Y373630D01*
G01X6589Y370297D02*
Y375297D01*
G01X12189Y370297D02*
Y375297D01*
G01X24722Y373214D02*
X24139Y373547D01*
X23639Y373630D01*
X22972Y373464D01*
X22472Y373130D01*
X22139Y372547D01*
X22056Y371964D01*
X22139Y371380D01*
X22472Y370880D01*
X22972Y370464D01*
X23639Y370297D01*
X24222Y370464D01*
X24722Y370797D01*
G01X28989Y370297D02*
X28489Y370380D01*
X27989Y370714D01*
X27656Y371297D01*
X27489Y371964D01*
X27656Y372630D01*
X27989Y373214D01*
X28489Y373547D01*
X28989Y373630D01*
X29489Y373547D01*
X29989Y373214D01*
X30322Y372630D01*
X30406Y371964D01*
X30322Y371297D01*
X29989Y370714D01*
X29489Y370380D01*
X28989Y370297D01*
G01X33172D02*
Y373630D01*
G01Y372797D02*
X33506Y373214D01*
X34006Y373547D01*
X34672Y373630D01*
X35256Y373547D01*
X35756Y373214D01*
X36006Y372630D01*
Y370297D01*
G01X40189Y375297D02*
Y370297D01*
G01X39022Y373630D02*
X41356D01*
G01X47289Y370297D02*
Y373630D01*
G01Y373047D02*
X46956Y373380D01*
X46456Y373547D01*
X45872Y373630D01*
X45289Y373464D01*
X44789Y373130D01*
X44456Y372630D01*
X44289Y371964D01*
X44456Y371297D01*
X44789Y370797D01*
X45289Y370464D01*
X45872Y370297D01*
X46456Y370380D01*
X46956Y370630D01*
X47289Y370964D01*
G01X52722Y373214D02*
X52139Y373547D01*
X51639Y373630D01*
X50972Y373464D01*
X50472Y373130D01*
X50139Y372547D01*
X50056Y371964D01*
X50139Y371380D01*
X50472Y370880D01*
X50972Y370464D01*
X51639Y370297D01*
X52222Y370464D01*
X52722Y370797D01*
G01X56989Y375297D02*
Y370297D01*
G01X55822Y373630D02*
X58156D01*
G01X-163494Y385297D02*
X-161411Y390297D01*
X-159328Y385297D01*
G01X-160078Y387047D02*
X-162744D01*
G01X-157228Y385297D02*
Y388630D01*
G01Y387797D02*
X-156894Y388214D01*
X-156394Y388547D01*
X-155728Y388630D01*
X-155144Y388547D01*
X-154644Y388214D01*
X-154394Y387630D01*
Y385297D01*
G01X-150211Y390297D02*
Y385297D01*
G01X-151378Y388630D02*
X-149044D01*
G01X-144611D02*
Y385297D01*
G01Y389964D02*
X-144778Y390047D01*
Y390214D01*
X-144611Y390297D01*
X-144444Y390214D01*
Y390047D01*
X-144611Y389964D01*
G01X-140094Y386964D02*
X-137928D01*
G01X-134911Y383630D02*
Y388630D01*
G01Y387880D02*
X-134494Y388297D01*
X-134078Y388547D01*
X-133411Y388630D01*
X-132828Y388547D01*
X-132244Y388130D01*
X-131994Y387547D01*
X-131911Y386964D01*
X-131994Y386380D01*
X-132244Y385797D01*
X-132744Y385464D01*
X-133411Y385297D01*
X-133994Y385380D01*
X-134578Y385630D01*
X-134911Y385964D01*
G01X-126311Y385297D02*
Y388630D01*
G01Y388047D02*
X-126644Y388380D01*
X-127144Y388547D01*
X-127728Y388630D01*
X-128311Y388464D01*
X-128811Y388130D01*
X-129144Y387630D01*
X-129311Y386964D01*
X-129144Y386297D01*
X-128811Y385797D01*
X-128311Y385464D01*
X-127728Y385297D01*
X-127144Y385380D01*
X-126644Y385630D01*
X-126311Y385964D01*
G01X-120711Y390297D02*
Y385297D01*
G01Y386047D02*
X-121044Y385630D01*
X-121544Y385380D01*
X-122128Y385297D01*
X-122794Y385464D01*
X-123294Y385880D01*
X-123628Y386380D01*
X-123711Y386964D01*
X-123628Y387547D01*
X-123294Y388047D01*
X-122794Y388464D01*
X-122128Y388630D01*
X-121544Y388547D01*
X-121128Y388380D01*
X-120711Y388047D01*
G01X-112261Y385880D02*
X-111844Y385547D01*
X-111261Y385297D01*
X-110761D01*
X-110261Y385464D01*
X-109928Y385714D01*
X-109761Y386047D01*
X-109844Y386547D01*
X-110178Y386797D01*
X-111678Y387297D01*
X-112011Y387880D01*
X-111844Y388297D01*
X-111511Y388547D01*
X-111011Y388630D01*
X-110511Y388547D01*
X-110011Y388297D01*
G01X-105411Y388630D02*
Y385297D01*
G01Y389964D02*
X-105578Y390047D01*
Y390214D01*
X-105411Y390297D01*
X-105244Y390214D01*
Y390047D01*
X-105411Y389964D01*
G01X-101061Y388630D02*
X-98561D01*
X-101061Y385297D01*
X-98561D01*
G01X-95461Y387547D02*
X-92794D01*
X-93044Y388130D01*
X-93461Y388464D01*
X-94044Y388630D01*
X-94628Y388547D01*
X-95128Y388297D01*
X-95461Y387714D01*
X-95628Y387214D01*
Y386714D01*
X-95461Y386214D01*
X-95044Y385714D01*
X-94544Y385380D01*
X-93961Y385297D01*
X-93378Y385464D01*
X-92794Y385964D01*
G01X-164694Y403870D02*
X-163694Y400537D01*
X-162611Y403870D01*
X-161528Y400537D01*
X-160528Y403870D01*
G01X-157011D02*
Y400537D01*
G01Y405204D02*
X-157178Y405287D01*
Y405454D01*
X-157011Y405537D01*
X-156844Y405454D01*
Y405287D01*
X-157011Y405204D01*
G01X-151411Y405537D02*
Y400537D01*
G01X-152578Y403870D02*
X-150244D01*
G01X-147228Y400537D02*
Y405537D01*
G01Y403120D02*
X-146811Y403537D01*
X-146394Y403787D01*
X-145728Y403870D01*
X-145228Y403787D01*
X-144644Y403454D01*
X-144394Y402954D01*
Y400537D01*
G01X-140211D02*
X-140711Y400620D01*
X-141211Y400954D01*
X-141544Y401537D01*
X-141711Y402204D01*
X-141544Y402870D01*
X-141211Y403454D01*
X-140711Y403787D01*
X-140211Y403870D01*
X-139711Y403787D01*
X-139211Y403454D01*
X-138878Y402870D01*
X-138794Y402204D01*
X-138878Y401537D01*
X-139211Y400954D01*
X-139711Y400620D01*
X-140211Y400537D01*
G01X-136028Y403870D02*
Y401537D01*
X-135694Y400954D01*
X-135194Y400620D01*
X-134611Y400537D01*
X-134028Y400620D01*
X-133528Y400954D01*
X-133194Y401537D01*
G01Y400537D02*
Y403870D01*
G01X-129011Y405537D02*
Y400537D01*
G01X-130178Y403870D02*
X-127844D01*
G01X-116478Y403454D02*
X-117061Y403787D01*
X-117561Y403870D01*
X-118228Y403704D01*
X-118728Y403370D01*
X-119061Y402787D01*
X-119144Y402204D01*
X-119061Y401620D01*
X-118728Y401120D01*
X-118228Y400704D01*
X-117561Y400537D01*
X-116978Y400704D01*
X-116478Y401037D01*
G01X-112211Y400537D02*
X-112711Y400620D01*
X-113211Y400954D01*
X-113544Y401537D01*
X-113711Y402204D01*
X-113544Y402870D01*
X-113211Y403454D01*
X-112711Y403787D01*
X-112211Y403870D01*
X-111711Y403787D01*
X-111211Y403454D01*
X-110878Y402870D01*
X-110794Y402204D01*
X-110878Y401537D01*
X-111211Y400954D01*
X-111711Y400620D01*
X-112211Y400537D01*
G01X-108028D02*
Y403870D01*
G01Y403037D02*
X-107694Y403454D01*
X-107194Y403787D01*
X-106528Y403870D01*
X-105944Y403787D01*
X-105444Y403454D01*
X-105194Y402870D01*
Y400537D01*
G01X-102428D02*
Y403870D01*
G01Y403037D02*
X-102094Y403454D01*
X-101594Y403787D01*
X-100928Y403870D01*
X-100344Y403787D01*
X-99844Y403454D01*
X-99594Y402870D01*
Y400537D01*
G01X-96661Y402787D02*
X-93994D01*
X-94244Y403370D01*
X-94661Y403704D01*
X-95244Y403870D01*
X-95828Y403787D01*
X-96328Y403537D01*
X-96661Y402954D01*
X-96828Y402454D01*
Y401954D01*
X-96661Y401454D01*
X-96244Y400954D01*
X-95744Y400620D01*
X-95161Y400537D01*
X-94578Y400704D01*
X-93994Y401204D01*
G01X-88478Y403454D02*
X-89061Y403787D01*
X-89561Y403870D01*
X-90228Y403704D01*
X-90728Y403370D01*
X-91061Y402787D01*
X-91144Y402204D01*
X-91061Y401620D01*
X-90728Y401120D01*
X-90228Y400704D01*
X-89561Y400537D01*
X-88978Y400704D01*
X-88478Y401037D01*
G01X-84211Y405537D02*
Y400537D01*
G01X-85378Y403870D02*
X-83044D01*
G01X-78611D02*
Y400537D01*
G01Y405204D02*
X-78778Y405287D01*
Y405454D01*
X-78611Y405537D01*
X-78444Y405454D01*
Y405287D01*
X-78611Y405204D01*
G01X-74428Y400537D02*
Y403870D01*
G01Y403037D02*
X-74094Y403454D01*
X-73594Y403787D01*
X-72928Y403870D01*
X-72344Y403787D01*
X-71844Y403454D01*
X-71594Y402870D01*
Y400537D01*
G01X-68578Y399287D02*
X-67994Y398954D01*
X-67328Y398870D01*
X-66744Y398954D01*
X-66244Y399370D01*
X-65911Y399954D01*
Y403870D01*
G01Y403204D02*
X-66244Y403537D01*
X-66744Y403787D01*
X-67328Y403870D01*
X-67994Y403704D01*
X-68411Y403370D01*
X-68744Y402787D01*
X-68911Y402204D01*
X-68828Y401704D01*
X-68494Y401120D01*
X-67994Y400704D01*
X-67328Y400537D01*
X-66828Y400620D01*
X-66244Y400954D01*
X-65911Y401287D01*
G01X-56211Y405537D02*
Y400537D01*
G01X-57378Y403870D02*
X-55044D01*
G01X-50611Y400537D02*
X-51111Y400620D01*
X-51611Y400954D01*
X-51944Y401537D01*
X-52111Y402204D01*
X-51944Y402870D01*
X-51611Y403454D01*
X-51111Y403787D01*
X-50611Y403870D01*
X-50111Y403787D01*
X-49611Y403454D01*
X-49278Y402870D01*
X-49194Y402204D01*
X-49278Y401537D01*
X-49611Y400954D01*
X-50111Y400620D01*
X-50611Y400537D01*
G01X-39411D02*
X-39911Y400620D01*
X-40411Y400954D01*
X-40744Y401537D01*
X-40911Y402204D01*
X-40744Y402870D01*
X-40411Y403454D01*
X-39911Y403787D01*
X-39411Y403870D01*
X-38911Y403787D01*
X-38411Y403454D01*
X-38078Y402870D01*
X-37994Y402204D01*
X-38078Y401537D01*
X-38411Y400954D01*
X-38911Y400620D01*
X-39411Y400537D01*
G01X-33811Y405537D02*
Y400537D01*
G01X-34978Y403870D02*
X-32644D01*
G01X-29628Y400537D02*
Y405537D01*
G01Y403120D02*
X-29211Y403537D01*
X-28794Y403787D01*
X-28128Y403870D01*
X-27628Y403787D01*
X-27044Y403454D01*
X-26794Y402954D01*
Y400537D01*
G01X-23861Y402787D02*
X-21194D01*
X-21444Y403370D01*
X-21861Y403704D01*
X-22444Y403870D01*
X-23028Y403787D01*
X-23528Y403537D01*
X-23861Y402954D01*
X-24028Y402454D01*
Y401954D01*
X-23861Y401454D01*
X-23444Y400954D01*
X-22944Y400620D01*
X-22361Y400537D01*
X-21778Y400704D01*
X-21194Y401204D01*
G01X-18178Y400537D02*
Y403870D01*
G01Y403204D02*
X-17761Y403537D01*
X-17344Y403787D01*
X-16761Y403870D01*
X-16344Y403787D01*
X-15844Y403537D01*
G01X-5811Y400537D02*
Y405537D01*
G01X1289Y400537D02*
Y403870D01*
G01Y403287D02*
X956Y403620D01*
X456Y403787D01*
X-128Y403870D01*
X-711Y403704D01*
X-1211Y403370D01*
X-1544Y402870D01*
X-1711Y402204D01*
X-1544Y401537D01*
X-1211Y401037D01*
X-711Y400704D01*
X-128Y400537D01*
X456Y400620D01*
X956Y400870D01*
X1289Y401204D01*
G01X3639Y399037D02*
X4139Y398870D01*
X4806Y399037D01*
X5222Y399370D01*
X5556Y399787D01*
X6056Y401120D01*
X7139Y403870D01*
G01X4472D02*
X6056Y401120D01*
G01X9739Y402787D02*
X12406D01*
X12156Y403370D01*
X11739Y403704D01*
X11156Y403870D01*
X10572Y403787D01*
X10072Y403537D01*
X9739Y402954D01*
X9572Y402454D01*
Y401954D01*
X9739Y401454D01*
X10156Y400954D01*
X10656Y400620D01*
X11239Y400537D01*
X11822Y400704D01*
X12406Y401204D01*
G01X15422Y400537D02*
Y403870D01*
G01Y403204D02*
X15839Y403537D01*
X16256Y403787D01*
X16839Y403870D01*
X17256Y403787D01*
X17756Y403537D01*
G01X20939Y401120D02*
X21356Y400787D01*
X21939Y400537D01*
X22439D01*
X22939Y400704D01*
X23272Y400954D01*
X23439Y401287D01*
X23356Y401787D01*
X23022Y402037D01*
X21522Y402537D01*
X21189Y403120D01*
X21356Y403537D01*
X21689Y403787D01*
X22189Y403870D01*
X22689Y403787D01*
X23189Y403537D01*
G01X28206Y398870D02*
X29039Y399704D01*
X29456Y400537D01*
Y403870D01*
X29039Y404704D01*
X28206Y405537D01*
G01X-164154Y411247D02*
Y416247D01*
X-162488D01*
X-161821Y415997D01*
X-161321Y415664D01*
X-160904Y415164D01*
X-160571Y414580D01*
X-160488Y413747D01*
X-160571Y412914D01*
X-160904Y412330D01*
X-161321Y411830D01*
X-161821Y411497D01*
X-162488Y411247D01*
X-164154D01*
G01X-157971Y413497D02*
X-155304D01*
X-155554Y414080D01*
X-155971Y414414D01*
X-156554Y414580D01*
X-157138Y414497D01*
X-157638Y414247D01*
X-157971Y413664D01*
X-158138Y413164D01*
Y412664D01*
X-157971Y412164D01*
X-157554Y411664D01*
X-157054Y411330D01*
X-156471Y411247D01*
X-155888Y411414D01*
X-155304Y411914D01*
G01X-151121Y411247D02*
Y416247D01*
G01X-146771Y413497D02*
X-144104D01*
X-144354Y414080D01*
X-144771Y414414D01*
X-145354Y414580D01*
X-145938Y414497D01*
X-146438Y414247D01*
X-146771Y413664D01*
X-146938Y413164D01*
Y412664D01*
X-146771Y412164D01*
X-146354Y411664D01*
X-145854Y411330D01*
X-145271Y411247D01*
X-144688Y411414D01*
X-144104Y411914D01*
G01X-139921Y416247D02*
Y411247D01*
G01X-141088Y414580D02*
X-138754D01*
G01X-135571Y413497D02*
X-132904D01*
X-133154Y414080D01*
X-133571Y414414D01*
X-134154Y414580D01*
X-134738Y414497D01*
X-135238Y414247D01*
X-135571Y413664D01*
X-135738Y413164D01*
Y412664D01*
X-135571Y412164D01*
X-135154Y411664D01*
X-134654Y411330D01*
X-134071Y411247D01*
X-133488Y411414D01*
X-132904Y411914D01*
G01X-124538Y411247D02*
Y414580D01*
G01Y413747D02*
X-124204Y414164D01*
X-123704Y414497D01*
X-123038Y414580D01*
X-122454Y414497D01*
X-121954Y414164D01*
X-121704Y413580D01*
Y411247D01*
G01X-117521D02*
X-118021Y411330D01*
X-118521Y411664D01*
X-118854Y412247D01*
X-119021Y412914D01*
X-118854Y413580D01*
X-118521Y414164D01*
X-118021Y414497D01*
X-117521Y414580D01*
X-117021Y414497D01*
X-116521Y414164D01*
X-116188Y413580D01*
X-116104Y412914D01*
X-116188Y412247D01*
X-116521Y411664D01*
X-117021Y411330D01*
X-117521Y411247D01*
G01X-113338D02*
Y414580D01*
G01Y413747D02*
X-113004Y414164D01*
X-112504Y414497D01*
X-111838Y414580D01*
X-111254Y414497D01*
X-110754Y414164D01*
X-110504Y413580D01*
Y411247D01*
G01X-107404Y412914D02*
X-105238D01*
G01X-101221Y411247D02*
Y415497D01*
X-101054Y415914D01*
X-100721Y416164D01*
X-100221Y416247D01*
X-99721Y416080D01*
X-99471Y415664D01*
G01X-100471Y414247D02*
X-102138D01*
G01X-96538Y414580D02*
Y412247D01*
X-96204Y411664D01*
X-95704Y411330D01*
X-95121Y411247D01*
X-94538Y411330D01*
X-94038Y411664D01*
X-93704Y412247D01*
G01Y411247D02*
Y414580D01*
G01X-90938Y411247D02*
Y414580D01*
G01Y413747D02*
X-90604Y414164D01*
X-90104Y414497D01*
X-89438Y414580D01*
X-88854Y414497D01*
X-88354Y414164D01*
X-88104Y413580D01*
Y411247D01*
G01X-82588Y414164D02*
X-83171Y414497D01*
X-83671Y414580D01*
X-84338Y414414D01*
X-84838Y414080D01*
X-85171Y413497D01*
X-85254Y412914D01*
X-85171Y412330D01*
X-84838Y411830D01*
X-84338Y411414D01*
X-83671Y411247D01*
X-83088Y411414D01*
X-82588Y411747D01*
G01X-78321Y416247D02*
Y411247D01*
G01X-79488Y414580D02*
X-77154D01*
G01X-72721D02*
Y411247D01*
G01Y415914D02*
X-72888Y415997D01*
Y416164D01*
X-72721Y416247D01*
X-72554Y416164D01*
Y415997D01*
X-72721Y415914D01*
G01X-67121Y411247D02*
X-67621Y411330D01*
X-68121Y411664D01*
X-68454Y412247D01*
X-68621Y412914D01*
X-68454Y413580D01*
X-68121Y414164D01*
X-67621Y414497D01*
X-67121Y414580D01*
X-66621Y414497D01*
X-66121Y414164D01*
X-65788Y413580D01*
X-65704Y412914D01*
X-65788Y412247D01*
X-66121Y411664D01*
X-66621Y411330D01*
X-67121Y411247D01*
G01X-62938D02*
Y414580D01*
G01Y413747D02*
X-62604Y414164D01*
X-62104Y414497D01*
X-61438Y414580D01*
X-60854Y414497D01*
X-60354Y414164D01*
X-60104Y413580D01*
Y411247D01*
G01X-54421D02*
Y414580D01*
G01Y413997D02*
X-54754Y414330D01*
X-55254Y414497D01*
X-55838Y414580D01*
X-56421Y414414D01*
X-56921Y414080D01*
X-57254Y413580D01*
X-57421Y412914D01*
X-57254Y412247D01*
X-56921Y411747D01*
X-56421Y411414D01*
X-55838Y411247D01*
X-55254Y411330D01*
X-54754Y411580D01*
X-54421Y411914D01*
G01X-50321Y411247D02*
Y416247D01*
G01X-40621Y409580D02*
Y414580D01*
G01Y413830D02*
X-40204Y414247D01*
X-39788Y414497D01*
X-39121Y414580D01*
X-38538Y414497D01*
X-37954Y414080D01*
X-37704Y413497D01*
X-37621Y412914D01*
X-37704Y412330D01*
X-37954Y411747D01*
X-38454Y411414D01*
X-39121Y411247D01*
X-39704Y411330D01*
X-40288Y411580D01*
X-40621Y411914D01*
G01X-32021Y411247D02*
Y414580D01*
G01Y413997D02*
X-32354Y414330D01*
X-32854Y414497D01*
X-33438Y414580D01*
X-34021Y414414D01*
X-34521Y414080D01*
X-34854Y413580D01*
X-35021Y412914D01*
X-34854Y412247D01*
X-34521Y411747D01*
X-34021Y411414D01*
X-33438Y411247D01*
X-32854Y411330D01*
X-32354Y411580D01*
X-32021Y411914D01*
G01X-26421Y416247D02*
Y411247D01*
G01Y411997D02*
X-26754Y411580D01*
X-27254Y411330D01*
X-27838Y411247D01*
X-28504Y411414D01*
X-29004Y411830D01*
X-29338Y412330D01*
X-29421Y412914D01*
X-29338Y413497D01*
X-29004Y413997D01*
X-28504Y414414D01*
X-27838Y414580D01*
X-27254Y414497D01*
X-26838Y414330D01*
X-26421Y413997D01*
G01X-16721Y414580D02*
Y411247D01*
G01Y415914D02*
X-16888Y415997D01*
Y416164D01*
X-16721Y416247D01*
X-16554Y416164D01*
Y415997D01*
X-16721Y415914D01*
G01X-12538Y411247D02*
Y414580D01*
G01Y413747D02*
X-12204Y414164D01*
X-11704Y414497D01*
X-11038Y414580D01*
X-10454Y414497D01*
X-9954Y414164D01*
X-9704Y413580D01*
Y411247D01*
G01X1579D02*
Y414580D01*
G01Y413997D02*
X1246Y414330D01*
X746Y414497D01*
X162Y414580D01*
X-421Y414414D01*
X-921Y414080D01*
X-1254Y413580D01*
X-1421Y412914D01*
X-1254Y412247D01*
X-921Y411747D01*
X-421Y411414D01*
X162Y411247D01*
X746Y411330D01*
X1246Y411580D01*
X1579Y411914D01*
G01X5679Y411247D02*
Y416247D01*
G01X11279Y411247D02*
Y416247D01*
G01X20979Y409580D02*
Y414580D01*
G01Y413830D02*
X21396Y414247D01*
X21812Y414497D01*
X22479Y414580D01*
X23062Y414497D01*
X23646Y414080D01*
X23896Y413497D01*
X23979Y412914D01*
X23896Y412330D01*
X23646Y411747D01*
X23146Y411414D01*
X22479Y411247D01*
X21896Y411330D01*
X21312Y411580D01*
X20979Y411914D01*
G01X26912Y411247D02*
Y414580D01*
G01Y413914D02*
X27329Y414247D01*
X27746Y414497D01*
X28329Y414580D01*
X28746Y414497D01*
X29246Y414247D01*
G01X33679Y411247D02*
X33179Y411330D01*
X32679Y411664D01*
X32346Y412247D01*
X32179Y412914D01*
X32346Y413580D01*
X32679Y414164D01*
X33179Y414497D01*
X33679Y414580D01*
X34179Y414497D01*
X34679Y414164D01*
X35012Y413580D01*
X35096Y412914D01*
X35012Y412247D01*
X34679Y411664D01*
X34179Y411330D01*
X33679Y411247D01*
G01X40779Y416247D02*
Y411247D01*
G01Y411997D02*
X40446Y411580D01*
X39946Y411330D01*
X39362Y411247D01*
X38696Y411414D01*
X38196Y411830D01*
X37862Y412330D01*
X37779Y412914D01*
X37862Y413497D01*
X38196Y413997D01*
X38696Y414414D01*
X39362Y414580D01*
X39946Y414497D01*
X40362Y414330D01*
X40779Y413997D01*
G01X43462Y414580D02*
Y412247D01*
X43796Y411664D01*
X44296Y411330D01*
X44879Y411247D01*
X45462Y411330D01*
X45962Y411664D01*
X46296Y412247D01*
G01Y411247D02*
Y414580D01*
G01X51812Y414164D02*
X51229Y414497D01*
X50729Y414580D01*
X50062Y414414D01*
X49562Y414080D01*
X49229Y413497D01*
X49146Y412914D01*
X49229Y412330D01*
X49562Y411830D01*
X50062Y411414D01*
X50729Y411247D01*
X51312Y411414D01*
X51812Y411747D01*
G01X56079Y416247D02*
Y411247D01*
G01X54912Y414580D02*
X57246D01*
G01X60429Y411830D02*
X60846Y411497D01*
X61429Y411247D01*
X61929D01*
X62429Y411414D01*
X62762Y411664D01*
X62929Y411997D01*
X62846Y412497D01*
X62512Y412747D01*
X61012Y413247D01*
X60679Y413830D01*
X60846Y414247D01*
X61179Y414497D01*
X61679Y414580D01*
X62179Y414497D01*
X62679Y414247D01*
G01X67279Y411080D02*
X67112Y411164D01*
Y411330D01*
X67279Y411414D01*
X67446Y411330D01*
Y411164D01*
X67279Y411080D01*
G01X72462Y409580D02*
X71629Y410414D01*
X71212Y411247D01*
Y414580D01*
X71629Y415414D01*
X72462Y416247D01*
G01X77479D02*
X79479D01*
G01X78479D02*
Y411247D01*
G01X77479D02*
X79479D01*
G01X82829Y411830D02*
X83246Y411497D01*
X83829Y411247D01*
X84329D01*
X84829Y411414D01*
X85162Y411664D01*
X85329Y411997D01*
X85246Y412497D01*
X84912Y412747D01*
X83412Y413247D01*
X83079Y413830D01*
X83246Y414247D01*
X83579Y414497D01*
X84079Y414580D01*
X84579Y414497D01*
X85079Y414247D01*
G01X89679Y411247D02*
X89179Y411330D01*
X88679Y411664D01*
X88346Y412247D01*
X88179Y412914D01*
X88346Y413580D01*
X88679Y414164D01*
X89179Y414497D01*
X89679Y414580D01*
X90179Y414497D01*
X90679Y414164D01*
X91012Y413580D01*
X91096Y412914D01*
X91012Y412247D01*
X90679Y411664D01*
X90179Y411330D01*
X89679Y411247D01*
G01X95279D02*
Y416247D01*
G01X102379Y411247D02*
Y414580D01*
G01Y413997D02*
X102046Y414330D01*
X101546Y414497D01*
X100962Y414580D01*
X100379Y414414D01*
X99879Y414080D01*
X99546Y413580D01*
X99379Y412914D01*
X99546Y412247D01*
X99879Y411747D01*
X100379Y411414D01*
X100962Y411247D01*
X101546Y411330D01*
X102046Y411580D01*
X102379Y411914D01*
G01X106479Y416247D02*
Y411247D01*
G01X105312Y414580D02*
X107646D01*
G01X110829Y413497D02*
X113496D01*
X113246Y414080D01*
X112829Y414414D01*
X112246Y414580D01*
X111662Y414497D01*
X111162Y414247D01*
X110829Y413664D01*
X110662Y413164D01*
Y412664D01*
X110829Y412164D01*
X111246Y411664D01*
X111746Y411330D01*
X112329Y411247D01*
X112912Y411414D01*
X113496Y411914D01*
G01X121779Y409580D02*
Y414580D01*
G01Y413830D02*
X122196Y414247D01*
X122612Y414497D01*
X123279Y414580D01*
X123862Y414497D01*
X124446Y414080D01*
X124696Y413497D01*
X124779Y412914D01*
X124696Y412330D01*
X124446Y411747D01*
X123946Y411414D01*
X123279Y411247D01*
X122696Y411330D01*
X122112Y411580D01*
X121779Y411914D01*
G01X130379Y411247D02*
Y414580D01*
G01Y413997D02*
X130046Y414330D01*
X129546Y414497D01*
X128962Y414580D01*
X128379Y414414D01*
X127879Y414080D01*
X127546Y413580D01*
X127379Y412914D01*
X127546Y412247D01*
X127879Y411747D01*
X128379Y411414D01*
X128962Y411247D01*
X129546Y411330D01*
X130046Y411580D01*
X130379Y411914D01*
G01X135979Y416247D02*
Y411247D01*
G01Y411997D02*
X135646Y411580D01*
X135146Y411330D01*
X134562Y411247D01*
X133896Y411414D01*
X133396Y411830D01*
X133062Y412330D01*
X132979Y412914D01*
X133062Y413497D01*
X133396Y413997D01*
X133896Y414414D01*
X134562Y414580D01*
X135146Y414497D01*
X135562Y414330D01*
X135979Y413997D01*
G01X-111788Y70260D02*
X-111521Y70460D01*
X-111321Y70794D01*
X-111188Y71260D01*
X-111321Y71660D01*
X-111588Y71927D01*
X-112054Y72127D01*
X-113854D01*
Y68127D01*
X-111654D01*
X-111188Y68394D01*
X-110921Y68794D01*
X-110788Y69260D01*
X-110921Y69727D01*
X-111321Y70127D01*
X-111788Y70260D01*
X-113854D01*
G01X-113988Y117627D02*
X-112321Y121627D01*
X-110654Y117627D01*
G01X-111254Y119027D02*
X-113388D01*
G01X-73294Y94834D02*
X-73694Y95034D01*
X-74161Y95167D01*
X-74694D01*
X-75294Y94967D01*
X-75761Y94634D01*
X-76094Y94234D01*
X-76361Y93567D01*
X-76428Y92967D01*
X-76294Y92367D01*
X-76094Y91967D01*
X-75694Y91567D01*
X-75228Y91300D01*
X-74761Y91167D01*
X-74294D01*
X-73828Y91300D01*
X-73428Y91500D01*
X-73094Y91767D01*
G01X-39411Y130797D02*
Y-58203D01*
G01X-31434Y-3816D02*
X-31101Y-3566D01*
X-30851Y-3150D01*
X-30684Y-2566D01*
X-30851Y-2066D01*
X-31184Y-1733D01*
X-31768Y-1483D01*
X-34018D01*
Y-6483D01*
X-31268D01*
X-30684Y-6150D01*
X-30351Y-5650D01*
X-30184Y-5066D01*
X-30351Y-4483D01*
X-30851Y-3983D01*
X-31434Y-3816D01*
X-34018D01*
G01X-27918Y-3150D02*
Y-5483D01*
X-27584Y-6066D01*
X-27084Y-6400D01*
X-26501Y-6483D01*
X-25918Y-6400D01*
X-25418Y-6066D01*
X-25084Y-5483D01*
G01Y-6483D02*
Y-3150D01*
G01X-23401Y-6483D02*
Y-3150D01*
G01Y-4066D02*
X-23151Y-3650D01*
X-22734Y-3316D01*
X-22151Y-3150D01*
X-21568Y-3316D01*
X-21151Y-3650D01*
X-20901Y-4066D01*
Y-6483D01*
G01Y-4066D02*
X-20651Y-3650D01*
X-20234Y-3316D01*
X-19651Y-3150D01*
X-19068Y-3316D01*
X-18651Y-3650D01*
X-18401Y-4150D01*
Y-6483D01*
G01X-16801Y-8150D02*
Y-3150D01*
G01Y-3900D02*
X-16384Y-3483D01*
X-15968Y-3233D01*
X-15301Y-3150D01*
X-14718Y-3233D01*
X-14134Y-3650D01*
X-13884Y-4233D01*
X-13801Y-4816D01*
X-13884Y-5400D01*
X-14134Y-5983D01*
X-14634Y-6316D01*
X-15301Y-6483D01*
X-15884Y-6400D01*
X-16468Y-6150D01*
X-16801Y-5816D01*
G01X-32891Y34510D02*
X-31391Y31177D01*
X-29891Y34510D01*
G01X-25791D02*
Y31177D01*
G01Y35844D02*
X-25958Y35927D01*
Y36094D01*
X-25791Y36177D01*
X-25624Y36094D01*
Y35927D01*
X-25791Y35844D01*
G01X-18691Y31177D02*
Y34510D01*
G01Y33927D02*
X-19024Y34260D01*
X-19524Y34427D01*
X-20108Y34510D01*
X-20691Y34344D01*
X-21191Y34010D01*
X-21524Y33510D01*
X-21691Y32844D01*
X-21524Y32177D01*
X-21191Y31677D01*
X-20691Y31344D01*
X-20108Y31177D01*
X-19524Y31260D01*
X-19024Y31510D01*
X-18691Y31844D01*
G01X-33344Y43657D02*
Y48657D01*
X-31678D01*
X-31011Y48407D01*
X-30511Y48074D01*
X-30094Y47574D01*
X-29761Y46990D01*
X-29678Y46157D01*
X-29761Y45324D01*
X-30094Y44740D01*
X-30511Y44240D01*
X-31011Y43907D01*
X-31678Y43657D01*
X-33344D01*
G01X-25911Y46990D02*
Y43657D01*
G01Y48324D02*
X-26078Y48407D01*
Y48574D01*
X-25911Y48657D01*
X-25744Y48574D01*
Y48407D01*
X-25911Y48324D01*
G01X-22811Y43657D02*
Y46990D01*
G01Y46074D02*
X-22561Y46490D01*
X-22144Y46824D01*
X-21561Y46990D01*
X-20978Y46824D01*
X-20561Y46490D01*
X-20311Y46074D01*
Y43657D01*
G01Y46074D02*
X-20061Y46490D01*
X-19644Y46824D01*
X-19061Y46990D01*
X-18478Y46824D01*
X-18061Y46490D01*
X-17811Y45990D01*
Y43657D01*
G01X-16211Y41990D02*
Y46990D01*
G01Y46240D02*
X-15794Y46657D01*
X-15378Y46907D01*
X-14711Y46990D01*
X-14128Y46907D01*
X-13544Y46490D01*
X-13294Y45907D01*
X-13211Y45324D01*
X-13294Y44740D01*
X-13544Y44157D01*
X-14044Y43824D01*
X-14711Y43657D01*
X-15294Y43740D01*
X-15878Y43990D01*
X-16211Y44324D01*
G01X-9111Y43657D02*
Y48657D01*
G01X-4761Y45907D02*
X-2094D01*
X-2344Y46490D01*
X-2761Y46824D01*
X-3344Y46990D01*
X-3928Y46907D01*
X-4428Y46657D01*
X-4761Y46074D01*
X-4928Y45574D01*
Y45074D01*
X-4761Y44574D01*
X-4344Y44074D01*
X-3844Y43740D01*
X-3261Y43657D01*
X-2678Y43824D01*
X-2094Y44324D01*
G01X7189Y43657D02*
Y47907D01*
X7356Y48324D01*
X7689Y48574D01*
X8189Y48657D01*
X8689Y48490D01*
X8939Y48074D01*
G01X7939Y46657D02*
X6272D01*
G01X13289Y43657D02*
X12789Y43740D01*
X12289Y44074D01*
X11956Y44657D01*
X11789Y45324D01*
X11956Y45990D01*
X12289Y46574D01*
X12789Y46907D01*
X13289Y46990D01*
X13789Y46907D01*
X14289Y46574D01*
X14622Y45990D01*
X14706Y45324D01*
X14622Y44657D01*
X14289Y44074D01*
X13789Y43740D01*
X13289Y43657D01*
G01X17722D02*
Y46990D01*
G01Y46324D02*
X18139Y46657D01*
X18556Y46907D01*
X19139Y46990D01*
X19556Y46907D01*
X20056Y46657D01*
G01X30089Y43657D02*
X29589Y43740D01*
X29089Y44074D01*
X28756Y44657D01*
X28589Y45324D01*
X28756Y45990D01*
X29089Y46574D01*
X29589Y46907D01*
X30089Y46990D01*
X30589Y46907D01*
X31089Y46574D01*
X31422Y45990D01*
X31506Y45324D01*
X31422Y44657D01*
X31089Y44074D01*
X30589Y43740D01*
X30089Y43657D01*
G01X34272Y46990D02*
Y44657D01*
X34606Y44074D01*
X35106Y43740D01*
X35689Y43657D01*
X36272Y43740D01*
X36772Y44074D01*
X37106Y44657D01*
G01Y43657D02*
Y46990D01*
G01X41289Y48657D02*
Y43657D01*
G01X40122Y46990D02*
X42456D01*
G01X45639Y45907D02*
X48306D01*
X48056Y46490D01*
X47639Y46824D01*
X47056Y46990D01*
X46472Y46907D01*
X45972Y46657D01*
X45639Y46074D01*
X45472Y45574D01*
Y45074D01*
X45639Y44574D01*
X46056Y44074D01*
X46556Y43740D01*
X47139Y43657D01*
X47722Y43824D01*
X48306Y44324D01*
G01X51322Y43657D02*
Y46990D01*
G01Y46324D02*
X51739Y46657D01*
X52156Y46907D01*
X52739Y46990D01*
X53156Y46907D01*
X53656Y46657D01*
G01X65189Y43657D02*
Y46990D01*
G01Y46407D02*
X64856Y46740D01*
X64356Y46907D01*
X63772Y46990D01*
X63189Y46824D01*
X62689Y46490D01*
X62356Y45990D01*
X62189Y45324D01*
X62356Y44657D01*
X62689Y44157D01*
X63189Y43824D01*
X63772Y43657D01*
X64356Y43740D01*
X64856Y43990D01*
X65189Y44324D01*
G01X67872Y43657D02*
Y46990D01*
G01Y46157D02*
X68206Y46574D01*
X68706Y46907D01*
X69372Y46990D01*
X69956Y46907D01*
X70456Y46574D01*
X70706Y45990D01*
Y43657D01*
G01X76389Y48657D02*
Y43657D01*
G01Y44407D02*
X76056Y43990D01*
X75556Y43740D01*
X74972Y43657D01*
X74306Y43824D01*
X73806Y44240D01*
X73472Y44740D01*
X73389Y45324D01*
X73472Y45907D01*
X73806Y46407D01*
X74306Y46824D01*
X74972Y46990D01*
X75556Y46907D01*
X75972Y46740D01*
X76389Y46407D01*
G01X86089Y46990D02*
Y43657D01*
G01Y48324D02*
X85922Y48407D01*
Y48574D01*
X86089Y48657D01*
X86256Y48574D01*
Y48407D01*
X86089Y48324D01*
G01X90272Y43657D02*
Y46990D01*
G01Y46157D02*
X90606Y46574D01*
X91106Y46907D01*
X91772Y46990D01*
X92356Y46907D01*
X92856Y46574D01*
X93106Y45990D01*
Y43657D01*
G01X95872D02*
Y46990D01*
G01Y46157D02*
X96206Y46574D01*
X96706Y46907D01*
X97372Y46990D01*
X97956Y46907D01*
X98456Y46574D01*
X98706Y45990D01*
Y43657D01*
G01X101639Y45907D02*
X104306D01*
X104056Y46490D01*
X103639Y46824D01*
X103056Y46990D01*
X102472Y46907D01*
X101972Y46657D01*
X101639Y46074D01*
X101472Y45574D01*
Y45074D01*
X101639Y44574D01*
X102056Y44074D01*
X102556Y43740D01*
X103139Y43657D01*
X103722Y43824D01*
X104306Y44324D01*
G01X107322Y43657D02*
Y46990D01*
G01Y46324D02*
X107739Y46657D01*
X108156Y46907D01*
X108739Y46990D01*
X109156Y46907D01*
X109656Y46657D01*
G01X119689Y43657D02*
Y48657D01*
G01X126789Y43657D02*
Y46990D01*
G01Y46407D02*
X126456Y46740D01*
X125956Y46907D01*
X125372Y46990D01*
X124789Y46824D01*
X124289Y46490D01*
X123956Y45990D01*
X123789Y45324D01*
X123956Y44657D01*
X124289Y44157D01*
X124789Y43824D01*
X125372Y43657D01*
X125956Y43740D01*
X126456Y43990D01*
X126789Y44324D01*
G01X129639Y44240D02*
X130056Y43907D01*
X130639Y43657D01*
X131139D01*
X131639Y43824D01*
X131972Y44074D01*
X132139Y44407D01*
X132056Y44907D01*
X131722Y45157D01*
X130222Y45657D01*
X129889Y46240D01*
X130056Y46657D01*
X130389Y46907D01*
X130889Y46990D01*
X131389Y46907D01*
X131889Y46657D01*
G01X135239Y45907D02*
X137906D01*
X137656Y46490D01*
X137239Y46824D01*
X136656Y46990D01*
X136072Y46907D01*
X135572Y46657D01*
X135239Y46074D01*
X135072Y45574D01*
Y45074D01*
X135239Y44574D01*
X135656Y44074D01*
X136156Y43740D01*
X136739Y43657D01*
X137322Y43824D01*
X137906Y44324D01*
G01X140922Y43657D02*
Y46990D01*
G01Y46324D02*
X141339Y46657D01*
X141756Y46907D01*
X142339Y46990D01*
X142756Y46907D01*
X143256Y46657D01*
G01X-32584Y61837D02*
X-30501Y66837D01*
X-28418Y61837D01*
G01X-29168Y63587D02*
X-31834D01*
G01X-26318Y61837D02*
Y65170D01*
G01Y64337D02*
X-25984Y64754D01*
X-25484Y65087D01*
X-24818Y65170D01*
X-24234Y65087D01*
X-23734Y64754D01*
X-23484Y64170D01*
Y61837D01*
G01X-20468Y60587D02*
X-19884Y60254D01*
X-19218Y60170D01*
X-18634Y60254D01*
X-18134Y60670D01*
X-17801Y61254D01*
Y65170D01*
G01Y64504D02*
X-18134Y64837D01*
X-18634Y65087D01*
X-19218Y65170D01*
X-19884Y65004D01*
X-20301Y64670D01*
X-20634Y64087D01*
X-20801Y63504D01*
X-20718Y63004D01*
X-20384Y62420D01*
X-19884Y62004D01*
X-19218Y61837D01*
X-18718Y61920D01*
X-18134Y62254D01*
X-17801Y62587D01*
G01X-13701Y61837D02*
Y66837D01*
G01X-9351Y64087D02*
X-6684D01*
X-6934Y64670D01*
X-7351Y65004D01*
X-7934Y65170D01*
X-8518Y65087D01*
X-9018Y64837D01*
X-9351Y64254D01*
X-9518Y63754D01*
Y63254D01*
X-9351Y62754D01*
X-8934Y62254D01*
X-8434Y61920D01*
X-7851Y61837D01*
X-7268Y62004D01*
X-6684Y62504D01*
G01X-2918Y60170D02*
X-3751Y61004D01*
X-4168Y61837D01*
Y65170D01*
X-3751Y66004D01*
X-2918Y66837D01*
G01X14716Y60170D02*
X15549Y61004D01*
X15966Y61837D01*
Y65170D01*
X15549Y66004D01*
X14716Y66837D01*
G01X-39411Y71797D02*
X260089D01*
G01X-32634Y98224D02*
X-32301Y98474D01*
X-32051Y98890D01*
X-31884Y99474D01*
X-32051Y99974D01*
X-32384Y100307D01*
X-32968Y100557D01*
X-35218D01*
Y95557D01*
X-32468D01*
X-31884Y95890D01*
X-31551Y96390D01*
X-31384Y96974D01*
X-31551Y97557D01*
X-32051Y98057D01*
X-32634Y98224D01*
X-35218D01*
G01X-29201Y95390D02*
X-26201Y100557D01*
G01X-24184Y95557D02*
X-22101Y100557D01*
X-20018Y95557D01*
G01X-20768Y97307D02*
X-23434D01*
G01X-33778Y125257D02*
Y120257D01*
X-30444D01*
G01X-25011D02*
Y123590D01*
G01Y123007D02*
X-25344Y123340D01*
X-25844Y123507D01*
X-26428Y123590D01*
X-27011Y123424D01*
X-27511Y123090D01*
X-27844Y122590D01*
X-28011Y121924D01*
X-27844Y121257D01*
X-27511Y120757D01*
X-27011Y120424D01*
X-26428Y120257D01*
X-25844Y120340D01*
X-25344Y120590D01*
X-25011Y120924D01*
G01X-22161Y120840D02*
X-21744Y120507D01*
X-21161Y120257D01*
X-20661D01*
X-20161Y120424D01*
X-19828Y120674D01*
X-19661Y121007D01*
X-19744Y121507D01*
X-20078Y121757D01*
X-21578Y122257D01*
X-21911Y122840D01*
X-21744Y123257D01*
X-21411Y123507D01*
X-20911Y123590D01*
X-20411Y123507D01*
X-19911Y123257D01*
G01X-16561Y122507D02*
X-13894D01*
X-14144Y123090D01*
X-14561Y123424D01*
X-15144Y123590D01*
X-15728Y123507D01*
X-16228Y123257D01*
X-16561Y122674D01*
X-16728Y122174D01*
Y121674D01*
X-16561Y121174D01*
X-16144Y120674D01*
X-15644Y120340D01*
X-15061Y120257D01*
X-14478Y120424D01*
X-13894Y120924D01*
G01X-10878Y120257D02*
Y123590D01*
G01Y122924D02*
X-10461Y123257D01*
X-10044Y123507D01*
X-9461Y123590D01*
X-9044Y123507D01*
X-8544Y123257D01*
G01X-11Y123590D02*
X1489Y120257D01*
X2989Y123590D01*
G01X7089D02*
Y120257D01*
G01Y124924D02*
X6922Y125007D01*
Y125174D01*
X7089Y125257D01*
X7256Y125174D01*
Y125007D01*
X7089Y124924D01*
G01X14189Y120257D02*
Y123590D01*
G01Y123007D02*
X13856Y123340D01*
X13356Y123507D01*
X12772Y123590D01*
X12189Y123424D01*
X11689Y123090D01*
X11356Y122590D01*
X11189Y121924D01*
X11356Y121257D01*
X11689Y120757D01*
X12189Y120424D01*
X12772Y120257D01*
X13356Y120340D01*
X13856Y120590D01*
X14189Y120924D01*
G01X22639Y120840D02*
X23056Y120507D01*
X23639Y120257D01*
X24139D01*
X24639Y120424D01*
X24972Y120674D01*
X25139Y121007D01*
X25056Y121507D01*
X24722Y121757D01*
X23222Y122257D01*
X22889Y122840D01*
X23056Y123257D01*
X23389Y123507D01*
X23889Y123590D01*
X24389Y123507D01*
X24889Y123257D01*
G01X29489Y123590D02*
Y120257D01*
G01Y124924D02*
X29322Y125007D01*
Y125174D01*
X29489Y125257D01*
X29656Y125174D01*
Y125007D01*
X29489Y124924D01*
G01X33839Y123590D02*
X36339D01*
X33839Y120257D01*
X36339D01*
G01X39439Y122507D02*
X42106D01*
X41856Y123090D01*
X41439Y123424D01*
X40856Y123590D01*
X40272Y123507D01*
X39772Y123257D01*
X39439Y122674D01*
X39272Y122174D01*
Y121674D01*
X39439Y121174D01*
X39856Y120674D01*
X40356Y120340D01*
X40939Y120257D01*
X41522Y120424D01*
X42106Y120924D01*
G01X49806Y123590D02*
X50806Y120257D01*
X51889Y123590D01*
X52972Y120257D01*
X53972Y123590D01*
G01X57489D02*
Y120257D01*
G01Y124924D02*
X57322Y125007D01*
Y125174D01*
X57489Y125257D01*
X57656Y125174D01*
Y125007D01*
X57489Y124924D01*
G01X63089Y125257D02*
Y120257D01*
G01X61922Y123590D02*
X64256D01*
G01X67272Y120257D02*
Y125257D01*
G01Y122840D02*
X67689Y123257D01*
X68106Y123507D01*
X68772Y123590D01*
X69272Y123507D01*
X69856Y123174D01*
X70106Y122674D01*
Y120257D01*
G01X74289D02*
X73789Y120340D01*
X73289Y120674D01*
X72956Y121257D01*
X72789Y121924D01*
X72956Y122590D01*
X73289Y123174D01*
X73789Y123507D01*
X74289Y123590D01*
X74789Y123507D01*
X75289Y123174D01*
X75622Y122590D01*
X75706Y121924D01*
X75622Y121257D01*
X75289Y120674D01*
X74789Y120340D01*
X74289Y120257D01*
G01X78472Y123590D02*
Y121257D01*
X78806Y120674D01*
X79306Y120340D01*
X79889Y120257D01*
X80472Y120340D01*
X80972Y120674D01*
X81306Y121257D01*
G01Y120257D02*
Y123590D01*
G01X85489Y125257D02*
Y120257D01*
G01X84322Y123590D02*
X86656D01*
G01X95189Y118590D02*
Y123590D01*
G01Y122840D02*
X95606Y123257D01*
X96022Y123507D01*
X96689Y123590D01*
X97272Y123507D01*
X97856Y123090D01*
X98106Y122507D01*
X98189Y121924D01*
X98106Y121340D01*
X97856Y120757D01*
X97356Y120424D01*
X96689Y120257D01*
X96106Y120340D01*
X95522Y120590D01*
X95189Y120924D01*
G01X102289Y120257D02*
Y125257D01*
G01X109389Y120257D02*
Y123590D01*
G01Y123007D02*
X109056Y123340D01*
X108556Y123507D01*
X107972Y123590D01*
X107389Y123424D01*
X106889Y123090D01*
X106556Y122590D01*
X106389Y121924D01*
X106556Y121257D01*
X106889Y120757D01*
X107389Y120424D01*
X107972Y120257D01*
X108556Y120340D01*
X109056Y120590D01*
X109389Y120924D01*
G01X113489Y125257D02*
Y120257D01*
G01X112322Y123590D02*
X114656D01*
G01X119089D02*
Y120257D01*
G01Y124924D02*
X118922Y125007D01*
Y125174D01*
X119089Y125257D01*
X119256Y125174D01*
Y125007D01*
X119089Y124924D01*
G01X123272Y120257D02*
Y123590D01*
G01Y122757D02*
X123606Y123174D01*
X124106Y123507D01*
X124772Y123590D01*
X125356Y123507D01*
X125856Y123174D01*
X126106Y122590D01*
Y120257D01*
G01X129122Y119007D02*
X129706Y118674D01*
X130372Y118590D01*
X130956Y118674D01*
X131456Y119090D01*
X131789Y119674D01*
Y123590D01*
G01Y122924D02*
X131456Y123257D01*
X130956Y123507D01*
X130372Y123590D01*
X129706Y123424D01*
X129289Y123090D01*
X128956Y122507D01*
X128789Y121924D01*
X128872Y121424D01*
X129206Y120840D01*
X129706Y120424D01*
X130372Y120257D01*
X130872Y120340D01*
X131456Y120674D01*
X131789Y121007D01*
G01X141072Y118590D02*
X140239Y119424D01*
X139822Y120257D01*
Y123590D01*
X140239Y124424D01*
X141072Y125257D01*
G01X147756Y122924D02*
X148089Y123174D01*
X148339Y123590D01*
X148506Y124174D01*
X148339Y124674D01*
X148006Y125007D01*
X147422Y125257D01*
X145172D01*
Y120257D01*
X147922D01*
X148506Y120590D01*
X148839Y121090D01*
X149006Y121674D01*
X148839Y122257D01*
X148339Y122757D01*
X147756Y122924D01*
X145172D01*
G01X153106Y118590D02*
X153939Y119424D01*
X154356Y120257D01*
Y123590D01*
X153939Y124424D01*
X153106Y125257D01*
G01X-39411Y103797D02*
X260089D01*
G01X-29911Y433130D02*
Y429797D01*
G01Y434464D02*
X-30078Y434547D01*
Y434714D01*
X-29911Y434797D01*
X-29744Y434714D01*
Y434547D01*
X-29911Y434464D01*
G01X-24311Y434797D02*
Y429797D01*
G01X-25478Y433130D02*
X-23144D01*
G01X-19961Y432047D02*
X-17294D01*
X-17544Y432630D01*
X-17961Y432964D01*
X-18544Y433130D01*
X-19128Y433047D01*
X-19628Y432797D01*
X-19961Y432214D01*
X-20128Y431714D01*
Y431214D01*
X-19961Y430714D01*
X-19544Y430214D01*
X-19044Y429880D01*
X-18461Y429797D01*
X-17878Y429964D01*
X-17294Y430464D01*
G01X-15611Y429797D02*
Y433130D01*
G01Y432214D02*
X-15361Y432630D01*
X-14944Y432964D01*
X-14361Y433130D01*
X-13778Y432964D01*
X-13361Y432630D01*
X-13111Y432214D01*
Y429797D01*
G01Y432214D02*
X-12861Y432630D01*
X-12444Y432964D01*
X-11861Y433130D01*
X-11278Y432964D01*
X-10861Y432630D01*
X-10611Y432130D01*
Y429797D01*
G01X9786Y66224D02*
X9386Y66424D01*
X8919Y66557D01*
X8386D01*
X7786Y66357D01*
X7319Y66024D01*
X6986Y65624D01*
X6719Y64957D01*
X6652Y64357D01*
X6786Y63757D01*
X6986Y63357D01*
X7386Y62957D01*
X7852Y62690D01*
X8319Y62557D01*
X8786D01*
X9252Y62690D01*
X9652Y62890D01*
X9986Y63157D01*
G01X161089Y-303203D02*
Y204297D01*
G01Y445297D02*
Y162297D01*
G01X156006Y626297D02*
X158089Y621297D01*
X160172Y626297D01*
G01X161856Y622297D02*
X162356Y621714D01*
X163022Y621380D01*
X163772Y621297D01*
X164439Y621380D01*
X165106Y621797D01*
X165522Y622297D01*
X165606Y622797D01*
X165439Y623380D01*
X164856Y623797D01*
X164272Y623964D01*
X163522D01*
G01X164272D02*
X164772Y624214D01*
X165189Y624630D01*
X165356Y625130D01*
X165189Y625630D01*
X164772Y626047D01*
X164022Y626297D01*
X163272Y626214D01*
X162522Y625880D01*
G01X169289Y621130D02*
X169122Y621214D01*
Y621380D01*
X169289Y621464D01*
X169456Y621380D01*
Y621214D01*
X169289Y621130D01*
G01X175889Y621297D02*
Y626297D01*
X172806Y622714D01*
X176972D01*
G01X180489Y621130D02*
X180322Y621214D01*
Y621380D01*
X180489Y621464D01*
X180656Y621380D01*
Y621214D01*
X180489Y621130D01*
G01X186089Y621297D02*
Y626297D01*
X185089Y625297D01*
G01Y621297D02*
X187089D01*
G01X206906Y625464D02*
X207406Y625964D01*
X207989Y626214D01*
X208656Y626297D01*
X209489Y626130D01*
X210072Y625714D01*
X210239Y625214D01*
X210156Y624714D01*
X209822Y624297D01*
X208156Y623464D01*
X207406Y622880D01*
X206906Y622047D01*
X206739Y621297D01*
X210239D01*
G01X214089Y626297D02*
X213422Y626130D01*
X212922Y625714D01*
X212589Y625214D01*
X212339Y624547D01*
X212256Y623797D01*
X212339Y623047D01*
X212589Y622380D01*
X212922Y621880D01*
X213422Y621464D01*
X214089Y621297D01*
X214756Y621464D01*
X215256Y621880D01*
X215589Y622380D01*
X215839Y623047D01*
X215922Y623797D01*
X215839Y624547D01*
X215589Y625214D01*
X215256Y625714D01*
X214756Y626130D01*
X214089Y626297D01*
G01X219689Y621297D02*
Y626297D01*
X218689Y625297D01*
G01Y621297D02*
X220689D01*
G01X223456Y622047D02*
X223956Y621630D01*
X224539Y621380D01*
X225289Y621297D01*
X226039Y621464D01*
X226622Y621797D01*
X227039Y622380D01*
X227122Y623047D01*
X226956Y623714D01*
X226539Y624130D01*
X225956Y624464D01*
X225372Y624547D01*
X224789Y624464D01*
X224039Y624130D01*
X224289Y626297D01*
X226539D01*
G01X229389Y621130D02*
X232389Y626297D01*
G01X236489D02*
X235822Y626130D01*
X235322Y625714D01*
X234989Y625214D01*
X234739Y624547D01*
X234656Y623797D01*
X234739Y623047D01*
X234989Y622380D01*
X235322Y621880D01*
X235822Y621464D01*
X236489Y621297D01*
X237156Y621464D01*
X237656Y621880D01*
X237989Y622380D01*
X238239Y623047D01*
X238322Y623797D01*
X238239Y624547D01*
X237989Y625214D01*
X237656Y625714D01*
X237156Y626130D01*
X236489Y626297D01*
G01X240506Y623380D02*
X241089Y623964D01*
X241589Y624297D01*
X242256Y624464D01*
X242839Y624297D01*
X243256Y623964D01*
X243589Y623464D01*
X243672Y622880D01*
X243589Y622380D01*
X243256Y621880D01*
X242756Y621464D01*
X242172Y621297D01*
X241506Y621464D01*
X240922Y621964D01*
X240589Y622714D01*
X240506Y623547D01*
X240672Y624630D01*
X240922Y625214D01*
X241339Y625797D01*
X241922Y626214D01*
X242506Y626297D01*
X243089Y626130D01*
X243506Y625714D01*
G01X174756Y-282203D02*
X171422Y-280536D01*
X174756Y-278870D01*
G01X177606Y-281286D02*
X179772D01*
G01Y-279786D02*
X177606D01*
G01X184289Y-282203D02*
Y-277203D01*
X183289Y-278203D01*
G01Y-282203D02*
X185289D01*
G01X189889Y-282370D02*
X189722Y-282286D01*
Y-282120D01*
X189889Y-282036D01*
X190056Y-282120D01*
Y-282286D01*
X189889Y-282370D01*
G01X196489Y-282203D02*
Y-277203D01*
X193406Y-280786D01*
X197572D01*
G01X198589Y-282203D02*
Y-278870D01*
G01Y-279786D02*
X198839Y-279370D01*
X199256Y-279036D01*
X199839Y-278870D01*
X200422Y-279036D01*
X200839Y-279370D01*
X201089Y-279786D01*
Y-282203D01*
G01Y-279786D02*
X201339Y-279370D01*
X201756Y-279036D01*
X202339Y-278870D01*
X202922Y-279036D01*
X203339Y-279370D01*
X203589Y-279870D01*
Y-282203D01*
G01X206689Y-278870D02*
Y-282203D01*
G01Y-277536D02*
X206522Y-277453D01*
Y-277286D01*
X206689Y-277203D01*
X206856Y-277286D01*
Y-277453D01*
X206689Y-277536D01*
G01X212289Y-282203D02*
Y-277203D01*
G01X170922Y-298703D02*
Y-293703D01*
X173089Y-297870D01*
X175256Y-293703D01*
Y-298703D01*
G01X177272Y-295370D02*
Y-297703D01*
X177606Y-298286D01*
X178106Y-298620D01*
X178689Y-298703D01*
X179272Y-298620D01*
X179772Y-298286D01*
X180106Y-297703D01*
G01Y-298703D02*
Y-295370D01*
G01X183039Y-298120D02*
X183456Y-298453D01*
X184039Y-298703D01*
X184539D01*
X185039Y-298536D01*
X185372Y-298286D01*
X185539Y-297953D01*
X185456Y-297453D01*
X185122Y-297203D01*
X183622Y-296703D01*
X183289Y-296120D01*
X183456Y-295703D01*
X183789Y-295453D01*
X184289Y-295370D01*
X184789Y-295453D01*
X185289Y-295703D01*
G01X189889Y-293703D02*
Y-298703D01*
G01X188722Y-295370D02*
X191056D01*
G01X200589Y-298703D02*
Y-294453D01*
X200756Y-294036D01*
X201089Y-293786D01*
X201589Y-293703D01*
X202089Y-293870D01*
X202339Y-294286D01*
G01X201339Y-295703D02*
X199672D01*
G01X206689Y-298703D02*
X206189Y-298620D01*
X205689Y-298286D01*
X205356Y-297703D01*
X205189Y-297036D01*
X205356Y-296370D01*
X205689Y-295786D01*
X206189Y-295453D01*
X206689Y-295370D01*
X207189Y-295453D01*
X207689Y-295786D01*
X208022Y-296370D01*
X208106Y-297036D01*
X208022Y-297703D01*
X207689Y-298286D01*
X207189Y-298620D01*
X206689Y-298703D01*
G01X212289D02*
Y-293703D01*
G01X217889Y-298703D02*
Y-293703D01*
G01X223489Y-298703D02*
X222989Y-298620D01*
X222489Y-298286D01*
X222156Y-297703D01*
X221989Y-297036D01*
X222156Y-296370D01*
X222489Y-295786D01*
X222989Y-295453D01*
X223489Y-295370D01*
X223989Y-295453D01*
X224489Y-295786D01*
X224822Y-296370D01*
X224906Y-297036D01*
X224822Y-297703D01*
X224489Y-298286D01*
X223989Y-298620D01*
X223489Y-298703D01*
G01X227006Y-295370D02*
X228006Y-298703D01*
X229089Y-295370D01*
X230172Y-298703D01*
X231172Y-295370D01*
G01X173089Y-262203D02*
X172422Y-262370D01*
X171922Y-262786D01*
X171589Y-263286D01*
X171339Y-263953D01*
X171256Y-264703D01*
X171339Y-265453D01*
X171589Y-266120D01*
X171922Y-266620D01*
X172422Y-267036D01*
X173089Y-267203D01*
X173756Y-267036D01*
X174256Y-266620D01*
X174589Y-266120D01*
X174839Y-265453D01*
X174922Y-264703D01*
X174839Y-263953D01*
X174589Y-263286D01*
X174256Y-262786D01*
X173756Y-262370D01*
X173089Y-262203D01*
G01X178689Y-267370D02*
X178522Y-267286D01*
Y-267120D01*
X178689Y-267036D01*
X178856Y-267120D01*
Y-267286D01*
X178689Y-267370D01*
G01X182456Y-266203D02*
X182956Y-266786D01*
X183622Y-267120D01*
X184372Y-267203D01*
X185039Y-267120D01*
X185706Y-266703D01*
X186122Y-266203D01*
X186206Y-265703D01*
X186039Y-265120D01*
X185456Y-264703D01*
X184872Y-264536D01*
X184122D01*
G01X184872D02*
X185372Y-264286D01*
X185789Y-263870D01*
X185956Y-263370D01*
X185789Y-262870D01*
X185372Y-262453D01*
X184622Y-262203D01*
X183872Y-262286D01*
X183122Y-262620D01*
G01X187389Y-265536D02*
X188222Y-263870D01*
X189056D01*
X190722Y-267203D01*
X191556D01*
X192389Y-265536D01*
G01X195489Y-262203D02*
X194822Y-262370D01*
X194322Y-262786D01*
X193989Y-263286D01*
X193739Y-263953D01*
X193656Y-264703D01*
X193739Y-265453D01*
X193989Y-266120D01*
X194322Y-266620D01*
X194822Y-267036D01*
X195489Y-267203D01*
X196156Y-267036D01*
X196656Y-266620D01*
X196989Y-266120D01*
X197239Y-265453D01*
X197322Y-264703D01*
X197239Y-263953D01*
X196989Y-263286D01*
X196656Y-262786D01*
X196156Y-262370D01*
X195489Y-262203D01*
G01X201089Y-267370D02*
X200922Y-267286D01*
Y-267120D01*
X201089Y-267036D01*
X201256Y-267120D01*
Y-267286D01*
X201089Y-267370D01*
G01X206522Y-267203D02*
X206689Y-266120D01*
X206939Y-265203D01*
X207272Y-264370D01*
X207689Y-263453D01*
X208356Y-262203D01*
X205022D01*
G01X209789Y-267203D02*
Y-263870D01*
G01Y-264786D02*
X210039Y-264370D01*
X210456Y-264036D01*
X211039Y-263870D01*
X211622Y-264036D01*
X212039Y-264370D01*
X212289Y-264786D01*
Y-267203D01*
G01Y-264786D02*
X212539Y-264370D01*
X212956Y-264036D01*
X213539Y-263870D01*
X214122Y-264036D01*
X214539Y-264370D01*
X214789Y-264870D01*
Y-267203D01*
G01X217889Y-263870D02*
Y-267203D01*
G01Y-262536D02*
X217722Y-262453D01*
Y-262286D01*
X217889Y-262203D01*
X218056Y-262286D01*
Y-262453D01*
X217889Y-262536D01*
G01X223489Y-267203D02*
Y-262203D01*
G01X172172Y-235536D02*
X174172D01*
G01X173089Y-234453D02*
Y-236620D01*
G01X177189Y-237370D02*
X180189Y-232203D01*
G01X183206Y-235536D02*
X185372D01*
G01X189889Y-237203D02*
Y-232203D01*
X188889Y-233203D01*
G01Y-237203D02*
X190889D01*
G01X192989D02*
Y-233870D01*
G01Y-234786D02*
X193239Y-234370D01*
X193656Y-234036D01*
X194239Y-233870D01*
X194822Y-234036D01*
X195239Y-234370D01*
X195489Y-234786D01*
Y-237203D01*
G01Y-234786D02*
X195739Y-234370D01*
X196156Y-234036D01*
X196739Y-233870D01*
X197322Y-234036D01*
X197739Y-234370D01*
X197989Y-234870D01*
Y-237203D01*
G01X201089Y-233870D02*
Y-237203D01*
G01Y-232536D02*
X200922Y-232453D01*
Y-232286D01*
X201089Y-232203D01*
X201256Y-232286D01*
Y-232453D01*
X201089Y-232536D01*
G01X206689Y-237203D02*
Y-232203D01*
G01X173089Y-248703D02*
X172422Y-248870D01*
X171922Y-249286D01*
X171589Y-249786D01*
X171339Y-250453D01*
X171256Y-251203D01*
X171339Y-251953D01*
X171589Y-252620D01*
X171922Y-253120D01*
X172422Y-253536D01*
X173089Y-253703D01*
X173756Y-253536D01*
X174256Y-253120D01*
X174589Y-252620D01*
X174839Y-251953D01*
X174922Y-251203D01*
X174839Y-250453D01*
X174589Y-249786D01*
X174256Y-249286D01*
X173756Y-248870D01*
X173089Y-248703D01*
G01X178689Y-253870D02*
X178522Y-253786D01*
Y-253620D01*
X178689Y-253536D01*
X178856Y-253620D01*
Y-253786D01*
X178689Y-253870D01*
G01X182456Y-252703D02*
X182956Y-253286D01*
X183622Y-253620D01*
X184372Y-253703D01*
X185039Y-253620D01*
X185706Y-253203D01*
X186122Y-252703D01*
X186206Y-252203D01*
X186039Y-251620D01*
X185456Y-251203D01*
X184872Y-251036D01*
X184122D01*
G01X184872D02*
X185372Y-250786D01*
X185789Y-250370D01*
X185956Y-249870D01*
X185789Y-249370D01*
X185372Y-248953D01*
X184622Y-248703D01*
X183872Y-248786D01*
X183122Y-249120D01*
G01X187389Y-252036D02*
X188222Y-250370D01*
X189056D01*
X190722Y-253703D01*
X191556D01*
X192389Y-252036D01*
G01X195489Y-248703D02*
X194822Y-248870D01*
X194322Y-249286D01*
X193989Y-249786D01*
X193739Y-250453D01*
X193656Y-251203D01*
X193739Y-251953D01*
X193989Y-252620D01*
X194322Y-253120D01*
X194822Y-253536D01*
X195489Y-253703D01*
X196156Y-253536D01*
X196656Y-253120D01*
X196989Y-252620D01*
X197239Y-251953D01*
X197322Y-251203D01*
X197239Y-250453D01*
X196989Y-249786D01*
X196656Y-249286D01*
X196156Y-248870D01*
X195489Y-248703D01*
G01X201089Y-253870D02*
X200922Y-253786D01*
Y-253620D01*
X201089Y-253536D01*
X201256Y-253620D01*
Y-253786D01*
X201089Y-253870D01*
G01X206522Y-253703D02*
X206689Y-252620D01*
X206939Y-251703D01*
X207272Y-250870D01*
X207689Y-249953D01*
X208356Y-248703D01*
X205022D01*
G01X209789Y-253703D02*
Y-250370D01*
G01Y-251286D02*
X210039Y-250870D01*
X210456Y-250536D01*
X211039Y-250370D01*
X211622Y-250536D01*
X212039Y-250870D01*
X212289Y-251286D01*
Y-253703D01*
G01Y-251286D02*
X212539Y-250870D01*
X212956Y-250536D01*
X213539Y-250370D01*
X214122Y-250536D01*
X214539Y-250870D01*
X214789Y-251370D01*
Y-253703D01*
G01X217889Y-250370D02*
Y-253703D01*
G01Y-249036D02*
X217722Y-248953D01*
Y-248786D01*
X217889Y-248703D01*
X218056Y-248786D01*
Y-248953D01*
X217889Y-249036D01*
G01X223489Y-253703D02*
Y-248703D01*
G01X172172Y-220536D02*
X174172D01*
G01X173089Y-219453D02*
Y-221620D01*
G01X177189Y-222370D02*
X180189Y-217203D01*
G01X183206Y-220536D02*
X185372D01*
G01X188306Y-218036D02*
X188806Y-217536D01*
X189389Y-217286D01*
X190056Y-217203D01*
X190889Y-217370D01*
X191472Y-217786D01*
X191639Y-218286D01*
X191556Y-218786D01*
X191222Y-219203D01*
X189556Y-220036D01*
X188806Y-220620D01*
X188306Y-221453D01*
X188139Y-222203D01*
X191639D01*
G01X192989D02*
Y-218870D01*
G01Y-219786D02*
X193239Y-219370D01*
X193656Y-219036D01*
X194239Y-218870D01*
X194822Y-219036D01*
X195239Y-219370D01*
X195489Y-219786D01*
Y-222203D01*
G01Y-219786D02*
X195739Y-219370D01*
X196156Y-219036D01*
X196739Y-218870D01*
X197322Y-219036D01*
X197739Y-219370D01*
X197989Y-219870D01*
Y-222203D01*
G01X201089Y-218870D02*
Y-222203D01*
G01Y-217536D02*
X200922Y-217453D01*
Y-217286D01*
X201089Y-217203D01*
X201256Y-217286D01*
Y-217453D01*
X201089Y-217536D01*
G01X206689Y-222203D02*
Y-217203D01*
G01X172172Y-209036D02*
X174172D01*
G01X173089Y-207953D02*
Y-210120D01*
G01X177189Y-210870D02*
X180189Y-205703D01*
G01X183206Y-209036D02*
X185372D01*
G01X189889Y-210703D02*
Y-205703D01*
X188889Y-206703D01*
G01Y-210703D02*
X190889D01*
G01X192989D02*
Y-207370D01*
G01Y-208286D02*
X193239Y-207870D01*
X193656Y-207536D01*
X194239Y-207370D01*
X194822Y-207536D01*
X195239Y-207870D01*
X195489Y-208286D01*
Y-210703D01*
G01Y-208286D02*
X195739Y-207870D01*
X196156Y-207536D01*
X196739Y-207370D01*
X197322Y-207536D01*
X197739Y-207870D01*
X197989Y-208370D01*
Y-210703D01*
G01X201089Y-207370D02*
Y-210703D01*
G01Y-206036D02*
X200922Y-205953D01*
Y-205786D01*
X201089Y-205703D01*
X201256Y-205786D01*
Y-205953D01*
X201089Y-206036D01*
G01X206689Y-210703D02*
Y-205703D01*
G01X172172Y-165536D02*
X174172D01*
G01X173089Y-164453D02*
Y-166620D01*
G01X177189Y-167370D02*
X180189Y-162203D01*
G01X183206Y-165536D02*
X185372D01*
G01X189889Y-167203D02*
Y-162203D01*
X188889Y-163203D01*
G01Y-167203D02*
X190889D01*
G01X193656Y-166453D02*
X194156Y-166870D01*
X194739Y-167120D01*
X195489Y-167203D01*
X196239Y-167036D01*
X196822Y-166703D01*
X197239Y-166120D01*
X197322Y-165453D01*
X197156Y-164786D01*
X196739Y-164370D01*
X196156Y-164036D01*
X195572Y-163953D01*
X194989Y-164036D01*
X194239Y-164370D01*
X194489Y-162203D01*
X196739D01*
G01X199589Y-167370D02*
X202589Y-162203D01*
G01X199589D02*
X199089Y-162370D01*
X198839Y-162620D01*
X198672Y-163120D01*
X198839Y-163620D01*
X199089Y-163870D01*
X199589Y-164036D01*
X200089Y-163870D01*
X200339Y-163620D01*
X200506Y-163120D01*
X200339Y-162620D01*
X200089Y-162370D01*
X199589Y-162203D01*
G01X202589Y-165536D02*
X202089Y-165703D01*
X201839Y-165953D01*
X201672Y-166453D01*
X201839Y-166953D01*
X202089Y-167203D01*
X202589Y-167370D01*
X203089Y-167203D01*
X203339Y-166953D01*
X203506Y-166453D01*
X203339Y-165953D01*
X203089Y-165703D01*
X202589Y-165536D01*
G01X172172Y-185036D02*
X174172D01*
G01X173089Y-183953D02*
Y-186120D01*
G01X177189Y-186870D02*
X180189Y-181703D01*
G01X183206Y-185036D02*
X185372D01*
G01X188306Y-182536D02*
X188806Y-182036D01*
X189389Y-181786D01*
X190056Y-181703D01*
X190889Y-181870D01*
X191472Y-182286D01*
X191639Y-182786D01*
X191556Y-183286D01*
X191222Y-183703D01*
X189556Y-184536D01*
X188806Y-185120D01*
X188306Y-185953D01*
X188139Y-186703D01*
X191639D01*
G01X192989D02*
Y-183370D01*
G01Y-184286D02*
X193239Y-183870D01*
X193656Y-183536D01*
X194239Y-183370D01*
X194822Y-183536D01*
X195239Y-183870D01*
X195489Y-184286D01*
Y-186703D01*
G01Y-184286D02*
X195739Y-183870D01*
X196156Y-183536D01*
X196739Y-183370D01*
X197322Y-183536D01*
X197739Y-183870D01*
X197989Y-184370D01*
Y-186703D01*
G01X201089Y-183370D02*
Y-186703D01*
G01Y-182036D02*
X200922Y-181953D01*
Y-181786D01*
X201089Y-181703D01*
X201256Y-181786D01*
Y-181953D01*
X201089Y-182036D01*
G01X206689Y-186703D02*
Y-181703D01*
G01X172172Y-150536D02*
X174172D01*
G01X173089Y-149453D02*
Y-151620D01*
G01X177189Y-152370D02*
X180189Y-147203D01*
G01X183206Y-150536D02*
X185372D01*
G01X189889Y-152203D02*
Y-147203D01*
X188889Y-148203D01*
G01Y-152203D02*
X190889D01*
G01X192989D02*
Y-148870D01*
G01Y-149786D02*
X193239Y-149370D01*
X193656Y-149036D01*
X194239Y-148870D01*
X194822Y-149036D01*
X195239Y-149370D01*
X195489Y-149786D01*
Y-152203D01*
G01Y-149786D02*
X195739Y-149370D01*
X196156Y-149036D01*
X196739Y-148870D01*
X197322Y-149036D01*
X197739Y-149370D01*
X197989Y-149870D01*
Y-152203D01*
G01X201089Y-148870D02*
Y-152203D01*
G01Y-147536D02*
X200922Y-147453D01*
Y-147286D01*
X201089Y-147203D01*
X201256Y-147286D01*
Y-147453D01*
X201089Y-147536D01*
G01X206689Y-152203D02*
Y-147203D01*
G01X172172Y-135536D02*
X174172D01*
G01X173089Y-134453D02*
Y-136620D01*
G01X177189Y-137370D02*
X180189Y-132203D01*
G01X183206Y-135536D02*
X185372D01*
G01X188306Y-133036D02*
X188806Y-132536D01*
X189389Y-132286D01*
X190056Y-132203D01*
X190889Y-132370D01*
X191472Y-132786D01*
X191639Y-133286D01*
X191556Y-133786D01*
X191222Y-134203D01*
X189556Y-135036D01*
X188806Y-135620D01*
X188306Y-136453D01*
X188139Y-137203D01*
X191639D01*
G01X195489Y-132203D02*
X194822Y-132370D01*
X194322Y-132786D01*
X193989Y-133286D01*
X193739Y-133953D01*
X193656Y-134703D01*
X193739Y-135453D01*
X193989Y-136120D01*
X194322Y-136620D01*
X194822Y-137036D01*
X195489Y-137203D01*
X196156Y-137036D01*
X196656Y-136620D01*
X196989Y-136120D01*
X197239Y-135453D01*
X197322Y-134703D01*
X197239Y-133953D01*
X196989Y-133286D01*
X196656Y-132786D01*
X196156Y-132370D01*
X195489Y-132203D01*
G01X199589Y-137370D02*
X202589Y-132203D01*
G01X199589D02*
X199089Y-132370D01*
X198839Y-132620D01*
X198672Y-133120D01*
X198839Y-133620D01*
X199089Y-133870D01*
X199589Y-134036D01*
X200089Y-133870D01*
X200339Y-133620D01*
X200506Y-133120D01*
X200339Y-132620D01*
X200089Y-132370D01*
X199589Y-132203D01*
G01X202589Y-135536D02*
X202089Y-135703D01*
X201839Y-135953D01*
X201672Y-136453D01*
X201839Y-136953D01*
X202089Y-137203D01*
X202589Y-137370D01*
X203089Y-137203D01*
X203339Y-136953D01*
X203506Y-136453D01*
X203339Y-135953D01*
X203089Y-135703D01*
X202589Y-135536D01*
G01X172172Y-120536D02*
X174172D01*
G01X173089Y-119453D02*
Y-121620D01*
G01X177189Y-122370D02*
X180189Y-117203D01*
G01X183206Y-120536D02*
X185372D01*
G01X188056Y-121203D02*
X188556Y-121786D01*
X189222Y-122120D01*
X189972Y-122203D01*
X190639Y-122120D01*
X191306Y-121703D01*
X191722Y-121203D01*
X191806Y-120703D01*
X191639Y-120120D01*
X191056Y-119703D01*
X190472Y-119536D01*
X189722D01*
G01X190472D02*
X190972Y-119286D01*
X191389Y-118870D01*
X191556Y-118370D01*
X191389Y-117870D01*
X190972Y-117453D01*
X190222Y-117203D01*
X189472Y-117286D01*
X188722Y-117620D01*
G01X192989Y-122203D02*
Y-118870D01*
G01Y-119786D02*
X193239Y-119370D01*
X193656Y-119036D01*
X194239Y-118870D01*
X194822Y-119036D01*
X195239Y-119370D01*
X195489Y-119786D01*
Y-122203D01*
G01Y-119786D02*
X195739Y-119370D01*
X196156Y-119036D01*
X196739Y-118870D01*
X197322Y-119036D01*
X197739Y-119370D01*
X197989Y-119870D01*
Y-122203D01*
G01X201089Y-118870D02*
Y-122203D01*
G01Y-117536D02*
X200922Y-117453D01*
Y-117286D01*
X201089Y-117203D01*
X201256Y-117286D01*
Y-117453D01*
X201089Y-117536D01*
G01X206689Y-122203D02*
Y-117203D01*
G01X171422Y-107203D02*
X174756Y-105536D01*
X171422Y-103870D01*
G01X177606Y-106286D02*
X179772D01*
G01Y-104786D02*
X177606D01*
G01X184289Y-107203D02*
Y-102203D01*
X183289Y-103203D01*
G01Y-107203D02*
X185289D01*
G01X189889Y-107370D02*
X189722Y-107286D01*
Y-107120D01*
X189889Y-107036D01*
X190056Y-107120D01*
Y-107286D01*
X189889Y-107370D01*
G01X195489Y-102203D02*
X194822Y-102370D01*
X194322Y-102786D01*
X193989Y-103286D01*
X193739Y-103953D01*
X193656Y-104703D01*
X193739Y-105453D01*
X193989Y-106120D01*
X194322Y-106620D01*
X194822Y-107036D01*
X195489Y-107203D01*
X196156Y-107036D01*
X196656Y-106620D01*
X196989Y-106120D01*
X197239Y-105453D01*
X197322Y-104703D01*
X197239Y-103953D01*
X196989Y-103286D01*
X196656Y-102786D01*
X196156Y-102370D01*
X195489Y-102203D01*
G01X198589Y-107203D02*
Y-103870D01*
G01Y-104786D02*
X198839Y-104370D01*
X199256Y-104036D01*
X199839Y-103870D01*
X200422Y-104036D01*
X200839Y-104370D01*
X201089Y-104786D01*
Y-107203D01*
G01Y-104786D02*
X201339Y-104370D01*
X201756Y-104036D01*
X202339Y-103870D01*
X202922Y-104036D01*
X203339Y-104370D01*
X203589Y-104870D01*
Y-107203D01*
G01X206689Y-103870D02*
Y-107203D01*
G01Y-102536D02*
X206522Y-102453D01*
Y-102286D01*
X206689Y-102203D01*
X206856Y-102286D01*
Y-102453D01*
X206689Y-102536D01*
G01X212289Y-107203D02*
Y-102203D01*
G01X171422Y-89703D02*
X174756Y-88036D01*
X171422Y-86370D01*
G01X177606Y-88786D02*
X179772D01*
G01Y-87286D02*
X177606D01*
G01X184289Y-89703D02*
Y-84703D01*
X183289Y-85703D01*
G01Y-89703D02*
X185289D01*
G01X189889Y-89870D02*
X189722Y-89786D01*
Y-89620D01*
X189889Y-89536D01*
X190056Y-89620D01*
Y-89786D01*
X189889Y-89870D01*
G01X193656Y-88953D02*
X194156Y-89370D01*
X194739Y-89620D01*
X195489Y-89703D01*
X196239Y-89536D01*
X196822Y-89203D01*
X197239Y-88620D01*
X197322Y-87953D01*
X197156Y-87286D01*
X196739Y-86870D01*
X196156Y-86536D01*
X195572Y-86453D01*
X194989Y-86536D01*
X194239Y-86870D01*
X194489Y-84703D01*
X196739D01*
G01X198589Y-89703D02*
Y-86370D01*
G01Y-87286D02*
X198839Y-86870D01*
X199256Y-86536D01*
X199839Y-86370D01*
X200422Y-86536D01*
X200839Y-86870D01*
X201089Y-87286D01*
Y-89703D01*
G01Y-87286D02*
X201339Y-86870D01*
X201756Y-86536D01*
X202339Y-86370D01*
X202922Y-86536D01*
X203339Y-86870D01*
X203589Y-87370D01*
Y-89703D01*
G01X206689Y-86370D02*
Y-89703D01*
G01Y-85036D02*
X206522Y-84953D01*
Y-84786D01*
X206689Y-84703D01*
X206856Y-84786D01*
Y-84953D01*
X206689Y-85036D01*
G01X212289Y-89703D02*
Y-84703D01*
G01X171422Y-67203D02*
X174756Y-65536D01*
X171422Y-63870D01*
G01X177606Y-66286D02*
X179772D01*
G01Y-64786D02*
X177606D01*
G01X184289Y-67203D02*
Y-62203D01*
X183289Y-63203D01*
G01Y-67203D02*
X185289D01*
G01X189889Y-67370D02*
X189722Y-67286D01*
Y-67120D01*
X189889Y-67036D01*
X190056Y-67120D01*
Y-67286D01*
X189889Y-67370D01*
G01X193656Y-66203D02*
X194156Y-66786D01*
X194822Y-67120D01*
X195572Y-67203D01*
X196239Y-67120D01*
X196906Y-66703D01*
X197322Y-66203D01*
X197406Y-65703D01*
X197239Y-65120D01*
X196656Y-64703D01*
X196072Y-64536D01*
X195322D01*
G01X196072D02*
X196572Y-64286D01*
X196989Y-63870D01*
X197156Y-63370D01*
X196989Y-62870D01*
X196572Y-62453D01*
X195822Y-62203D01*
X195072Y-62286D01*
X194322Y-62620D01*
G01X198589Y-67203D02*
Y-63870D01*
G01Y-64786D02*
X198839Y-64370D01*
X199256Y-64036D01*
X199839Y-63870D01*
X200422Y-64036D01*
X200839Y-64370D01*
X201089Y-64786D01*
Y-67203D01*
G01Y-64786D02*
X201339Y-64370D01*
X201756Y-64036D01*
X202339Y-63870D01*
X202922Y-64036D01*
X203339Y-64370D01*
X203589Y-64870D01*
Y-67203D01*
G01X206689Y-63870D02*
Y-67203D01*
G01Y-62536D02*
X206522Y-62453D01*
Y-62286D01*
X206689Y-62203D01*
X206856Y-62286D01*
Y-62453D01*
X206689Y-62536D01*
G01X212289Y-67203D02*
Y-62203D01*
G01X178566Y-33213D02*
X175232Y-31546D01*
X178566Y-29880D01*
G01X182499Y-28213D02*
X181832Y-28380D01*
X181332Y-28796D01*
X180999Y-29296D01*
X180749Y-29963D01*
X180666Y-30713D01*
X180749Y-31463D01*
X180999Y-32130D01*
X181332Y-32630D01*
X181832Y-33046D01*
X182499Y-33213D01*
X183166Y-33046D01*
X183666Y-32630D01*
X183999Y-32130D01*
X184249Y-31463D01*
X184332Y-30713D01*
X184249Y-29963D01*
X183999Y-29296D01*
X183666Y-28796D01*
X183166Y-28380D01*
X182499Y-28213D01*
G01X188099Y-33380D02*
X187932Y-33296D01*
Y-33130D01*
X188099Y-33046D01*
X188266Y-33130D01*
Y-33296D01*
X188099Y-33380D01*
G01X191866Y-32213D02*
X192366Y-32796D01*
X193032Y-33130D01*
X193782Y-33213D01*
X194449Y-33130D01*
X195116Y-32713D01*
X195532Y-32213D01*
X195616Y-31713D01*
X195449Y-31130D01*
X194866Y-30713D01*
X194282Y-30546D01*
X193532D01*
G01X194282D02*
X194782Y-30296D01*
X195199Y-29880D01*
X195366Y-29380D01*
X195199Y-28880D01*
X194782Y-28463D01*
X194032Y-28213D01*
X193282Y-28296D01*
X192532Y-28630D01*
G01X196799Y-33213D02*
Y-29880D01*
G01Y-30796D02*
X197049Y-30380D01*
X197466Y-30046D01*
X198049Y-29880D01*
X198632Y-30046D01*
X199049Y-30380D01*
X199299Y-30796D01*
Y-33213D01*
G01Y-30796D02*
X199549Y-30380D01*
X199966Y-30046D01*
X200549Y-29880D01*
X201132Y-30046D01*
X201549Y-30380D01*
X201799Y-30880D01*
Y-33213D01*
G01X204899Y-29880D02*
Y-33213D01*
G01Y-28546D02*
X204732Y-28463D01*
Y-28296D01*
X204899Y-28213D01*
X205066Y-28296D01*
Y-28463D01*
X204899Y-28546D01*
G01X210499Y-33213D02*
Y-28213D01*
G01X177966Y21977D02*
X174632Y23644D01*
X177966Y25310D01*
G01X181899Y21977D02*
Y26977D01*
X180899Y25977D01*
G01Y21977D02*
X182899D01*
G01X184999D02*
Y25310D01*
G01Y24394D02*
X185249Y24810D01*
X185666Y25144D01*
X186249Y25310D01*
X186832Y25144D01*
X187249Y24810D01*
X187499Y24394D01*
Y21977D01*
G01Y24394D02*
X187749Y24810D01*
X188166Y25144D01*
X188749Y25310D01*
X189332Y25144D01*
X189749Y24810D01*
X189999Y24310D01*
Y21977D01*
G01X193099Y25310D02*
Y21977D01*
G01Y26644D02*
X192932Y26727D01*
Y26894D01*
X193099Y26977D01*
X193266Y26894D01*
Y26727D01*
X193099Y26644D01*
G01X198699Y21977D02*
Y26977D01*
G01X167709Y76767D02*
Y80100D01*
G01Y79184D02*
X167959Y79600D01*
X168376Y79934D01*
X168959Y80100D01*
X169542Y79934D01*
X169959Y79600D01*
X170209Y79184D01*
Y76767D01*
G01Y79184D02*
X170459Y79600D01*
X170876Y79934D01*
X171459Y80100D01*
X172042Y79934D01*
X172459Y79600D01*
X172709Y79100D01*
Y76767D01*
G01X174392Y80100D02*
Y77767D01*
X174726Y77184D01*
X175226Y76850D01*
X175809Y76767D01*
X176392Y76850D01*
X176892Y77184D01*
X177226Y77767D01*
G01Y76767D02*
Y80100D01*
G01X180159Y77350D02*
X180576Y77017D01*
X181159Y76767D01*
X181659D01*
X182159Y76934D01*
X182492Y77184D01*
X182659Y77517D01*
X182576Y78017D01*
X182242Y78267D01*
X180742Y78767D01*
X180409Y79350D01*
X180576Y79767D01*
X180909Y80017D01*
X181409Y80100D01*
X181909Y80017D01*
X182409Y79767D01*
G01X187009Y81767D02*
Y76767D01*
G01X185842Y80100D02*
X188176D01*
G01X194276Y76767D02*
X190942Y78434D01*
X194276Y80100D01*
G01X196126Y76767D02*
X198209Y81767D01*
X200292Y76767D01*
G01X199542Y78517D02*
X196876D01*
G01X210909Y81767D02*
Y76767D01*
G01Y77517D02*
X210576Y77100D01*
X210076Y76850D01*
X209492Y76767D01*
X208826Y76934D01*
X208326Y77350D01*
X207992Y77850D01*
X207909Y78434D01*
X207992Y79017D01*
X208326Y79517D01*
X208826Y79934D01*
X209492Y80100D01*
X210076Y80017D01*
X210492Y79850D01*
X210909Y79517D01*
G01X215009Y80100D02*
Y76767D01*
G01Y81434D02*
X214842Y81517D01*
Y81684D01*
X215009Y81767D01*
X215176Y81684D01*
Y81517D01*
X215009Y81434D01*
G01X222109Y76767D02*
Y80100D01*
G01Y79517D02*
X221776Y79850D01*
X221276Y80017D01*
X220692Y80100D01*
X220109Y79934D01*
X219609Y79600D01*
X219276Y79100D01*
X219109Y78434D01*
X219276Y77767D01*
X219609Y77267D01*
X220109Y76934D01*
X220692Y76767D01*
X221276Y76850D01*
X221776Y77100D01*
X222109Y77434D01*
G01X223709Y76767D02*
Y80100D01*
G01Y79184D02*
X223959Y79600D01*
X224376Y79934D01*
X224959Y80100D01*
X225542Y79934D01*
X225959Y79600D01*
X226209Y79184D01*
Y76767D01*
G01Y79184D02*
X226459Y79600D01*
X226876Y79934D01*
X227459Y80100D01*
X228042Y79934D01*
X228459Y79600D01*
X228709Y79100D01*
Y76767D01*
G01X230559Y79017D02*
X233226D01*
X232976Y79600D01*
X232559Y79934D01*
X231976Y80100D01*
X231392Y80017D01*
X230892Y79767D01*
X230559Y79184D01*
X230392Y78684D01*
Y78184D01*
X230559Y77684D01*
X230976Y77184D01*
X231476Y76850D01*
X232059Y76767D01*
X232642Y76934D01*
X233226Y77434D01*
G01X237409Y81767D02*
Y76767D01*
G01X236242Y80100D02*
X238576D01*
G01X241759Y79017D02*
X244426D01*
X244176Y79600D01*
X243759Y79934D01*
X243176Y80100D01*
X242592Y80017D01*
X242092Y79767D01*
X241759Y79184D01*
X241592Y78684D01*
Y78184D01*
X241759Y77684D01*
X242176Y77184D01*
X242676Y76850D01*
X243259Y76767D01*
X243842Y76934D01*
X244426Y77434D01*
G01X247442Y76767D02*
Y80100D01*
G01Y79434D02*
X247859Y79767D01*
X248276Y80017D01*
X248859Y80100D01*
X249276Y80017D01*
X249776Y79767D01*
G01X173986Y61527D02*
X170652Y63194D01*
X173986Y64860D01*
G01X176502Y62110D02*
X177086Y61694D01*
X177752Y61527D01*
X178419Y61694D01*
X179002Y62194D01*
X179419Y62944D01*
X179586Y63694D01*
Y64610D01*
X179419Y65360D01*
X179002Y66027D01*
X178502Y66360D01*
X177919Y66527D01*
X177252Y66360D01*
X176752Y66027D01*
X176419Y65527D01*
X176252Y64860D01*
X176419Y64277D01*
X176836Y63694D01*
X177336Y63360D01*
X177919Y63277D01*
X178586Y63444D01*
X179086Y63860D01*
X179586Y64610D01*
G01X183519Y66527D02*
X182852Y66360D01*
X182352Y65944D01*
X182019Y65444D01*
X181769Y64777D01*
X181686Y64027D01*
X181769Y63277D01*
X182019Y62610D01*
X182352Y62110D01*
X182852Y61694D01*
X183519Y61527D01*
X184186Y61694D01*
X184686Y62110D01*
X185019Y62610D01*
X185269Y63277D01*
X185352Y64027D01*
X185269Y64777D01*
X185019Y65444D01*
X184686Y65944D01*
X184186Y66360D01*
X183519Y66527D01*
G01X196219D02*
Y61527D01*
G01Y62277D02*
X195886Y61860D01*
X195386Y61610D01*
X194802Y61527D01*
X194136Y61694D01*
X193636Y62110D01*
X193302Y62610D01*
X193219Y63194D01*
X193302Y63777D01*
X193636Y64277D01*
X194136Y64694D01*
X194802Y64860D01*
X195386Y64777D01*
X195802Y64610D01*
X196219Y64277D01*
G01X199069Y63777D02*
X201736D01*
X201486Y64360D01*
X201069Y64694D01*
X200486Y64860D01*
X199902Y64777D01*
X199402Y64527D01*
X199069Y63944D01*
X198902Y63444D01*
Y62944D01*
X199069Y62444D01*
X199486Y61944D01*
X199986Y61610D01*
X200569Y61527D01*
X201152Y61694D01*
X201736Y62194D01*
G01X204752Y60277D02*
X205336Y59944D01*
X206002Y59860D01*
X206586Y59944D01*
X207086Y60360D01*
X207419Y60944D01*
Y64860D01*
G01Y64194D02*
X207086Y64527D01*
X206586Y64777D01*
X206002Y64860D01*
X205336Y64694D01*
X204919Y64360D01*
X204586Y63777D01*
X204419Y63194D01*
X204502Y62694D01*
X204836Y62110D01*
X205336Y61694D01*
X206002Y61527D01*
X206502Y61610D01*
X207086Y61944D01*
X207419Y62277D01*
G01X210352Y61527D02*
Y64860D01*
G01Y64194D02*
X210769Y64527D01*
X211186Y64777D01*
X211769Y64860D01*
X212186Y64777D01*
X212686Y64527D01*
G01X215869Y63777D02*
X218536D01*
X218286Y64360D01*
X217869Y64694D01*
X217286Y64860D01*
X216702Y64777D01*
X216202Y64527D01*
X215869Y63944D01*
X215702Y63444D01*
Y62944D01*
X215869Y62444D01*
X216286Y61944D01*
X216786Y61610D01*
X217369Y61527D01*
X217952Y61694D01*
X218536Y62194D01*
G01X221469Y63777D02*
X224136D01*
X223886Y64360D01*
X223469Y64694D01*
X222886Y64860D01*
X222302Y64777D01*
X221802Y64527D01*
X221469Y63944D01*
X221302Y63444D01*
Y62944D01*
X221469Y62444D01*
X221886Y61944D01*
X222386Y61610D01*
X222969Y61527D01*
X223552Y61694D01*
X224136Y62194D01*
G01X168289Y85537D02*
Y90537D01*
G01Y88037D02*
X168706Y88537D01*
X169206Y88787D01*
X169706Y88870D01*
X170456Y88704D01*
X170956Y88370D01*
X171289Y87787D01*
Y87120D01*
X171122Y86454D01*
X170789Y85954D01*
X170206Y85620D01*
X169706Y85537D01*
X169206Y85620D01*
X168706Y85870D01*
X168289Y86287D01*
G01X173972Y88870D02*
Y86537D01*
X174306Y85954D01*
X174806Y85620D01*
X175389Y85537D01*
X175972Y85620D01*
X176472Y85954D01*
X176806Y86537D01*
G01Y85537D02*
Y88870D01*
G01X180989Y90537D02*
Y85537D01*
G01X179822Y88870D02*
X182156D01*
G01X192856Y88204D02*
X193189Y88454D01*
X193439Y88870D01*
X193606Y89454D01*
X193439Y89954D01*
X193106Y90287D01*
X192522Y90537D01*
X190272D01*
Y85537D01*
X193022D01*
X193606Y85870D01*
X193939Y86370D01*
X194106Y86954D01*
X193939Y87537D01*
X193439Y88037D01*
X192856Y88204D01*
X190272D01*
G01X204889Y90537D02*
Y85537D01*
G01Y86287D02*
X204556Y85870D01*
X204056Y85620D01*
X203472Y85537D01*
X202806Y85704D01*
X202306Y86120D01*
X201972Y86620D01*
X201889Y87204D01*
X201972Y87787D01*
X202306Y88287D01*
X202806Y88704D01*
X203472Y88870D01*
X204056Y88787D01*
X204472Y88620D01*
X204889Y88287D01*
G01X208989Y88870D02*
Y85537D01*
G01Y90204D02*
X208822Y90287D01*
Y90454D01*
X208989Y90537D01*
X209156Y90454D01*
Y90287D01*
X208989Y90204D01*
G01X216089Y85537D02*
Y88870D01*
G01Y88287D02*
X215756Y88620D01*
X215256Y88787D01*
X214672Y88870D01*
X214089Y88704D01*
X213589Y88370D01*
X213256Y87870D01*
X213089Y87204D01*
X213256Y86537D01*
X213589Y86037D01*
X214089Y85704D01*
X214672Y85537D01*
X215256Y85620D01*
X215756Y85870D01*
X216089Y86204D01*
G01X217689Y85537D02*
Y88870D01*
G01Y87954D02*
X217939Y88370D01*
X218356Y88704D01*
X218939Y88870D01*
X219522Y88704D01*
X219939Y88370D01*
X220189Y87954D01*
Y85537D01*
G01Y87954D02*
X220439Y88370D01*
X220856Y88704D01*
X221439Y88870D01*
X222022Y88704D01*
X222439Y88370D01*
X222689Y87870D01*
Y85537D01*
G01X224539Y87787D02*
X227206D01*
X226956Y88370D01*
X226539Y88704D01*
X225956Y88870D01*
X225372Y88787D01*
X224872Y88537D01*
X224539Y87954D01*
X224372Y87454D01*
Y86954D01*
X224539Y86454D01*
X224956Y85954D01*
X225456Y85620D01*
X226039Y85537D01*
X226622Y85704D01*
X227206Y86204D01*
G01X231389Y90537D02*
Y85537D01*
G01X230222Y88870D02*
X232556D01*
G01X235739Y87787D02*
X238406D01*
X238156Y88370D01*
X237739Y88704D01*
X237156Y88870D01*
X236572Y88787D01*
X236072Y88537D01*
X235739Y87954D01*
X235572Y87454D01*
Y86954D01*
X235739Y86454D01*
X236156Y85954D01*
X236656Y85620D01*
X237239Y85537D01*
X237822Y85704D01*
X238406Y86204D01*
G01X241422Y85537D02*
Y88870D01*
G01Y88204D02*
X241839Y88537D01*
X242256Y88787D01*
X242839Y88870D01*
X243256Y88787D01*
X243756Y88537D01*
G01X169372Y95557D02*
X172706Y97224D01*
X169372Y98890D01*
G01X175556Y96474D02*
X177722D01*
G01Y97974D02*
X175556D01*
G01X182072Y95557D02*
X182239Y96640D01*
X182489Y97557D01*
X182822Y98390D01*
X183239Y99307D01*
X183906Y100557D01*
X180572D01*
G01X187839D02*
X187172Y100390D01*
X186672Y99974D01*
X186339Y99474D01*
X186089Y98807D01*
X186006Y98057D01*
X186089Y97307D01*
X186339Y96640D01*
X186672Y96140D01*
X187172Y95724D01*
X187839Y95557D01*
X188506Y95724D01*
X189006Y96140D01*
X189339Y96640D01*
X189589Y97307D01*
X189672Y98057D01*
X189589Y98807D01*
X189339Y99474D01*
X189006Y99974D01*
X188506Y100390D01*
X187839Y100557D01*
G01X191939Y95390D02*
X194939Y100557D01*
G01X191939D02*
X191439Y100390D01*
X191189Y100140D01*
X191022Y99640D01*
X191189Y99140D01*
X191439Y98890D01*
X191939Y98724D01*
X192439Y98890D01*
X192689Y99140D01*
X192856Y99640D01*
X192689Y100140D01*
X192439Y100390D01*
X191939Y100557D01*
G01X194939Y97224D02*
X194439Y97057D01*
X194189Y96807D01*
X194022Y96307D01*
X194189Y95807D01*
X194439Y95557D01*
X194939Y95390D01*
X195439Y95557D01*
X195689Y95807D01*
X195856Y96307D01*
X195689Y96807D01*
X195439Y97057D01*
X194939Y97224D01*
G01X198872Y94640D02*
X199206Y95724D01*
G01X171352Y115984D02*
X173352D01*
G01X172269Y117067D02*
Y114900D01*
G01X176369Y114150D02*
X179369Y119317D01*
G01X182386Y115984D02*
X184552D01*
G01X189069Y114317D02*
Y119317D01*
X188069Y118317D01*
G01Y114317D02*
X190069D01*
G01X192169D02*
Y117650D01*
G01Y116734D02*
X192419Y117150D01*
X192836Y117484D01*
X193419Y117650D01*
X194002Y117484D01*
X194419Y117150D01*
X194669Y116734D01*
Y114317D01*
G01Y116734D02*
X194919Y117150D01*
X195336Y117484D01*
X195919Y117650D01*
X196502Y117484D01*
X196919Y117150D01*
X197169Y116650D01*
Y114317D01*
G01X200269Y117650D02*
Y114317D01*
G01Y118984D02*
X200102Y119067D01*
Y119234D01*
X200269Y119317D01*
X200436Y119234D01*
Y119067D01*
X200269Y118984D01*
G01X205869Y114317D02*
Y119317D01*
G01X173922Y159297D02*
Y164297D01*
X176089Y160130D01*
X178256Y164297D01*
Y159297D01*
G01X180272Y162630D02*
Y160297D01*
X180606Y159714D01*
X181106Y159380D01*
X181689Y159297D01*
X182272Y159380D01*
X182772Y159714D01*
X183106Y160297D01*
G01Y159297D02*
Y162630D01*
G01X186039Y159880D02*
X186456Y159547D01*
X187039Y159297D01*
X187539D01*
X188039Y159464D01*
X188372Y159714D01*
X188539Y160047D01*
X188456Y160547D01*
X188122Y160797D01*
X186622Y161297D01*
X186289Y161880D01*
X186456Y162297D01*
X186789Y162547D01*
X187289Y162630D01*
X187789Y162547D01*
X188289Y162297D01*
G01X192889Y164297D02*
Y159297D01*
G01X191722Y162630D02*
X194056D01*
G01X203589Y159297D02*
Y163547D01*
X203756Y163964D01*
X204089Y164214D01*
X204589Y164297D01*
X205089Y164130D01*
X205339Y163714D01*
G01X204339Y162297D02*
X202672D01*
G01X209689Y159297D02*
X209189Y159380D01*
X208689Y159714D01*
X208356Y160297D01*
X208189Y160964D01*
X208356Y161630D01*
X208689Y162214D01*
X209189Y162547D01*
X209689Y162630D01*
X210189Y162547D01*
X210689Y162214D01*
X211022Y161630D01*
X211106Y160964D01*
X211022Y160297D01*
X210689Y159714D01*
X210189Y159380D01*
X209689Y159297D01*
G01X215289D02*
Y164297D01*
G01X220889Y159297D02*
Y164297D01*
G01X226489Y159297D02*
X225989Y159380D01*
X225489Y159714D01*
X225156Y160297D01*
X224989Y160964D01*
X225156Y161630D01*
X225489Y162214D01*
X225989Y162547D01*
X226489Y162630D01*
X226989Y162547D01*
X227489Y162214D01*
X227822Y161630D01*
X227906Y160964D01*
X227822Y160297D01*
X227489Y159714D01*
X226989Y159380D01*
X226489Y159297D01*
G01X230006Y162630D02*
X231006Y159297D01*
X232089Y162630D01*
X233172Y159297D01*
X234172Y162630D01*
G01X171399Y196287D02*
Y200537D01*
X171566Y200954D01*
X171899Y201204D01*
X172399Y201287D01*
X172899Y201120D01*
X173149Y200704D01*
G01X172149Y199287D02*
X170482D01*
G01X177499Y196287D02*
X176999Y196370D01*
X176499Y196704D01*
X176166Y197287D01*
X175999Y197954D01*
X176166Y198620D01*
X176499Y199204D01*
X176999Y199537D01*
X177499Y199620D01*
X177999Y199537D01*
X178499Y199204D01*
X178832Y198620D01*
X178916Y197954D01*
X178832Y197287D01*
X178499Y196704D01*
X177999Y196370D01*
X177499Y196287D01*
G01X183099D02*
Y201287D01*
G01X188699Y196287D02*
Y201287D01*
G01X194299Y196287D02*
X193799Y196370D01*
X193299Y196704D01*
X192966Y197287D01*
X192799Y197954D01*
X192966Y198620D01*
X193299Y199204D01*
X193799Y199537D01*
X194299Y199620D01*
X194799Y199537D01*
X195299Y199204D01*
X195632Y198620D01*
X195716Y197954D01*
X195632Y197287D01*
X195299Y196704D01*
X194799Y196370D01*
X194299Y196287D01*
G01X197816Y199620D02*
X198816Y196287D01*
X199899Y199620D01*
X200982Y196287D01*
X201982Y199620D01*
G01X212599Y201287D02*
Y196287D01*
G01Y197037D02*
X212266Y196620D01*
X211766Y196370D01*
X211182Y196287D01*
X210516Y196454D01*
X210016Y196870D01*
X209682Y197370D01*
X209599Y197954D01*
X209682Y198537D01*
X210016Y199037D01*
X210516Y199454D01*
X211182Y199620D01*
X211766Y199537D01*
X212182Y199370D01*
X212599Y199037D01*
G01X215532Y196287D02*
Y199620D01*
G01Y198954D02*
X215949Y199287D01*
X216366Y199537D01*
X216949Y199620D01*
X217366Y199537D01*
X217866Y199287D01*
G01X223799Y196287D02*
Y199620D01*
G01Y199037D02*
X223466Y199370D01*
X222966Y199537D01*
X222382Y199620D01*
X221799Y199454D01*
X221299Y199120D01*
X220966Y198620D01*
X220799Y197954D01*
X220966Y197287D01*
X221299Y196787D01*
X221799Y196454D01*
X222382Y196287D01*
X222966Y196370D01*
X223466Y196620D01*
X223799Y196954D01*
G01X225816Y199620D02*
X226816Y196287D01*
X227899Y199620D01*
X228982Y196287D01*
X229982Y199620D01*
G01X233499D02*
Y196287D01*
G01Y200954D02*
X233332Y201037D01*
Y201204D01*
X233499Y201287D01*
X233666Y201204D01*
Y201037D01*
X233499Y200954D01*
G01X237682Y196287D02*
Y199620D01*
G01Y198787D02*
X238016Y199204D01*
X238516Y199537D01*
X239182Y199620D01*
X239766Y199537D01*
X240266Y199204D01*
X240516Y198620D01*
Y196287D01*
G01X243532Y195037D02*
X244116Y194704D01*
X244782Y194620D01*
X245366Y194704D01*
X245866Y195120D01*
X246199Y195704D01*
Y199620D01*
G01Y198954D02*
X245866Y199287D01*
X245366Y199537D01*
X244782Y199620D01*
X244116Y199454D01*
X243699Y199120D01*
X243366Y198537D01*
X243199Y197954D01*
X243282Y197454D01*
X243616Y196870D01*
X244116Y196454D01*
X244782Y196287D01*
X245282Y196370D01*
X245866Y196704D01*
X246199Y197037D01*
G01X250716Y194620D02*
X251549Y195454D01*
X251966Y196287D01*
Y199620D01*
X251549Y200454D01*
X250716Y201287D01*
G01X172492Y206884D02*
X174492D01*
G01X173409Y207967D02*
Y205800D01*
G01X177509Y205050D02*
X180509Y210217D01*
G01X183526Y206884D02*
X185692D01*
G01X188376Y205967D02*
X188876Y205550D01*
X189459Y205300D01*
X190209Y205217D01*
X190959Y205384D01*
X191542Y205717D01*
X191959Y206300D01*
X192042Y206967D01*
X191876Y207634D01*
X191459Y208050D01*
X190876Y208384D01*
X190292Y208467D01*
X189709Y208384D01*
X188959Y208050D01*
X189209Y210217D01*
X191459D01*
G01X193309Y205217D02*
Y208550D01*
G01Y207634D02*
X193559Y208050D01*
X193976Y208384D01*
X194559Y208550D01*
X195142Y208384D01*
X195559Y208050D01*
X195809Y207634D01*
Y205217D01*
G01Y207634D02*
X196059Y208050D01*
X196476Y208384D01*
X197059Y208550D01*
X197642Y208384D01*
X198059Y208050D01*
X198309Y207550D01*
Y205217D01*
G01X201409Y208550D02*
Y205217D01*
G01Y209884D02*
X201242Y209967D01*
Y210134D01*
X201409Y210217D01*
X201576Y210134D01*
Y209967D01*
X201409Y209884D01*
G01X207009Y205217D02*
Y210217D01*
G01X173089Y218297D02*
Y223297D01*
X172089Y222297D01*
G01Y218297D02*
X174089D01*
G01X178689Y218130D02*
X178522Y218214D01*
Y218380D01*
X178689Y218464D01*
X178856Y218380D01*
Y218214D01*
X178689Y218130D01*
G01X184289Y223297D02*
X183622Y223130D01*
X183122Y222714D01*
X182789Y222214D01*
X182539Y221547D01*
X182456Y220797D01*
X182539Y220047D01*
X182789Y219380D01*
X183122Y218880D01*
X183622Y218464D01*
X184289Y218297D01*
X184956Y218464D01*
X185456Y218880D01*
X185789Y219380D01*
X186039Y220047D01*
X186122Y220797D01*
X186039Y221547D01*
X185789Y222214D01*
X185456Y222714D01*
X184956Y223130D01*
X184289Y223297D01*
G01X187389Y218297D02*
Y221630D01*
G01Y220714D02*
X187639Y221130D01*
X188056Y221464D01*
X188639Y221630D01*
X189222Y221464D01*
X189639Y221130D01*
X189889Y220714D01*
Y218297D01*
G01Y220714D02*
X190139Y221130D01*
X190556Y221464D01*
X191139Y221630D01*
X191722Y221464D01*
X192139Y221130D01*
X192389Y220630D01*
Y218297D01*
G01X195489Y221630D02*
Y218297D01*
G01Y222964D02*
X195322Y223047D01*
Y223214D01*
X195489Y223297D01*
X195656Y223214D01*
Y223047D01*
X195489Y222964D01*
G01X201089Y218297D02*
Y223297D01*
G01X209789Y218297D02*
Y221630D01*
G01Y220714D02*
X210039Y221130D01*
X210456Y221464D01*
X211039Y221630D01*
X211622Y221464D01*
X212039Y221130D01*
X212289Y220714D01*
Y218297D01*
G01Y220714D02*
X212539Y221130D01*
X212956Y221464D01*
X213539Y221630D01*
X214122Y221464D01*
X214539Y221130D01*
X214789Y220630D01*
Y218297D01*
G01X219389D02*
Y221630D01*
G01Y221047D02*
X219056Y221380D01*
X218556Y221547D01*
X217972Y221630D01*
X217389Y221464D01*
X216889Y221130D01*
X216556Y220630D01*
X216389Y219964D01*
X216556Y219297D01*
X216889Y218797D01*
X217389Y218464D01*
X217972Y218297D01*
X218556Y218380D01*
X219056Y218630D01*
X219389Y218964D01*
G01X222239Y221630D02*
X224739Y218297D01*
G01Y221630D02*
X222239Y218297D01*
G01X172172Y237964D02*
X174172D01*
G01X173089Y239047D02*
Y236880D01*
G01X177189Y236130D02*
X180189Y241297D01*
G01X183206Y237964D02*
X185372D01*
G01X188056Y237047D02*
X188556Y236630D01*
X189139Y236380D01*
X189889Y236297D01*
X190639Y236464D01*
X191222Y236797D01*
X191639Y237380D01*
X191722Y238047D01*
X191556Y238714D01*
X191139Y239130D01*
X190556Y239464D01*
X189972Y239547D01*
X189389Y239464D01*
X188639Y239130D01*
X188889Y241297D01*
X191139D01*
G01X192989Y236297D02*
Y239630D01*
G01Y238714D02*
X193239Y239130D01*
X193656Y239464D01*
X194239Y239630D01*
X194822Y239464D01*
X195239Y239130D01*
X195489Y238714D01*
Y236297D01*
G01Y238714D02*
X195739Y239130D01*
X196156Y239464D01*
X196739Y239630D01*
X197322Y239464D01*
X197739Y239130D01*
X197989Y238630D01*
Y236297D01*
G01X201089Y239630D02*
Y236297D01*
G01Y240964D02*
X200922Y241047D01*
Y241214D01*
X201089Y241297D01*
X201256Y241214D01*
Y241047D01*
X201089Y240964D01*
G01X206689Y236297D02*
Y241297D01*
G01X172172Y252964D02*
X174172D01*
G01X173089Y254047D02*
Y251880D01*
G01X177189Y251130D02*
X180189Y256297D01*
G01X183206Y252964D02*
X185372D01*
G01X188056Y252047D02*
X188556Y251630D01*
X189139Y251380D01*
X189889Y251297D01*
X190639Y251464D01*
X191222Y251797D01*
X191639Y252380D01*
X191722Y253047D01*
X191556Y253714D01*
X191139Y254130D01*
X190556Y254464D01*
X189972Y254547D01*
X189389Y254464D01*
X188639Y254130D01*
X188889Y256297D01*
X191139D01*
G01X192989Y251297D02*
Y254630D01*
G01Y253714D02*
X193239Y254130D01*
X193656Y254464D01*
X194239Y254630D01*
X194822Y254464D01*
X195239Y254130D01*
X195489Y253714D01*
Y251297D01*
G01Y253714D02*
X195739Y254130D01*
X196156Y254464D01*
X196739Y254630D01*
X197322Y254464D01*
X197739Y254130D01*
X197989Y253630D01*
Y251297D01*
G01X201089Y254630D02*
Y251297D01*
G01Y255964D02*
X200922Y256047D01*
Y256214D01*
X201089Y256297D01*
X201256Y256214D01*
Y256047D01*
X201089Y255964D01*
G01X206689Y251297D02*
Y256297D01*
G01X172172Y267964D02*
X174172D01*
G01X173089Y269047D02*
Y266880D01*
G01X176856Y267297D02*
X177356Y266714D01*
X178022Y266380D01*
X178772Y266297D01*
X179439Y266380D01*
X180106Y266797D01*
X180522Y267297D01*
X180606Y267797D01*
X180439Y268380D01*
X179856Y268797D01*
X179272Y268964D01*
X178522D01*
G01X179272D02*
X179772Y269214D01*
X180189Y269630D01*
X180356Y270130D01*
X180189Y270630D01*
X179772Y271047D01*
X179022Y271297D01*
X178272Y271214D01*
X177522Y270880D01*
G01X182789Y266130D02*
X185789Y271297D01*
G01X188806Y267964D02*
X190972D01*
G01X195489Y271297D02*
X194822Y271130D01*
X194322Y270714D01*
X193989Y270214D01*
X193739Y269547D01*
X193656Y268797D01*
X193739Y268047D01*
X193989Y267380D01*
X194322Y266880D01*
X194822Y266464D01*
X195489Y266297D01*
X196156Y266464D01*
X196656Y266880D01*
X196989Y267380D01*
X197239Y268047D01*
X197322Y268797D01*
X197239Y269547D01*
X196989Y270214D01*
X196656Y270714D01*
X196156Y271130D01*
X195489Y271297D01*
G01X198589Y266297D02*
Y269630D01*
G01Y268714D02*
X198839Y269130D01*
X199256Y269464D01*
X199839Y269630D01*
X200422Y269464D01*
X200839Y269130D01*
X201089Y268714D01*
Y266297D01*
G01Y268714D02*
X201339Y269130D01*
X201756Y269464D01*
X202339Y269630D01*
X202922Y269464D01*
X203339Y269130D01*
X203589Y268630D01*
Y266297D01*
G01X206689Y269630D02*
Y266297D01*
G01Y270964D02*
X206522Y271047D01*
Y271214D01*
X206689Y271297D01*
X206856Y271214D01*
Y271047D01*
X206689Y270964D01*
G01X212289Y266297D02*
Y271297D01*
G01X172172Y282964D02*
X174172D01*
G01X173089Y284047D02*
Y281880D01*
G01X177189Y281130D02*
X180189Y286297D01*
G01X183206Y282964D02*
X185372D01*
G01X188306Y285464D02*
X188806Y285964D01*
X189389Y286214D01*
X190056Y286297D01*
X190889Y286130D01*
X191472Y285714D01*
X191639Y285214D01*
X191556Y284714D01*
X191222Y284297D01*
X189556Y283464D01*
X188806Y282880D01*
X188306Y282047D01*
X188139Y281297D01*
X191639D01*
G01X192989D02*
Y284630D01*
G01Y283714D02*
X193239Y284130D01*
X193656Y284464D01*
X194239Y284630D01*
X194822Y284464D01*
X195239Y284130D01*
X195489Y283714D01*
Y281297D01*
G01Y283714D02*
X195739Y284130D01*
X196156Y284464D01*
X196739Y284630D01*
X197322Y284464D01*
X197739Y284130D01*
X197989Y283630D01*
Y281297D01*
G01X201089Y284630D02*
Y281297D01*
G01Y285964D02*
X200922Y286047D01*
Y286214D01*
X201089Y286297D01*
X201256Y286214D01*
Y286047D01*
X201089Y285964D01*
G01X206689Y281297D02*
Y286297D01*
G01X172172Y296464D02*
X174172D01*
G01X173089Y297547D02*
Y295380D01*
G01X177189Y294630D02*
X180189Y299797D01*
G01X183206Y296464D02*
X185372D01*
G01X188056Y295797D02*
X188556Y295214D01*
X189222Y294880D01*
X189972Y294797D01*
X190639Y294880D01*
X191306Y295297D01*
X191722Y295797D01*
X191806Y296297D01*
X191639Y296880D01*
X191056Y297297D01*
X190472Y297464D01*
X189722D01*
G01X190472D02*
X190972Y297714D01*
X191389Y298130D01*
X191556Y298630D01*
X191389Y299130D01*
X190972Y299547D01*
X190222Y299797D01*
X189472Y299714D01*
X188722Y299380D01*
G01X192989Y294797D02*
Y298130D01*
G01Y297214D02*
X193239Y297630D01*
X193656Y297964D01*
X194239Y298130D01*
X194822Y297964D01*
X195239Y297630D01*
X195489Y297214D01*
Y294797D01*
G01Y297214D02*
X195739Y297630D01*
X196156Y297964D01*
X196739Y298130D01*
X197322Y297964D01*
X197739Y297630D01*
X197989Y297130D01*
Y294797D01*
G01X201089Y298130D02*
Y294797D01*
G01Y299464D02*
X200922Y299547D01*
Y299714D01*
X201089Y299797D01*
X201256Y299714D01*
Y299547D01*
X201089Y299464D01*
G01X206689Y294797D02*
Y299797D01*
G01X172172Y312964D02*
X174172D01*
G01X173089Y314047D02*
Y311880D01*
G01X177189Y311130D02*
X180189Y316297D01*
G01X183206Y312964D02*
X185372D01*
G01X188306Y315464D02*
X188806Y315964D01*
X189389Y316214D01*
X190056Y316297D01*
X190889Y316130D01*
X191472Y315714D01*
X191639Y315214D01*
X191556Y314714D01*
X191222Y314297D01*
X189556Y313464D01*
X188806Y312880D01*
X188306Y312047D01*
X188139Y311297D01*
X191639D01*
G01X192989D02*
Y314630D01*
G01Y313714D02*
X193239Y314130D01*
X193656Y314464D01*
X194239Y314630D01*
X194822Y314464D01*
X195239Y314130D01*
X195489Y313714D01*
Y311297D01*
G01Y313714D02*
X195739Y314130D01*
X196156Y314464D01*
X196739Y314630D01*
X197322Y314464D01*
X197739Y314130D01*
X197989Y313630D01*
Y311297D01*
G01X201089Y314630D02*
Y311297D01*
G01Y315964D02*
X200922Y316047D01*
Y316214D01*
X201089Y316297D01*
X201256Y316214D01*
Y316047D01*
X201089Y315964D01*
G01X206689Y311297D02*
Y316297D01*
G01X172172Y327964D02*
X174172D01*
G01X173089Y329047D02*
Y326880D01*
G01X177189Y326130D02*
X180189Y331297D01*
G01X183206Y327964D02*
X185372D01*
G01X188306Y330464D02*
X188806Y330964D01*
X189389Y331214D01*
X190056Y331297D01*
X190889Y331130D01*
X191472Y330714D01*
X191639Y330214D01*
X191556Y329714D01*
X191222Y329297D01*
X189556Y328464D01*
X188806Y327880D01*
X188306Y327047D01*
X188139Y326297D01*
X191639D01*
G01X192989D02*
Y329630D01*
G01Y328714D02*
X193239Y329130D01*
X193656Y329464D01*
X194239Y329630D01*
X194822Y329464D01*
X195239Y329130D01*
X195489Y328714D01*
Y326297D01*
G01Y328714D02*
X195739Y329130D01*
X196156Y329464D01*
X196739Y329630D01*
X197322Y329464D01*
X197739Y329130D01*
X197989Y328630D01*
Y326297D01*
G01X201089Y329630D02*
Y326297D01*
G01Y330964D02*
X200922Y331047D01*
Y331214D01*
X201089Y331297D01*
X201256Y331214D01*
Y331047D01*
X201089Y330964D01*
G01X206689Y326297D02*
Y331297D01*
G01X172172Y341464D02*
X174172D01*
G01X173089Y342547D02*
Y340380D01*
G01X177106Y343964D02*
X177606Y344464D01*
X178189Y344714D01*
X178856Y344797D01*
X179689Y344630D01*
X180272Y344214D01*
X180439Y343714D01*
X180356Y343214D01*
X180022Y342797D01*
X178356Y341964D01*
X177606Y341380D01*
X177106Y340547D01*
X176939Y339797D01*
X180439D01*
G01X182789Y339630D02*
X185789Y344797D01*
G01X188806Y341464D02*
X190972D01*
G01X196489Y339797D02*
Y344797D01*
X193406Y341214D01*
X197572D01*
G01X198589Y339797D02*
Y343130D01*
G01Y342214D02*
X198839Y342630D01*
X199256Y342964D01*
X199839Y343130D01*
X200422Y342964D01*
X200839Y342630D01*
X201089Y342214D01*
Y339797D01*
G01Y342214D02*
X201339Y342630D01*
X201756Y342964D01*
X202339Y343130D01*
X202922Y342964D01*
X203339Y342630D01*
X203589Y342130D01*
Y339797D01*
G01X206689Y343130D02*
Y339797D01*
G01Y344464D02*
X206522Y344547D01*
Y344714D01*
X206689Y344797D01*
X206856Y344714D01*
Y344547D01*
X206689Y344464D01*
G01X212289Y339797D02*
Y344797D01*
G01X172172Y357964D02*
X174172D01*
G01X173089Y359047D02*
Y356880D01*
G01X177189Y356130D02*
X180189Y361297D01*
G01X183206Y357964D02*
X185372D01*
G01X188056Y357297D02*
X188556Y356714D01*
X189222Y356380D01*
X189972Y356297D01*
X190639Y356380D01*
X191306Y356797D01*
X191722Y357297D01*
X191806Y357797D01*
X191639Y358380D01*
X191056Y358797D01*
X190472Y358964D01*
X189722D01*
G01X190472D02*
X190972Y359214D01*
X191389Y359630D01*
X191556Y360130D01*
X191389Y360630D01*
X190972Y361047D01*
X190222Y361297D01*
X189472Y361214D01*
X188722Y360880D01*
G01X192989Y356297D02*
Y359630D01*
G01Y358714D02*
X193239Y359130D01*
X193656Y359464D01*
X194239Y359630D01*
X194822Y359464D01*
X195239Y359130D01*
X195489Y358714D01*
Y356297D01*
G01Y358714D02*
X195739Y359130D01*
X196156Y359464D01*
X196739Y359630D01*
X197322Y359464D01*
X197739Y359130D01*
X197989Y358630D01*
Y356297D01*
G01X201089Y359630D02*
Y356297D01*
G01Y360964D02*
X200922Y361047D01*
Y361214D01*
X201089Y361297D01*
X201256Y361214D01*
Y361047D01*
X201089Y360964D01*
G01X206689Y356297D02*
Y361297D01*
G01X171006Y369797D02*
X173089Y374797D01*
X175172Y369797D01*
G01X174422Y371547D02*
X171756D01*
G01X178689Y369797D02*
Y374797D01*
G01X184289Y369797D02*
Y374797D01*
G01X189889Y369797D02*
X189389Y369880D01*
X188889Y370214D01*
X188556Y370797D01*
X188389Y371464D01*
X188556Y372130D01*
X188889Y372714D01*
X189389Y373047D01*
X189889Y373130D01*
X190389Y373047D01*
X190889Y372714D01*
X191222Y372130D01*
X191306Y371464D01*
X191222Y370797D01*
X190889Y370214D01*
X190389Y369880D01*
X189889Y369797D01*
G01X193406Y373130D02*
X194406Y369797D01*
X195489Y373130D01*
X196572Y369797D01*
X197572Y373130D01*
G01X172172Y386464D02*
X174172D01*
G01X173089Y387547D02*
Y385380D01*
G01X177189Y384630D02*
X180189Y389797D01*
G01X183206Y386464D02*
X185372D01*
G01X188306Y388964D02*
X188806Y389464D01*
X189389Y389714D01*
X190056Y389797D01*
X190889Y389630D01*
X191472Y389214D01*
X191639Y388714D01*
X191556Y388214D01*
X191222Y387797D01*
X189556Y386964D01*
X188806Y386380D01*
X188306Y385547D01*
X188139Y384797D01*
X191639D01*
G01X192989D02*
Y388130D01*
G01Y387214D02*
X193239Y387630D01*
X193656Y387964D01*
X194239Y388130D01*
X194822Y387964D01*
X195239Y387630D01*
X195489Y387214D01*
Y384797D01*
G01Y387214D02*
X195739Y387630D01*
X196156Y387964D01*
X196739Y388130D01*
X197322Y387964D01*
X197739Y387630D01*
X197989Y387130D01*
Y384797D01*
G01X201089Y388130D02*
Y384797D01*
G01Y389464D02*
X200922Y389547D01*
Y389714D01*
X201089Y389797D01*
X201256Y389714D01*
Y389547D01*
X201089Y389464D01*
G01X206689Y384797D02*
Y389797D01*
G01X170942Y404997D02*
Y409997D01*
X173109Y405830D01*
X175276Y409997D01*
Y404997D01*
G01X177292Y408330D02*
Y405997D01*
X177626Y405414D01*
X178126Y405080D01*
X178709Y404997D01*
X179292Y405080D01*
X179792Y405414D01*
X180126Y405997D01*
G01Y404997D02*
Y408330D01*
G01X183059Y405580D02*
X183476Y405247D01*
X184059Y404997D01*
X184559D01*
X185059Y405164D01*
X185392Y405414D01*
X185559Y405747D01*
X185476Y406247D01*
X185142Y406497D01*
X183642Y406997D01*
X183309Y407580D01*
X183476Y407997D01*
X183809Y408247D01*
X184309Y408330D01*
X184809Y408247D01*
X185309Y407997D01*
G01X189909Y409997D02*
Y404997D01*
G01X188742Y408330D02*
X191076D01*
G01X200609Y404997D02*
Y409247D01*
X200776Y409664D01*
X201109Y409914D01*
X201609Y409997D01*
X202109Y409830D01*
X202359Y409414D01*
G01X201359Y407997D02*
X199692D01*
G01X206709Y404997D02*
X206209Y405080D01*
X205709Y405414D01*
X205376Y405997D01*
X205209Y406664D01*
X205376Y407330D01*
X205709Y407914D01*
X206209Y408247D01*
X206709Y408330D01*
X207209Y408247D01*
X207709Y407914D01*
X208042Y407330D01*
X208126Y406664D01*
X208042Y405997D01*
X207709Y405414D01*
X207209Y405080D01*
X206709Y404997D01*
G01X212309D02*
Y409997D01*
G01X217909Y404997D02*
Y409997D01*
G01X223509Y404997D02*
X223009Y405080D01*
X222509Y405414D01*
X222176Y405997D01*
X222009Y406664D01*
X222176Y407330D01*
X222509Y407914D01*
X223009Y408247D01*
X223509Y408330D01*
X224009Y408247D01*
X224509Y407914D01*
X224842Y407330D01*
X224926Y406664D01*
X224842Y405997D01*
X224509Y405414D01*
X224009Y405080D01*
X223509Y404997D01*
G01X227026Y408330D02*
X228026Y404997D01*
X229109Y408330D01*
X230192Y404997D01*
X231192Y408330D01*
G01X183089Y434797D02*
Y429797D01*
G01X181172Y434797D02*
X185006D01*
G01X188689Y429797D02*
X188189Y429880D01*
X187689Y430214D01*
X187356Y430797D01*
X187189Y431464D01*
X187356Y432130D01*
X187689Y432714D01*
X188189Y433047D01*
X188689Y433130D01*
X189189Y433047D01*
X189689Y432714D01*
X190022Y432130D01*
X190106Y431464D01*
X190022Y430797D01*
X189689Y430214D01*
X189189Y429880D01*
X188689Y429797D01*
G01X194289D02*
Y434797D01*
G01X198639Y432047D02*
X201306D01*
X201056Y432630D01*
X200639Y432964D01*
X200056Y433130D01*
X199472Y433047D01*
X198972Y432797D01*
X198639Y432214D01*
X198472Y431714D01*
Y431214D01*
X198639Y430714D01*
X199056Y430214D01*
X199556Y429880D01*
X200139Y429797D01*
X200722Y429964D01*
X201306Y430464D01*
G01X204322Y429797D02*
Y433130D01*
G01Y432464D02*
X204739Y432797D01*
X205156Y433047D01*
X205739Y433130D01*
X206156Y433047D01*
X206656Y432797D01*
G01X212589Y429797D02*
Y433130D01*
G01Y432547D02*
X212256Y432880D01*
X211756Y433047D01*
X211172Y433130D01*
X210589Y432964D01*
X210089Y432630D01*
X209756Y432130D01*
X209589Y431464D01*
X209756Y430797D01*
X210089Y430297D01*
X210589Y429964D01*
X211172Y429797D01*
X211756Y429880D01*
X212256Y430130D01*
X212589Y430464D01*
G01X215272Y429797D02*
Y433130D01*
G01Y432297D02*
X215606Y432714D01*
X216106Y433047D01*
X216772Y433130D01*
X217356Y433047D01*
X217856Y432714D01*
X218106Y432130D01*
Y429797D01*
G01X223622Y432714D02*
X223039Y433047D01*
X222539Y433130D01*
X221872Y432964D01*
X221372Y432630D01*
X221039Y432047D01*
X220956Y431464D01*
X221039Y430880D01*
X221372Y430380D01*
X221872Y429964D01*
X222539Y429797D01*
X223122Y429964D01*
X223622Y430297D01*
G01X226639Y432047D02*
X229306D01*
X229056Y432630D01*
X228639Y432964D01*
X228056Y433130D01*
X227472Y433047D01*
X226972Y432797D01*
X226639Y432214D01*
X226472Y431714D01*
Y431214D01*
X226639Y430714D01*
X227056Y430214D01*
X227556Y429880D01*
X228139Y429797D01*
X228722Y429964D01*
X229306Y430464D01*
G01X216442Y204450D02*
X215609Y205284D01*
X215192Y206117D01*
Y209450D01*
X215609Y210284D01*
X216442Y211117D01*
G01X222459Y206117D02*
X221959Y206200D01*
X221459Y206534D01*
X221126Y207117D01*
X220959Y207784D01*
X221126Y208450D01*
X221459Y209034D01*
X221959Y209367D01*
X222459Y209450D01*
X222959Y209367D01*
X223459Y209034D01*
X223792Y208450D01*
X223876Y207784D01*
X223792Y207117D01*
X223459Y206534D01*
X222959Y206200D01*
X222459Y206117D01*
G01X226892D02*
Y209450D01*
G01Y208784D02*
X227309Y209117D01*
X227726Y209367D01*
X228309Y209450D01*
X228726Y209367D01*
X229226Y209117D01*
G01X260089Y482297D02*
Y-303203D01*
G01X278589Y616797D02*
Y-306703D01*
X908589D01*
Y548297D01*
X278589D01*
G01Y-286703D02*
X908589D01*
G01X288256Y-271953D02*
X288756Y-272370D01*
X289339Y-272620D01*
X290089Y-272703D01*
X290839Y-272536D01*
X291422Y-272203D01*
X291839Y-271620D01*
X291922Y-270953D01*
X291756Y-270286D01*
X291339Y-269870D01*
X290756Y-269536D01*
X290172Y-269453D01*
X289589Y-269536D01*
X288839Y-269870D01*
X289089Y-267703D01*
X291339D01*
G01X295689Y-272870D02*
X295522Y-272786D01*
Y-272620D01*
X295689Y-272536D01*
X295856Y-272620D01*
Y-272786D01*
X295689Y-272870D01*
G01X305222Y-272703D02*
Y-267703D01*
X307306D01*
X307972Y-267953D01*
X308389Y-268286D01*
X308556Y-268953D01*
X308389Y-269620D01*
X307889Y-270036D01*
X307306Y-270286D01*
X305222D01*
G01X307306D02*
X308556Y-272703D01*
G01X311239Y-270453D02*
X313906D01*
X313656Y-269870D01*
X313239Y-269536D01*
X312656Y-269370D01*
X312072Y-269453D01*
X311572Y-269703D01*
X311239Y-270286D01*
X311072Y-270786D01*
Y-271286D01*
X311239Y-271786D01*
X311656Y-272286D01*
X312156Y-272620D01*
X312739Y-272703D01*
X313322Y-272536D01*
X313906Y-272036D01*
G01X315589Y-272703D02*
Y-269370D01*
G01Y-270286D02*
X315839Y-269870D01*
X316256Y-269536D01*
X316839Y-269370D01*
X317422Y-269536D01*
X317839Y-269870D01*
X318089Y-270286D01*
Y-272703D01*
G01Y-270286D02*
X318339Y-269870D01*
X318756Y-269536D01*
X319339Y-269370D01*
X319922Y-269536D01*
X320339Y-269870D01*
X320589Y-270370D01*
Y-272703D01*
G01X325189D02*
Y-269370D01*
G01Y-269953D02*
X324856Y-269620D01*
X324356Y-269453D01*
X323772Y-269370D01*
X323189Y-269536D01*
X322689Y-269870D01*
X322356Y-270370D01*
X322189Y-271036D01*
X322356Y-271703D01*
X322689Y-272203D01*
X323189Y-272536D01*
X323772Y-272703D01*
X324356Y-272620D01*
X324856Y-272370D01*
X325189Y-272036D01*
G01X328122Y-272703D02*
Y-269370D01*
G01Y-270036D02*
X328539Y-269703D01*
X328956Y-269453D01*
X329539Y-269370D01*
X329956Y-269453D01*
X330456Y-269703D01*
G01X333472Y-272703D02*
Y-267703D01*
G01X336139Y-269370D02*
X333472Y-271286D01*
G01X334556Y-270536D02*
X336306Y-272703D01*
G01X338656Y-272870D02*
X342322Y-269203D01*
G01X340489Y-268536D02*
Y-273536D01*
G01X342322Y-272870D02*
X338656Y-269203D01*
G01X337989Y-271036D02*
X342989D01*
G01X278589Y-256703D02*
X908589D01*
G01X278589Y-148203D02*
X908589D01*
G01X278589Y101797D02*
X908589D01*
G01X291089Y115797D02*
Y120797D01*
X288006Y117214D01*
X292172D01*
G01X295689Y115630D02*
X295522Y115714D01*
Y115880D01*
X295689Y115964D01*
X295856Y115880D01*
Y115714D01*
X295689Y115630D01*
G01X305389Y115797D02*
Y120797D01*
G01Y118297D02*
X305806Y118797D01*
X306306Y119047D01*
X306806Y119130D01*
X307556Y118964D01*
X308056Y118630D01*
X308389Y118047D01*
Y117380D01*
X308222Y116714D01*
X307889Y116214D01*
X307306Y115880D01*
X306806Y115797D01*
X306306Y115880D01*
X305806Y116130D01*
X305389Y116547D01*
G01X313989Y115797D02*
Y119130D01*
G01Y118547D02*
X313656Y118880D01*
X313156Y119047D01*
X312572Y119130D01*
X311989Y118964D01*
X311489Y118630D01*
X311156Y118130D01*
X310989Y117464D01*
X311156Y116797D01*
X311489Y116297D01*
X311989Y115964D01*
X312572Y115797D01*
X313156Y115880D01*
X313656Y116130D01*
X313989Y116464D01*
G01X319422Y118714D02*
X318839Y119047D01*
X318339Y119130D01*
X317672Y118964D01*
X317172Y118630D01*
X316839Y118047D01*
X316756Y117464D01*
X316839Y116880D01*
X317172Y116380D01*
X317672Y115964D01*
X318339Y115797D01*
X318922Y115964D01*
X319422Y116297D01*
G01X322272Y115797D02*
Y120797D01*
G01X324939Y119130D02*
X322272Y117214D01*
G01X323356Y117964D02*
X325106Y115797D01*
G01X330789Y120797D02*
Y115797D01*
G01Y116547D02*
X330456Y116130D01*
X329956Y115880D01*
X329372Y115797D01*
X328706Y115964D01*
X328206Y116380D01*
X327872Y116880D01*
X327789Y117464D01*
X327872Y118047D01*
X328206Y118547D01*
X328706Y118964D01*
X329372Y119130D01*
X329956Y119047D01*
X330372Y118880D01*
X330789Y118547D01*
G01X333722Y115797D02*
Y119130D01*
G01Y118464D02*
X334139Y118797D01*
X334556Y119047D01*
X335139Y119130D01*
X335556Y119047D01*
X336056Y118797D01*
G01X340489Y119130D02*
Y115797D01*
G01Y120464D02*
X340322Y120547D01*
Y120714D01*
X340489Y120797D01*
X340656Y120714D01*
Y120547D01*
X340489Y120464D01*
G01X346089Y115797D02*
Y120797D01*
G01X351689Y115797D02*
Y120797D01*
G01X364389Y115797D02*
Y119130D01*
G01Y118547D02*
X364056Y118880D01*
X363556Y119047D01*
X362972Y119130D01*
X362389Y118964D01*
X361889Y118630D01*
X361556Y118130D01*
X361389Y117464D01*
X361556Y116797D01*
X361889Y116297D01*
X362389Y115964D01*
X362972Y115797D01*
X363556Y115880D01*
X364056Y116130D01*
X364389Y116464D01*
G01X367072Y115797D02*
Y119130D01*
G01Y118297D02*
X367406Y118714D01*
X367906Y119047D01*
X368572Y119130D01*
X369156Y119047D01*
X369656Y118714D01*
X369906Y118130D01*
Y115797D01*
G01X375589Y120797D02*
Y115797D01*
G01Y116547D02*
X375256Y116130D01*
X374756Y115880D01*
X374172Y115797D01*
X373506Y115964D01*
X373006Y116380D01*
X372672Y116880D01*
X372589Y117464D01*
X372672Y118047D01*
X373006Y118547D01*
X373506Y118964D01*
X374172Y119130D01*
X374756Y119047D01*
X375172Y118880D01*
X375589Y118547D01*
G01X384039Y116380D02*
X384456Y116047D01*
X385039Y115797D01*
X385539D01*
X386039Y115964D01*
X386372Y116214D01*
X386539Y116547D01*
X386456Y117047D01*
X386122Y117297D01*
X384622Y117797D01*
X384289Y118380D01*
X384456Y118797D01*
X384789Y119047D01*
X385289Y119130D01*
X385789Y119047D01*
X386289Y118797D01*
G01X392389Y114130D02*
Y119130D01*
G01Y118380D02*
X391972Y118797D01*
X391472Y119047D01*
X390889Y119130D01*
X390389Y119047D01*
X389806Y118630D01*
X389472Y118047D01*
X389389Y117464D01*
X389472Y116880D01*
X389806Y116297D01*
X390389Y115880D01*
X390889Y115797D01*
X391472Y115880D01*
X391972Y116130D01*
X392389Y116547D01*
G01X395072Y119130D02*
Y116797D01*
X395406Y116214D01*
X395906Y115880D01*
X396489Y115797D01*
X397072Y115880D01*
X397572Y116214D01*
X397906Y116797D01*
G01Y115797D02*
Y119130D01*
G01X403589Y115797D02*
Y119130D01*
G01Y118547D02*
X403256Y118880D01*
X402756Y119047D01*
X402172Y119130D01*
X401589Y118964D01*
X401089Y118630D01*
X400756Y118130D01*
X400589Y117464D01*
X400756Y116797D01*
X401089Y116297D01*
X401589Y115964D01*
X402172Y115797D01*
X402756Y115880D01*
X403256Y116130D01*
X403589Y116464D01*
G01X406522Y115797D02*
Y119130D01*
G01Y118464D02*
X406939Y118797D01*
X407356Y119047D01*
X407939Y119130D01*
X408356Y119047D01*
X408856Y118797D01*
G01X412039Y118047D02*
X414706D01*
X414456Y118630D01*
X414039Y118964D01*
X413456Y119130D01*
X412872Y119047D01*
X412372Y118797D01*
X412039Y118214D01*
X411872Y117714D01*
Y117214D01*
X412039Y116714D01*
X412456Y116214D01*
X412956Y115880D01*
X413539Y115797D01*
X414122Y115964D01*
X414706Y116464D01*
G01X423072Y115797D02*
Y120797D01*
G01Y118380D02*
X423489Y118797D01*
X423906Y119047D01*
X424572Y119130D01*
X425072Y119047D01*
X425656Y118714D01*
X425906Y118214D01*
Y115797D01*
G01X430089D02*
X429589Y115880D01*
X429089Y116214D01*
X428756Y116797D01*
X428589Y117464D01*
X428756Y118130D01*
X429089Y118714D01*
X429589Y119047D01*
X430089Y119130D01*
X430589Y119047D01*
X431089Y118714D01*
X431422Y118130D01*
X431506Y117464D01*
X431422Y116797D01*
X431089Y116214D01*
X430589Y115880D01*
X430089Y115797D01*
G01X435689D02*
Y120797D01*
G01X440039Y118047D02*
X442706D01*
X442456Y118630D01*
X442039Y118964D01*
X441456Y119130D01*
X440872Y119047D01*
X440372Y118797D01*
X440039Y118214D01*
X439872Y117714D01*
Y117214D01*
X440039Y116714D01*
X440456Y116214D01*
X440956Y115880D01*
X441539Y115797D01*
X442122Y115964D01*
X442706Y116464D01*
G01X446889Y115630D02*
X446722Y115714D01*
Y115880D01*
X446889Y115964D01*
X447056Y115880D01*
Y115714D01*
X446889Y115630D01*
G01Y117880D02*
X446722Y117964D01*
Y118130D01*
X446889Y118214D01*
X447056Y118130D01*
Y117964D01*
X446889Y117880D01*
G01X286996Y140970D02*
X290662Y144637D01*
G01X288829Y145304D02*
Y140304D01*
G01X290662Y140970D02*
X286996Y144637D01*
G01X286329Y142804D02*
X291329D01*
G01X294012Y139470D02*
X293179Y140304D01*
X292762Y141137D01*
Y144470D01*
X293179Y145304D01*
X294012Y146137D01*
G01X298196Y141887D02*
X298696Y141470D01*
X299279Y141220D01*
X300029Y141137D01*
X300779Y141304D01*
X301362Y141637D01*
X301779Y142220D01*
X301862Y142887D01*
X301696Y143554D01*
X301279Y143970D01*
X300696Y144304D01*
X300112Y144387D01*
X299529Y144304D01*
X298779Y143970D01*
X299029Y146137D01*
X301279D01*
G01X305629Y140970D02*
X305462Y141054D01*
Y141220D01*
X305629Y141304D01*
X305796Y141220D01*
Y141054D01*
X305629Y140970D01*
G01X311229Y141137D02*
Y146137D01*
X310229Y145137D01*
G01Y141137D02*
X312229D01*
G01X317246Y139470D02*
X318079Y140304D01*
X318496Y141137D01*
Y144470D01*
X318079Y145304D01*
X317246Y146137D01*
G01X278589Y131797D02*
X908589D01*
G01X286806Y158037D02*
X288889Y153037D01*
X290972Y158037D01*
G01X294489Y156370D02*
Y153037D01*
G01Y157704D02*
X294322Y157787D01*
Y157954D01*
X294489Y158037D01*
X294656Y157954D01*
Y157787D01*
X294489Y157704D01*
G01X301589Y153037D02*
Y156370D01*
G01Y155787D02*
X301256Y156120D01*
X300756Y156287D01*
X300172Y156370D01*
X299589Y156204D01*
X299089Y155870D01*
X298756Y155370D01*
X298589Y154704D01*
X298756Y154037D01*
X299089Y153537D01*
X299589Y153204D01*
X300172Y153037D01*
X300756Y153120D01*
X301256Y153370D01*
X301589Y153704D01*
G01X310289Y158037D02*
X312289D01*
G01X311289D02*
Y153037D01*
G01X310289D02*
X312289D01*
G01X315472D02*
Y156370D01*
G01Y155537D02*
X315806Y155954D01*
X316306Y156287D01*
X316972Y156370D01*
X317556Y156287D01*
X318056Y155954D01*
X318306Y155370D01*
Y153037D01*
G01X326422D02*
Y158037D01*
X328422D01*
X329089Y157787D01*
X329589Y157204D01*
X329756Y156537D01*
X329589Y155870D01*
X329172Y155370D01*
X328422Y155120D01*
X326422D01*
G01X335189Y153037D02*
Y156370D01*
G01Y155787D02*
X334856Y156120D01*
X334356Y156287D01*
X333772Y156370D01*
X333189Y156204D01*
X332689Y155870D01*
X332356Y155370D01*
X332189Y154704D01*
X332356Y154037D01*
X332689Y153537D01*
X333189Y153204D01*
X333772Y153037D01*
X334356Y153120D01*
X334856Y153370D01*
X335189Y153704D01*
G01X340789Y158037D02*
Y153037D01*
G01Y153787D02*
X340456Y153370D01*
X339956Y153120D01*
X339372Y153037D01*
X338706Y153204D01*
X338206Y153620D01*
X337872Y154120D01*
X337789Y154704D01*
X337872Y155287D01*
X338206Y155787D01*
X338706Y156204D01*
X339372Y156370D01*
X339956Y156287D01*
X340372Y156120D01*
X340789Y155787D01*
G01X344472Y151370D02*
X343639Y152204D01*
X343222Y153037D01*
Y156370D01*
X343639Y157204D01*
X344472Y158037D01*
G01X348406D02*
X350489Y153037D01*
X352572Y158037D01*
G01X355089D02*
X357089D01*
G01X356089D02*
Y153037D01*
G01X355089D02*
X357089D01*
G01X360022D02*
Y158037D01*
X362022D01*
X362689Y157787D01*
X363189Y157204D01*
X363356Y156537D01*
X363189Y155870D01*
X362772Y155370D01*
X362022Y155120D01*
X360022D01*
G01X367706Y151370D02*
X368539Y152204D01*
X368956Y153037D01*
Y156370D01*
X368539Y157204D01*
X367706Y158037D01*
G01X278589Y166797D02*
X908589D01*
G01X286696Y174600D02*
X290362Y178267D01*
G01X288529Y178934D02*
Y173934D01*
G01X290362Y174600D02*
X286696Y178267D01*
G01X286029Y176434D02*
X291029D01*
G01X293712Y173100D02*
X292879Y173934D01*
X292462Y174767D01*
Y178100D01*
X292879Y178934D01*
X293712Y179767D01*
G01X297896Y175517D02*
X298396Y175100D01*
X298979Y174850D01*
X299729Y174767D01*
X300479Y174934D01*
X301062Y175267D01*
X301479Y175850D01*
X301562Y176517D01*
X301396Y177184D01*
X300979Y177600D01*
X300396Y177934D01*
X299812Y178017D01*
X299229Y177934D01*
X298479Y177600D01*
X298729Y179767D01*
X300979D01*
G01X305329Y174600D02*
X305162Y174684D01*
Y174850D01*
X305329Y174934D01*
X305496Y174850D01*
Y174684D01*
X305329Y174600D01*
G01X310929Y174767D02*
Y179767D01*
X309929Y178767D01*
G01Y174767D02*
X311929D01*
G01X316946Y173100D02*
X317779Y173934D01*
X318196Y174767D01*
Y178100D01*
X317779Y178934D01*
X316946Y179767D01*
G01X286506Y190797D02*
X288589Y185797D01*
X290672Y190797D01*
G01X294189Y189130D02*
Y185797D01*
G01Y190464D02*
X294022Y190547D01*
Y190714D01*
X294189Y190797D01*
X294356Y190714D01*
Y190547D01*
X294189Y190464D01*
G01X301289Y185797D02*
Y189130D01*
G01Y188547D02*
X300956Y188880D01*
X300456Y189047D01*
X299872Y189130D01*
X299289Y188964D01*
X298789Y188630D01*
X298456Y188130D01*
X298289Y187464D01*
X298456Y186797D01*
X298789Y186297D01*
X299289Y185964D01*
X299872Y185797D01*
X300456Y185880D01*
X300956Y186130D01*
X301289Y186464D01*
G01X310989Y185797D02*
X310322Y185880D01*
X309739Y186214D01*
X309239Y186714D01*
X308906Y187297D01*
X308739Y187964D01*
Y188630D01*
X308906Y189297D01*
X309239Y189880D01*
X309739Y190380D01*
X310322Y190714D01*
X310989Y190797D01*
X311656Y190714D01*
X312239Y190380D01*
X312739Y189880D01*
X313072Y189297D01*
X313239Y188630D01*
Y187964D01*
X313072Y187297D01*
X312739Y186714D01*
X312239Y186214D01*
X311656Y185880D01*
X310989Y185797D01*
G01X315172D02*
Y189130D01*
G01Y188297D02*
X315506Y188714D01*
X316006Y189047D01*
X316672Y189130D01*
X317256Y189047D01*
X317756Y188714D01*
X318006Y188130D01*
Y185797D01*
G01X326122D02*
Y190797D01*
X328122D01*
X328789Y190547D01*
X329289Y189964D01*
X329456Y189297D01*
X329289Y188630D01*
X328872Y188130D01*
X328122Y187880D01*
X326122D01*
G01X334889Y185797D02*
Y189130D01*
G01Y188547D02*
X334556Y188880D01*
X334056Y189047D01*
X333472Y189130D01*
X332889Y188964D01*
X332389Y188630D01*
X332056Y188130D01*
X331889Y187464D01*
X332056Y186797D01*
X332389Y186297D01*
X332889Y185964D01*
X333472Y185797D01*
X334056Y185880D01*
X334556Y186130D01*
X334889Y186464D01*
G01X340489Y190797D02*
Y185797D01*
G01Y186547D02*
X340156Y186130D01*
X339656Y185880D01*
X339072Y185797D01*
X338406Y185964D01*
X337906Y186380D01*
X337572Y186880D01*
X337489Y187464D01*
X337572Y188047D01*
X337906Y188547D01*
X338406Y188964D01*
X339072Y189130D01*
X339656Y189047D01*
X340072Y188880D01*
X340489Y188547D01*
G01X344172Y184130D02*
X343339Y184964D01*
X342922Y185797D01*
Y189130D01*
X343339Y189964D01*
X344172Y190797D01*
G01X348106D02*
X350189Y185797D01*
X352272Y190797D01*
G01X355789Y185797D02*
X355122Y185880D01*
X354539Y186214D01*
X354039Y186714D01*
X353706Y187297D01*
X353539Y187964D01*
Y188630D01*
X353706Y189297D01*
X354039Y189880D01*
X354539Y190380D01*
X355122Y190714D01*
X355789Y190797D01*
X356456Y190714D01*
X357039Y190380D01*
X357539Y189880D01*
X357872Y189297D01*
X358039Y188630D01*
Y187964D01*
X357872Y187297D01*
X357539Y186714D01*
X357039Y186214D01*
X356456Y185880D01*
X355789Y185797D01*
G01X359722D02*
Y190797D01*
X361722D01*
X362389Y190547D01*
X362889Y189964D01*
X363056Y189297D01*
X362889Y188630D01*
X362472Y188130D01*
X361722Y187880D01*
X359722D01*
G01X367406Y184130D02*
X368239Y184964D01*
X368656Y185797D01*
Y189130D01*
X368239Y189964D01*
X367406Y190797D01*
G01X289256Y209464D02*
X289589Y209714D01*
X289839Y210130D01*
X290006Y210714D01*
X289839Y211214D01*
X289506Y211547D01*
X288922Y211797D01*
X286672D01*
Y206797D01*
X289422D01*
X290006Y207130D01*
X290339Y207630D01*
X290506Y208214D01*
X290339Y208797D01*
X289839Y209297D01*
X289256Y209464D01*
X286672D01*
G01X292772Y210130D02*
Y207797D01*
X293106Y207214D01*
X293606Y206880D01*
X294189Y206797D01*
X294772Y206880D01*
X295272Y207214D01*
X295606Y207797D01*
G01Y206797D02*
Y210130D01*
G01X298622Y206797D02*
Y210130D01*
G01Y209464D02*
X299039Y209797D01*
X299456Y210047D01*
X300039Y210130D01*
X300456Y210047D01*
X300956Y209797D01*
G01X305389Y210130D02*
Y206797D01*
G01Y211464D02*
X305222Y211547D01*
Y211714D01*
X305389Y211797D01*
X305556Y211714D01*
Y211547D01*
X305389Y211464D01*
G01X309739Y209047D02*
X312406D01*
X312156Y209630D01*
X311739Y209964D01*
X311156Y210130D01*
X310572Y210047D01*
X310072Y209797D01*
X309739Y209214D01*
X309572Y208714D01*
Y208214D01*
X309739Y207714D01*
X310156Y207214D01*
X310656Y206880D01*
X311239Y206797D01*
X311822Y206964D01*
X312406Y207464D01*
G01X318089Y211797D02*
Y206797D01*
G01Y207547D02*
X317756Y207130D01*
X317256Y206880D01*
X316672Y206797D01*
X316006Y206964D01*
X315506Y207380D01*
X315172Y207880D01*
X315089Y208464D01*
X315172Y209047D01*
X315506Y209547D01*
X316006Y209964D01*
X316672Y210130D01*
X317256Y210047D01*
X317672Y209880D01*
X318089Y209547D01*
G01X326372Y206797D02*
Y211797D01*
G01Y209380D02*
X326789Y209797D01*
X327206Y210047D01*
X327872Y210130D01*
X328372Y210047D01*
X328956Y209714D01*
X329206Y209214D01*
Y206797D01*
G01X333389D02*
X332889Y206880D01*
X332389Y207214D01*
X332056Y207797D01*
X331889Y208464D01*
X332056Y209130D01*
X332389Y209714D01*
X332889Y210047D01*
X333389Y210130D01*
X333889Y210047D01*
X334389Y209714D01*
X334722Y209130D01*
X334806Y208464D01*
X334722Y207797D01*
X334389Y207214D01*
X333889Y206880D01*
X333389Y206797D01*
G01X338989D02*
Y211797D01*
G01X343339Y209047D02*
X346006D01*
X345756Y209630D01*
X345339Y209964D01*
X344756Y210130D01*
X344172Y210047D01*
X343672Y209797D01*
X343339Y209214D01*
X343172Y208714D01*
Y208214D01*
X343339Y207714D01*
X343756Y207214D01*
X344256Y206880D01*
X344839Y206797D01*
X345422Y206964D01*
X346006Y207464D01*
G01X278589Y201797D02*
X908589D01*
G01X278589Y216797D02*
X908589D01*
G01X287006Y227797D02*
Y232797D01*
X290172D01*
G01X289006Y230380D02*
X287006D01*
G01X292772Y231130D02*
Y228797D01*
X293106Y228214D01*
X293606Y227880D01*
X294189Y227797D01*
X294772Y227880D01*
X295272Y228214D01*
X295606Y228797D01*
G01Y227797D02*
Y231130D01*
G01X299789Y227797D02*
Y232797D01*
G01X305389Y227797D02*
Y232797D01*
G01X315089Y226130D02*
Y231130D01*
G01Y230380D02*
X315506Y230797D01*
X315922Y231047D01*
X316589Y231130D01*
X317172Y231047D01*
X317756Y230630D01*
X318006Y230047D01*
X318089Y229464D01*
X318006Y228880D01*
X317756Y228297D01*
X317256Y227964D01*
X316589Y227797D01*
X316006Y227880D01*
X315422Y228130D01*
X315089Y228464D01*
G01X322189Y227797D02*
Y232797D01*
G01X326372Y231130D02*
Y228797D01*
X326706Y228214D01*
X327206Y227880D01*
X327789Y227797D01*
X328372Y227880D01*
X328872Y228214D01*
X329206Y228797D01*
G01Y227797D02*
Y231130D01*
G01X332222Y226547D02*
X332806Y226214D01*
X333472Y226130D01*
X334056Y226214D01*
X334556Y226630D01*
X334889Y227214D01*
Y231130D01*
G01Y230464D02*
X334556Y230797D01*
X334056Y231047D01*
X333472Y231130D01*
X332806Y230964D01*
X332389Y230630D01*
X332056Y230047D01*
X331889Y229464D01*
X331972Y228964D01*
X332306Y228380D01*
X332806Y227964D01*
X333472Y227797D01*
X333972Y227880D01*
X334556Y228214D01*
X334889Y228547D01*
G01X337822Y226547D02*
X338406Y226214D01*
X339072Y226130D01*
X339656Y226214D01*
X340156Y226630D01*
X340489Y227214D01*
Y231130D01*
G01Y230464D02*
X340156Y230797D01*
X339656Y231047D01*
X339072Y231130D01*
X338406Y230964D01*
X337989Y230630D01*
X337656Y230047D01*
X337489Y229464D01*
X337572Y228964D01*
X337906Y228380D01*
X338406Y227964D01*
X339072Y227797D01*
X339572Y227880D01*
X340156Y228214D01*
X340489Y228547D01*
G01X344589Y231130D02*
Y227797D01*
G01Y232464D02*
X344422Y232547D01*
Y232714D01*
X344589Y232797D01*
X344756Y232714D01*
Y232547D01*
X344589Y232464D01*
G01X348772Y227797D02*
Y231130D01*
G01Y230297D02*
X349106Y230714D01*
X349606Y231047D01*
X350272Y231130D01*
X350856Y231047D01*
X351356Y230714D01*
X351606Y230130D01*
Y227797D01*
G01X354622Y226547D02*
X355206Y226214D01*
X355872Y226130D01*
X356456Y226214D01*
X356956Y226630D01*
X357289Y227214D01*
Y231130D01*
G01Y230464D02*
X356956Y230797D01*
X356456Y231047D01*
X355872Y231130D01*
X355206Y230964D01*
X354789Y230630D01*
X354456Y230047D01*
X354289Y229464D01*
X354372Y228964D01*
X354706Y228380D01*
X355206Y227964D01*
X355872Y227797D01*
X356372Y227880D01*
X356956Y228214D01*
X357289Y228547D01*
G01X278589Y243797D02*
X908589D01*
G01X286839Y296297D02*
Y301297D01*
G01X290339D02*
Y296297D01*
G01Y298797D02*
X286839D01*
G01X295689Y296297D02*
Y299630D01*
G01Y299047D02*
X295356Y299380D01*
X294856Y299547D01*
X294272Y299630D01*
X293689Y299464D01*
X293189Y299130D01*
X292856Y298630D01*
X292689Y297964D01*
X292856Y297297D01*
X293189Y296797D01*
X293689Y296464D01*
X294272Y296297D01*
X294856Y296380D01*
X295356Y296630D01*
X295689Y296964D01*
G01X299789Y296297D02*
Y301297D01*
G01X304889Y296297D02*
Y300547D01*
X305056Y300964D01*
X305389Y301214D01*
X305889Y301297D01*
X306389Y301130D01*
X306639Y300714D01*
G01X305639Y299297D02*
X303972D01*
G01X314922Y296297D02*
Y301297D01*
X316922D01*
X317589Y301047D01*
X318089Y300464D01*
X318256Y299797D01*
X318089Y299130D01*
X317672Y298630D01*
X316922Y298380D01*
X314922D01*
G01X322189Y296297D02*
Y301297D01*
G01X326372Y299630D02*
Y297297D01*
X326706Y296714D01*
X327206Y296380D01*
X327789Y296297D01*
X328372Y296380D01*
X328872Y296714D01*
X329206Y297297D01*
G01Y296297D02*
Y299630D01*
G01X332222Y295047D02*
X332806Y294714D01*
X333472Y294630D01*
X334056Y294714D01*
X334556Y295130D01*
X334889Y295714D01*
Y299630D01*
G01Y298964D02*
X334556Y299297D01*
X334056Y299547D01*
X333472Y299630D01*
X332806Y299464D01*
X332389Y299130D01*
X332056Y298547D01*
X331889Y297964D01*
X331972Y297464D01*
X332306Y296880D01*
X332806Y296464D01*
X333472Y296297D01*
X333972Y296380D01*
X334556Y296714D01*
X334889Y297047D01*
G01X337822Y295047D02*
X338406Y294714D01*
X339072Y294630D01*
X339656Y294714D01*
X340156Y295130D01*
X340489Y295714D01*
Y299630D01*
G01Y298964D02*
X340156Y299297D01*
X339656Y299547D01*
X339072Y299630D01*
X338406Y299464D01*
X337989Y299130D01*
X337656Y298547D01*
X337489Y297964D01*
X337572Y297464D01*
X337906Y296880D01*
X338406Y296464D01*
X339072Y296297D01*
X339572Y296380D01*
X340156Y296714D01*
X340489Y297047D01*
G01X344589Y299630D02*
Y296297D01*
G01Y300964D02*
X344422Y301047D01*
Y301214D01*
X344589Y301297D01*
X344756Y301214D01*
Y301047D01*
X344589Y300964D01*
G01X348772Y296297D02*
Y299630D01*
G01Y298797D02*
X349106Y299214D01*
X349606Y299547D01*
X350272Y299630D01*
X350856Y299547D01*
X351356Y299214D01*
X351606Y298630D01*
Y296297D01*
G01X354622Y295047D02*
X355206Y294714D01*
X355872Y294630D01*
X356456Y294714D01*
X356956Y295130D01*
X357289Y295714D01*
Y299630D01*
G01Y298964D02*
X356956Y299297D01*
X356456Y299547D01*
X355872Y299630D01*
X355206Y299464D01*
X354789Y299130D01*
X354456Y298547D01*
X354289Y297964D01*
X354372Y297464D01*
X354706Y296880D01*
X355206Y296464D01*
X355872Y296297D01*
X356372Y296380D01*
X356956Y296714D01*
X357289Y297047D01*
G01X278589Y345797D02*
X908589D01*
G01X288422Y355297D02*
Y360297D01*
X290422D01*
X291089Y360047D01*
X291589Y359464D01*
X291756Y358797D01*
X291589Y358130D01*
X291172Y357630D01*
X290422Y357380D01*
X288422D01*
G01X295689Y355297D02*
Y360297D01*
G01X299872Y358630D02*
Y356297D01*
X300206Y355714D01*
X300706Y355380D01*
X301289Y355297D01*
X301872Y355380D01*
X302372Y355714D01*
X302706Y356297D01*
G01Y355297D02*
Y358630D01*
G01X305722Y354047D02*
X306306Y353714D01*
X306972Y353630D01*
X307556Y353714D01*
X308056Y354130D01*
X308389Y354714D01*
Y358630D01*
G01Y357964D02*
X308056Y358297D01*
X307556Y358547D01*
X306972Y358630D01*
X306306Y358464D01*
X305889Y358130D01*
X305556Y357547D01*
X305389Y356964D01*
X305472Y356464D01*
X305806Y355880D01*
X306306Y355464D01*
X306972Y355297D01*
X307472Y355380D01*
X308056Y355714D01*
X308389Y356047D01*
G01X311322Y354047D02*
X311906Y353714D01*
X312572Y353630D01*
X313156Y353714D01*
X313656Y354130D01*
X313989Y354714D01*
Y358630D01*
G01Y357964D02*
X313656Y358297D01*
X313156Y358547D01*
X312572Y358630D01*
X311906Y358464D01*
X311489Y358130D01*
X311156Y357547D01*
X310989Y356964D01*
X311072Y356464D01*
X311406Y355880D01*
X311906Y355464D01*
X312572Y355297D01*
X313072Y355380D01*
X313656Y355714D01*
X313989Y356047D01*
G01X318089Y358630D02*
Y355297D01*
G01Y359964D02*
X317922Y360047D01*
Y360214D01*
X318089Y360297D01*
X318256Y360214D01*
Y360047D01*
X318089Y359964D01*
G01X322272Y355297D02*
Y358630D01*
G01Y357797D02*
X322606Y358214D01*
X323106Y358547D01*
X323772Y358630D01*
X324356Y358547D01*
X324856Y358214D01*
X325106Y357630D01*
Y355297D01*
G01X328122Y354047D02*
X328706Y353714D01*
X329372Y353630D01*
X329956Y353714D01*
X330456Y354130D01*
X330789Y354714D01*
Y358630D01*
G01Y357964D02*
X330456Y358297D01*
X329956Y358547D01*
X329372Y358630D01*
X328706Y358464D01*
X328289Y358130D01*
X327956Y357547D01*
X327789Y356964D01*
X327872Y356464D01*
X328206Y355880D01*
X328706Y355464D01*
X329372Y355297D01*
X329872Y355380D01*
X330456Y355714D01*
X330789Y356047D01*
G01X341989Y360297D02*
Y355297D01*
G01Y356047D02*
X341656Y355630D01*
X341156Y355380D01*
X340572Y355297D01*
X339906Y355464D01*
X339406Y355880D01*
X339072Y356380D01*
X338989Y356964D01*
X339072Y357547D01*
X339406Y358047D01*
X339906Y358464D01*
X340572Y358630D01*
X341156Y358547D01*
X341572Y358380D01*
X341989Y358047D01*
G01X344839Y357547D02*
X347506D01*
X347256Y358130D01*
X346839Y358464D01*
X346256Y358630D01*
X345672Y358547D01*
X345172Y358297D01*
X344839Y357714D01*
X344672Y357214D01*
Y356714D01*
X344839Y356214D01*
X345256Y355714D01*
X345756Y355380D01*
X346339Y355297D01*
X346922Y355464D01*
X347506Y355964D01*
G01X351189Y355297D02*
Y359547D01*
X351356Y359964D01*
X351689Y360214D01*
X352189Y360297D01*
X352689Y360130D01*
X352939Y359714D01*
G01X351939Y358297D02*
X350272D01*
G01X357289Y358630D02*
Y355297D01*
G01Y359964D02*
X357122Y360047D01*
Y360214D01*
X357289Y360297D01*
X357456Y360214D01*
Y360047D01*
X357289Y359964D01*
G01X361472Y355297D02*
Y358630D01*
G01Y357797D02*
X361806Y358214D01*
X362306Y358547D01*
X362972Y358630D01*
X363556Y358547D01*
X364056Y358214D01*
X364306Y357630D01*
Y355297D01*
G01X367239Y357547D02*
X369906D01*
X369656Y358130D01*
X369239Y358464D01*
X368656Y358630D01*
X368072Y358547D01*
X367572Y358297D01*
X367239Y357714D01*
X367072Y357214D01*
Y356714D01*
X367239Y356214D01*
X367656Y355714D01*
X368156Y355380D01*
X368739Y355297D01*
X369322Y355464D01*
X369906Y355964D01*
G01X278589Y370797D02*
X908589D01*
G01X288256Y531297D02*
X288756Y530714D01*
X289422Y530380D01*
X290172Y530297D01*
X290839Y530380D01*
X291506Y530797D01*
X291922Y531297D01*
X292006Y531797D01*
X291839Y532380D01*
X291256Y532797D01*
X290672Y532964D01*
X289922D01*
G01X290672D02*
X291172Y533214D01*
X291589Y533630D01*
X291756Y534130D01*
X291589Y534630D01*
X291172Y535047D01*
X290422Y535297D01*
X289672Y535214D01*
X288922Y534880D01*
G01X295689Y530130D02*
X295522Y530214D01*
Y530380D01*
X295689Y530464D01*
X295856Y530380D01*
Y530214D01*
X295689Y530130D01*
G01X305222Y530297D02*
Y535297D01*
X307222D01*
X307889Y535047D01*
X308389Y534464D01*
X308556Y533797D01*
X308389Y533130D01*
X307972Y532630D01*
X307222Y532380D01*
X305222D01*
G01X312489Y530297D02*
Y535297D01*
G01X316672Y533630D02*
Y531297D01*
X317006Y530714D01*
X317506Y530380D01*
X318089Y530297D01*
X318672Y530380D01*
X319172Y530714D01*
X319506Y531297D01*
G01Y530297D02*
Y533630D01*
G01X322522Y529047D02*
X323106Y528714D01*
X323772Y528630D01*
X324356Y528714D01*
X324856Y529130D01*
X325189Y529714D01*
Y533630D01*
G01Y532964D02*
X324856Y533297D01*
X324356Y533547D01*
X323772Y533630D01*
X323106Y533464D01*
X322689Y533130D01*
X322356Y532547D01*
X322189Y531964D01*
X322272Y531464D01*
X322606Y530880D01*
X323106Y530464D01*
X323772Y530297D01*
X324272Y530380D01*
X324856Y530714D01*
X325189Y531047D01*
G01X333389Y533630D02*
X334889Y530297D01*
X336389Y533630D01*
G01X340489D02*
Y530297D01*
G01Y534964D02*
X340322Y535047D01*
Y535214D01*
X340489Y535297D01*
X340656Y535214D01*
Y535047D01*
X340489Y534964D01*
G01X347589Y530297D02*
Y533630D01*
G01Y533047D02*
X347256Y533380D01*
X346756Y533547D01*
X346172Y533630D01*
X345589Y533464D01*
X345089Y533130D01*
X344756Y532630D01*
X344589Y531964D01*
X344756Y531297D01*
X345089Y530797D01*
X345589Y530464D01*
X346172Y530297D01*
X346756Y530380D01*
X347256Y530630D01*
X347589Y530964D01*
G01X355789Y530130D02*
X358789Y535297D01*
G01X360806D02*
X362889Y530297D01*
X364972Y535297D01*
G01X368489Y530297D02*
X367822Y530380D01*
X367239Y530714D01*
X366739Y531214D01*
X366406Y531797D01*
X366239Y532464D01*
Y533130D01*
X366406Y533797D01*
X366739Y534380D01*
X367239Y534880D01*
X367822Y535214D01*
X368489Y535297D01*
X369156Y535214D01*
X369739Y534880D01*
X370239Y534380D01*
X370572Y533797D01*
X370739Y533130D01*
Y532464D01*
X370572Y531797D01*
X370239Y531214D01*
X369739Y530714D01*
X369156Y530380D01*
X368489Y530297D01*
G01X372422D02*
Y535297D01*
X374422D01*
X375089Y535047D01*
X375589Y534464D01*
X375756Y533797D01*
X375589Y533130D01*
X375172Y532630D01*
X374422Y532380D01*
X372422D01*
G01X378189Y530130D02*
X381189Y535297D01*
G01X383206D02*
X385289Y530297D01*
X387372Y535297D01*
G01X389889D02*
X391889D01*
G01X390889D02*
Y530297D01*
G01X389889D02*
X391889D01*
G01X394822D02*
Y535297D01*
X396822D01*
X397489Y535047D01*
X397989Y534464D01*
X398156Y533797D01*
X397989Y533130D01*
X397572Y532630D01*
X396822Y532380D01*
X394822D01*
G01X402089Y530130D02*
X401922Y530214D01*
Y530380D01*
X402089Y530464D01*
X402256Y530380D01*
Y530214D01*
X402089Y530130D01*
G01Y532380D02*
X401922Y532464D01*
Y532630D01*
X402089Y532714D01*
X402256Y532630D01*
Y532464D01*
X402089Y532380D01*
G01X278589Y518297D02*
X910089D01*
G01X290402Y579297D02*
Y584297D01*
X292486D01*
X293152Y584047D01*
X293569Y583714D01*
X293736Y583047D01*
X293569Y582380D01*
X293069Y581964D01*
X292486Y581714D01*
X290402D01*
G01X292486D02*
X293736Y579297D01*
G01X297669D02*
X297169Y579380D01*
X296669Y579714D01*
X296336Y580297D01*
X296169Y580964D01*
X296336Y581630D01*
X296669Y582214D01*
X297169Y582547D01*
X297669Y582630D01*
X298169Y582547D01*
X298669Y582214D01*
X299002Y581630D01*
X299086Y580964D01*
X299002Y580297D01*
X298669Y579714D01*
X298169Y579380D01*
X297669Y579297D01*
G01X301852Y582630D02*
Y580297D01*
X302186Y579714D01*
X302686Y579380D01*
X303269Y579297D01*
X303852Y579380D01*
X304352Y579714D01*
X304686Y580297D01*
G01Y579297D02*
Y582630D01*
G01X308869Y584297D02*
Y579297D01*
G01X307702Y582630D02*
X310036D01*
G01X314469D02*
Y579297D01*
G01Y583964D02*
X314302Y584047D01*
Y584214D01*
X314469Y584297D01*
X314636Y584214D01*
Y584047D01*
X314469Y583964D01*
G01X318652Y579297D02*
Y582630D01*
G01Y581797D02*
X318986Y582214D01*
X319486Y582547D01*
X320152Y582630D01*
X320736Y582547D01*
X321236Y582214D01*
X321486Y581630D01*
Y579297D01*
G01X324502Y578047D02*
X325086Y577714D01*
X325752Y577630D01*
X326336Y577714D01*
X326836Y578130D01*
X327169Y578714D01*
Y582630D01*
G01Y581964D02*
X326836Y582297D01*
X326336Y582547D01*
X325752Y582630D01*
X325086Y582464D01*
X324669Y582130D01*
X324336Y581547D01*
X324169Y580964D01*
X324252Y580464D01*
X324586Y579880D01*
X325086Y579464D01*
X325752Y579297D01*
X326252Y579380D01*
X326836Y579714D01*
X327169Y580047D01*
G01X278569Y616797D02*
X908589D01*
G01X302526Y-299023D02*
X303026Y-299440D01*
X303609Y-299690D01*
X304359Y-299773D01*
X305109Y-299606D01*
X305692Y-299273D01*
X306109Y-298690D01*
X306192Y-298023D01*
X306026Y-297356D01*
X305609Y-296940D01*
X305026Y-296606D01*
X304442Y-296523D01*
X303859Y-296606D01*
X303109Y-296940D01*
X303359Y-294773D01*
X305609D01*
G01X309959Y-299940D02*
X309792Y-299856D01*
Y-299690D01*
X309959Y-299606D01*
X310126Y-299690D01*
Y-299856D01*
X309959Y-299940D01*
G01X315559Y-299773D02*
Y-294773D01*
X314559Y-295773D01*
G01Y-299773D02*
X316559D01*
G01X325759Y-294773D02*
X327759D01*
G01X326759D02*
Y-299773D01*
G01X325759D02*
X327759D01*
G01X331859D02*
Y-295523D01*
X332026Y-295106D01*
X332359Y-294856D01*
X332859Y-294773D01*
X333359Y-294940D01*
X333609Y-295356D01*
G01X332609Y-296773D02*
X330942D01*
G01X344059Y-297273D02*
X345726D01*
Y-298773D01*
X345226Y-299273D01*
X344642Y-299606D01*
X343809Y-299773D01*
X342976Y-299606D01*
X342392Y-299273D01*
X341892Y-298773D01*
X341559Y-298190D01*
X341392Y-297523D01*
Y-296940D01*
X341559Y-296440D01*
X341892Y-295856D01*
X342392Y-295356D01*
X342892Y-295023D01*
X343559Y-294773D01*
X344142D01*
X344809Y-294940D01*
X345309Y-295273D01*
G01X347909Y-297523D02*
X350576D01*
X350326Y-296940D01*
X349909Y-296606D01*
X349326Y-296440D01*
X348742Y-296523D01*
X348242Y-296773D01*
X347909Y-297356D01*
X347742Y-297856D01*
Y-298356D01*
X347909Y-298856D01*
X348326Y-299356D01*
X348826Y-299690D01*
X349409Y-299773D01*
X349992Y-299606D01*
X350576Y-299106D01*
G01X353592Y-299773D02*
Y-296440D01*
G01Y-297106D02*
X354009Y-296773D01*
X354426Y-296523D01*
X355009Y-296440D01*
X355426Y-296523D01*
X355926Y-296773D01*
G01X358859Y-299773D02*
Y-294773D01*
G01Y-297273D02*
X359276Y-296773D01*
X359776Y-296523D01*
X360276Y-296440D01*
X361026Y-296606D01*
X361526Y-296940D01*
X361859Y-297523D01*
Y-298190D01*
X361692Y-298856D01*
X361359Y-299356D01*
X360776Y-299690D01*
X360276Y-299773D01*
X359776Y-299690D01*
X359276Y-299440D01*
X358859Y-299023D01*
G01X364709Y-297523D02*
X367376D01*
X367126Y-296940D01*
X366709Y-296606D01*
X366126Y-296440D01*
X365542Y-296523D01*
X365042Y-296773D01*
X364709Y-297356D01*
X364542Y-297856D01*
Y-298356D01*
X364709Y-298856D01*
X365126Y-299356D01*
X365626Y-299690D01*
X366209Y-299773D01*
X366792Y-299606D01*
X367376Y-299106D01*
G01X370392Y-299773D02*
Y-296440D01*
G01Y-297106D02*
X370809Y-296773D01*
X371226Y-296523D01*
X371809Y-296440D01*
X372226Y-296523D01*
X372726Y-296773D01*
G01X381342Y-299773D02*
Y-294773D01*
G01Y-297190D02*
X381759Y-296773D01*
X382176Y-296523D01*
X382842Y-296440D01*
X383342Y-296523D01*
X383926Y-296856D01*
X384176Y-297356D01*
Y-299773D01*
G01X389859D02*
Y-296440D01*
G01Y-297023D02*
X389526Y-296690D01*
X389026Y-296523D01*
X388442Y-296440D01*
X387859Y-296606D01*
X387359Y-296940D01*
X387026Y-297440D01*
X386859Y-298106D01*
X387026Y-298773D01*
X387359Y-299273D01*
X387859Y-299606D01*
X388442Y-299773D01*
X389026Y-299690D01*
X389526Y-299440D01*
X389859Y-299106D01*
G01X392709Y-299190D02*
X393126Y-299523D01*
X393709Y-299773D01*
X394209D01*
X394709Y-299606D01*
X395042Y-299356D01*
X395209Y-299023D01*
X395126Y-298523D01*
X394792Y-298273D01*
X393292Y-297773D01*
X392959Y-297190D01*
X393126Y-296773D01*
X393459Y-296523D01*
X393959Y-296440D01*
X394459Y-296523D01*
X394959Y-296773D01*
G01X405159Y-294773D02*
Y-299773D01*
G01X403992Y-296440D02*
X406326D01*
G01X409342Y-299773D02*
Y-294773D01*
G01Y-297190D02*
X409759Y-296773D01*
X410176Y-296523D01*
X410842Y-296440D01*
X411342Y-296523D01*
X411926Y-296856D01*
X412176Y-297356D01*
Y-299773D01*
G01X416359Y-296440D02*
Y-299773D01*
G01Y-295106D02*
X416192Y-295023D01*
Y-294856D01*
X416359Y-294773D01*
X416526Y-294856D01*
Y-295023D01*
X416359Y-295106D01*
G01X420709Y-299190D02*
X421126Y-299523D01*
X421709Y-299773D01*
X422209D01*
X422709Y-299606D01*
X423042Y-299356D01*
X423209Y-299023D01*
X423126Y-298523D01*
X422792Y-298273D01*
X421292Y-297773D01*
X420959Y-297190D01*
X421126Y-296773D01*
X421459Y-296523D01*
X421959Y-296440D01*
X422459Y-296523D01*
X422959Y-296773D01*
G01X431742Y-299773D02*
Y-294773D01*
G01X434409Y-296440D02*
X431742Y-298356D01*
G01X432826Y-297606D02*
X434576Y-299773D01*
G01X438759Y-296440D02*
Y-299773D01*
G01Y-295106D02*
X438592Y-295023D01*
Y-294856D01*
X438759Y-294773D01*
X438926Y-294856D01*
Y-295023D01*
X438759Y-295106D01*
G01X442942Y-299773D02*
Y-296440D01*
G01Y-297273D02*
X443276Y-296856D01*
X443776Y-296523D01*
X444442Y-296440D01*
X445026Y-296523D01*
X445526Y-296856D01*
X445776Y-297440D01*
Y-299773D01*
G01X451459Y-294773D02*
Y-299773D01*
G01Y-299023D02*
X451126Y-299440D01*
X450626Y-299690D01*
X450042Y-299773D01*
X449376Y-299606D01*
X448876Y-299190D01*
X448542Y-298690D01*
X448459Y-298106D01*
X448542Y-297523D01*
X448876Y-297023D01*
X449376Y-296606D01*
X450042Y-296440D01*
X450626Y-296523D01*
X451042Y-296690D01*
X451459Y-297023D01*
G01X461159Y-299773D02*
X460659Y-299690D01*
X460159Y-299356D01*
X459826Y-298773D01*
X459659Y-298106D01*
X459826Y-297440D01*
X460159Y-296856D01*
X460659Y-296523D01*
X461159Y-296440D01*
X461659Y-296523D01*
X462159Y-296856D01*
X462492Y-297440D01*
X462576Y-298106D01*
X462492Y-298773D01*
X462159Y-299356D01*
X461659Y-299690D01*
X461159Y-299773D01*
G01X466259D02*
Y-295523D01*
X466426Y-295106D01*
X466759Y-294856D01*
X467259Y-294773D01*
X467759Y-294940D01*
X468009Y-295356D01*
G01X467009Y-296773D02*
X465342D01*
G01X479459Y-294773D02*
Y-299773D01*
G01Y-299023D02*
X479126Y-299440D01*
X478626Y-299690D01*
X478042Y-299773D01*
X477376Y-299606D01*
X476876Y-299190D01*
X476542Y-298690D01*
X476459Y-298106D01*
X476542Y-297523D01*
X476876Y-297023D01*
X477376Y-296606D01*
X478042Y-296440D01*
X478626Y-296523D01*
X479042Y-296690D01*
X479459Y-297023D01*
G01X482309Y-297523D02*
X484976D01*
X484726Y-296940D01*
X484309Y-296606D01*
X483726Y-296440D01*
X483142Y-296523D01*
X482642Y-296773D01*
X482309Y-297356D01*
X482142Y-297856D01*
Y-298356D01*
X482309Y-298856D01*
X482726Y-299356D01*
X483226Y-299690D01*
X483809Y-299773D01*
X484392Y-299606D01*
X484976Y-299106D01*
G01X487909Y-299190D02*
X488326Y-299523D01*
X488909Y-299773D01*
X489409D01*
X489909Y-299606D01*
X490242Y-299356D01*
X490409Y-299023D01*
X490326Y-298523D01*
X489992Y-298273D01*
X488492Y-297773D01*
X488159Y-297190D01*
X488326Y-296773D01*
X488659Y-296523D01*
X489159Y-296440D01*
X489659Y-296523D01*
X490159Y-296773D01*
G01X494759Y-296440D02*
Y-299773D01*
G01Y-295106D02*
X494592Y-295023D01*
Y-294856D01*
X494759Y-294773D01*
X494926Y-294856D01*
Y-295023D01*
X494759Y-295106D01*
G01X499192Y-301023D02*
X499776Y-301356D01*
X500442Y-301440D01*
X501026Y-301356D01*
X501526Y-300940D01*
X501859Y-300356D01*
Y-296440D01*
G01Y-297106D02*
X501526Y-296773D01*
X501026Y-296523D01*
X500442Y-296440D01*
X499776Y-296606D01*
X499359Y-296940D01*
X499026Y-297523D01*
X498859Y-298106D01*
X498942Y-298606D01*
X499276Y-299190D01*
X499776Y-299606D01*
X500442Y-299773D01*
X500942Y-299690D01*
X501526Y-299356D01*
X501859Y-299023D01*
G01X504542Y-299773D02*
Y-296440D01*
G01Y-297273D02*
X504876Y-296856D01*
X505376Y-296523D01*
X506042Y-296440D01*
X506626Y-296523D01*
X507126Y-296856D01*
X507376Y-297440D01*
Y-299773D01*
G01X511392Y-300690D02*
X511726Y-299606D01*
G01X521259Y-301440D02*
Y-296440D01*
G01Y-297190D02*
X521676Y-296773D01*
X522092Y-296523D01*
X522759Y-296440D01*
X523342Y-296523D01*
X523926Y-296940D01*
X524176Y-297523D01*
X524259Y-298106D01*
X524176Y-298690D01*
X523926Y-299273D01*
X523426Y-299606D01*
X522759Y-299773D01*
X522176Y-299690D01*
X521592Y-299440D01*
X521259Y-299106D01*
G01X528359Y-299773D02*
Y-294773D01*
G01X532709Y-297523D02*
X535376D01*
X535126Y-296940D01*
X534709Y-296606D01*
X534126Y-296440D01*
X533542Y-296523D01*
X533042Y-296773D01*
X532709Y-297356D01*
X532542Y-297856D01*
Y-298356D01*
X532709Y-298856D01*
X533126Y-299356D01*
X533626Y-299690D01*
X534209Y-299773D01*
X534792Y-299606D01*
X535376Y-299106D01*
G01X541059Y-299773D02*
Y-296440D01*
G01Y-297023D02*
X540726Y-296690D01*
X540226Y-296523D01*
X539642Y-296440D01*
X539059Y-296606D01*
X538559Y-296940D01*
X538226Y-297440D01*
X538059Y-298106D01*
X538226Y-298773D01*
X538559Y-299273D01*
X539059Y-299606D01*
X539642Y-299773D01*
X540226Y-299690D01*
X540726Y-299440D01*
X541059Y-299106D01*
G01X543909Y-299190D02*
X544326Y-299523D01*
X544909Y-299773D01*
X545409D01*
X545909Y-299606D01*
X546242Y-299356D01*
X546409Y-299023D01*
X546326Y-298523D01*
X545992Y-298273D01*
X544492Y-297773D01*
X544159Y-297190D01*
X544326Y-296773D01*
X544659Y-296523D01*
X545159Y-296440D01*
X545659Y-296523D01*
X546159Y-296773D01*
G01X549509Y-297523D02*
X552176D01*
X551926Y-296940D01*
X551509Y-296606D01*
X550926Y-296440D01*
X550342Y-296523D01*
X549842Y-296773D01*
X549509Y-297356D01*
X549342Y-297856D01*
Y-298356D01*
X549509Y-298856D01*
X549926Y-299356D01*
X550426Y-299690D01*
X551009Y-299773D01*
X551592Y-299606D01*
X552176Y-299106D01*
G01X561459Y-299773D02*
Y-295523D01*
X561626Y-295106D01*
X561959Y-294856D01*
X562459Y-294773D01*
X562959Y-294940D01*
X563209Y-295356D01*
G01X562209Y-296773D02*
X560542D01*
G01X567559Y-299773D02*
X567059Y-299690D01*
X566559Y-299356D01*
X566226Y-298773D01*
X566059Y-298106D01*
X566226Y-297440D01*
X566559Y-296856D01*
X567059Y-296523D01*
X567559Y-296440D01*
X568059Y-296523D01*
X568559Y-296856D01*
X568892Y-297440D01*
X568976Y-298106D01*
X568892Y-298773D01*
X568559Y-299356D01*
X568059Y-299690D01*
X567559Y-299773D01*
G01X573159D02*
Y-294773D01*
G01X578759Y-299773D02*
Y-294773D01*
G01X584359Y-299773D02*
X583859Y-299690D01*
X583359Y-299356D01*
X583026Y-298773D01*
X582859Y-298106D01*
X583026Y-297440D01*
X583359Y-296856D01*
X583859Y-296523D01*
X584359Y-296440D01*
X584859Y-296523D01*
X585359Y-296856D01*
X585692Y-297440D01*
X585776Y-298106D01*
X585692Y-298773D01*
X585359Y-299356D01*
X584859Y-299690D01*
X584359Y-299773D01*
G01X587876Y-296440D02*
X588876Y-299773D01*
X589959Y-296440D01*
X591042Y-299773D01*
X592042Y-296440D01*
G01X595559Y-299940D02*
X595392Y-299856D01*
Y-299690D01*
X595559Y-299606D01*
X595726Y-299690D01*
Y-299856D01*
X595559Y-299940D01*
G01X605759Y-294773D02*
X607759D01*
G01X606759D02*
Y-299773D01*
G01X605759D02*
X607759D01*
G01X611859D02*
Y-295523D01*
X612026Y-295106D01*
X612359Y-294856D01*
X612859Y-294773D01*
X613359Y-294940D01*
X613609Y-295356D01*
G01X612609Y-296773D02*
X610942D01*
G01X622142Y-299773D02*
Y-296440D01*
G01Y-297273D02*
X622476Y-296856D01*
X622976Y-296523D01*
X623642Y-296440D01*
X624226Y-296523D01*
X624726Y-296856D01*
X624976Y-297440D01*
Y-299773D01*
G01X629159D02*
X628659Y-299690D01*
X628159Y-299356D01*
X627826Y-298773D01*
X627659Y-298106D01*
X627826Y-297440D01*
X628159Y-296856D01*
X628659Y-296523D01*
X629159Y-296440D01*
X629659Y-296523D01*
X630159Y-296856D01*
X630492Y-297440D01*
X630576Y-298106D01*
X630492Y-298773D01*
X630159Y-299356D01*
X629659Y-299690D01*
X629159Y-299773D01*
G01X634759Y-294773D02*
Y-299773D01*
G01X633592Y-296440D02*
X635926D01*
G01X640192Y-300690D02*
X640526Y-299606D01*
G01X650059Y-301440D02*
Y-296440D01*
G01Y-297190D02*
X650476Y-296773D01*
X650892Y-296523D01*
X651559Y-296440D01*
X652142Y-296523D01*
X652726Y-296940D01*
X652976Y-297523D01*
X653059Y-298106D01*
X652976Y-298690D01*
X652726Y-299273D01*
X652226Y-299606D01*
X651559Y-299773D01*
X650976Y-299690D01*
X650392Y-299440D01*
X650059Y-299106D01*
G01X657159Y-299773D02*
Y-294773D01*
G01X661509Y-297523D02*
X664176D01*
X663926Y-296940D01*
X663509Y-296606D01*
X662926Y-296440D01*
X662342Y-296523D01*
X661842Y-296773D01*
X661509Y-297356D01*
X661342Y-297856D01*
Y-298356D01*
X661509Y-298856D01*
X661926Y-299356D01*
X662426Y-299690D01*
X663009Y-299773D01*
X663592Y-299606D01*
X664176Y-299106D01*
G01X669859Y-299773D02*
Y-296440D01*
G01Y-297023D02*
X669526Y-296690D01*
X669026Y-296523D01*
X668442Y-296440D01*
X667859Y-296606D01*
X667359Y-296940D01*
X667026Y-297440D01*
X666859Y-298106D01*
X667026Y-298773D01*
X667359Y-299273D01*
X667859Y-299606D01*
X668442Y-299773D01*
X669026Y-299690D01*
X669526Y-299440D01*
X669859Y-299106D01*
G01X672709Y-299190D02*
X673126Y-299523D01*
X673709Y-299773D01*
X674209D01*
X674709Y-299606D01*
X675042Y-299356D01*
X675209Y-299023D01*
X675126Y-298523D01*
X674792Y-298273D01*
X673292Y-297773D01*
X672959Y-297190D01*
X673126Y-296773D01*
X673459Y-296523D01*
X673959Y-296440D01*
X674459Y-296523D01*
X674959Y-296773D01*
G01X678309Y-297523D02*
X680976D01*
X680726Y-296940D01*
X680309Y-296606D01*
X679726Y-296440D01*
X679142Y-296523D01*
X678642Y-296773D01*
X678309Y-297356D01*
X678142Y-297856D01*
Y-298356D01*
X678309Y-298856D01*
X678726Y-299356D01*
X679226Y-299690D01*
X679809Y-299773D01*
X680392Y-299606D01*
X680976Y-299106D01*
G01X690759Y-296440D02*
Y-299773D01*
G01Y-295106D02*
X690592Y-295023D01*
Y-294856D01*
X690759Y-294773D01*
X690926Y-294856D01*
Y-295023D01*
X690759Y-295106D01*
G01X697859Y-301440D02*
Y-296440D01*
G01Y-297190D02*
X697442Y-296773D01*
X696942Y-296523D01*
X696359Y-296440D01*
X695859Y-296523D01*
X695276Y-296940D01*
X694942Y-297523D01*
X694859Y-298106D01*
X694942Y-298690D01*
X695276Y-299273D01*
X695859Y-299690D01*
X696359Y-299773D01*
X696942Y-299690D01*
X697442Y-299440D01*
X697859Y-299023D01*
G01X700542Y-299773D02*
Y-296440D01*
G01Y-297273D02*
X700876Y-296856D01*
X701376Y-296523D01*
X702042Y-296440D01*
X702626Y-296523D01*
X703126Y-296856D01*
X703376Y-297440D01*
Y-299773D01*
G01X707559D02*
X707059Y-299690D01*
X706559Y-299356D01*
X706226Y-298773D01*
X706059Y-298106D01*
X706226Y-297440D01*
X706559Y-296856D01*
X707059Y-296523D01*
X707559Y-296440D01*
X708059Y-296523D01*
X708559Y-296856D01*
X708892Y-297440D01*
X708976Y-298106D01*
X708892Y-298773D01*
X708559Y-299356D01*
X708059Y-299690D01*
X707559Y-299773D01*
G01X711992D02*
Y-296440D01*
G01Y-297106D02*
X712409Y-296773D01*
X712826Y-296523D01*
X713409Y-296440D01*
X713826Y-296523D01*
X714326Y-296773D01*
G01X717509Y-297523D02*
X720176D01*
X719926Y-296940D01*
X719509Y-296606D01*
X718926Y-296440D01*
X718342Y-296523D01*
X717842Y-296773D01*
X717509Y-297356D01*
X717342Y-297856D01*
Y-298356D01*
X717509Y-298856D01*
X717926Y-299356D01*
X718426Y-299690D01*
X719009Y-299773D01*
X719592Y-299606D01*
X720176Y-299106D01*
G01X729959Y-294773D02*
Y-299773D01*
G01X728792Y-296440D02*
X731126D01*
G01X734142Y-299773D02*
Y-294773D01*
G01Y-297190D02*
X734559Y-296773D01*
X734976Y-296523D01*
X735642Y-296440D01*
X736142Y-296523D01*
X736726Y-296856D01*
X736976Y-297356D01*
Y-299773D01*
G01X741159Y-296440D02*
Y-299773D01*
G01Y-295106D02*
X740992Y-295023D01*
Y-294856D01*
X741159Y-294773D01*
X741326Y-294856D01*
Y-295023D01*
X741159Y-295106D01*
G01X745509Y-299190D02*
X745926Y-299523D01*
X746509Y-299773D01*
X747009D01*
X747509Y-299606D01*
X747842Y-299356D01*
X748009Y-299023D01*
X747926Y-298523D01*
X747592Y-298273D01*
X746092Y-297773D01*
X745759Y-297190D01*
X745926Y-296773D01*
X746259Y-296523D01*
X746759Y-296440D01*
X747259Y-296523D01*
X747759Y-296773D01*
G01X756792Y-299773D02*
Y-296440D01*
G01Y-297106D02*
X757209Y-296773D01*
X757626Y-296523D01*
X758209Y-296440D01*
X758626Y-296523D01*
X759126Y-296773D01*
G01X762309Y-297523D02*
X764976D01*
X764726Y-296940D01*
X764309Y-296606D01*
X763726Y-296440D01*
X763142Y-296523D01*
X762642Y-296773D01*
X762309Y-297356D01*
X762142Y-297856D01*
Y-298356D01*
X762309Y-298856D01*
X762726Y-299356D01*
X763226Y-299690D01*
X763809Y-299773D01*
X764392Y-299606D01*
X764976Y-299106D01*
G01X770659Y-301440D02*
Y-296440D01*
G01Y-297190D02*
X770242Y-296773D01*
X769742Y-296523D01*
X769159Y-296440D01*
X768659Y-296523D01*
X768076Y-296940D01*
X767742Y-297523D01*
X767659Y-298106D01*
X767742Y-298690D01*
X768076Y-299273D01*
X768659Y-299690D01*
X769159Y-299773D01*
X769742Y-299690D01*
X770242Y-299440D01*
X770659Y-299023D01*
G01X773342Y-296440D02*
Y-298773D01*
X773676Y-299356D01*
X774176Y-299690D01*
X774759Y-299773D01*
X775342Y-299690D01*
X775842Y-299356D01*
X776176Y-298773D01*
G01Y-299773D02*
Y-296440D01*
G01X779109Y-297523D02*
X781776D01*
X781526Y-296940D01*
X781109Y-296606D01*
X780526Y-296440D01*
X779942Y-296523D01*
X779442Y-296773D01*
X779109Y-297356D01*
X778942Y-297856D01*
Y-298356D01*
X779109Y-298856D01*
X779526Y-299356D01*
X780026Y-299690D01*
X780609Y-299773D01*
X781192Y-299606D01*
X781776Y-299106D01*
G01X784709Y-299190D02*
X785126Y-299523D01*
X785709Y-299773D01*
X786209D01*
X786709Y-299606D01*
X787042Y-299356D01*
X787209Y-299023D01*
X787126Y-298523D01*
X786792Y-298273D01*
X785292Y-297773D01*
X784959Y-297190D01*
X785126Y-296773D01*
X785459Y-296523D01*
X785959Y-296440D01*
X786459Y-296523D01*
X786959Y-296773D01*
G01X791559Y-294773D02*
Y-299773D01*
G01X790392Y-296440D02*
X792726D01*
G01X797159Y-299940D02*
X796992Y-299856D01*
Y-299690D01*
X797159Y-299606D01*
X797326Y-299690D01*
Y-299856D01*
X797159Y-299940D01*
G01X343172Y-129003D02*
Y-134003D01*
X346506D01*
G01X349189Y-130670D02*
X351689Y-134003D01*
G01Y-130670D02*
X349189Y-134003D01*
G01X356039Y-134170D02*
X355872Y-134086D01*
Y-133920D01*
X356039Y-133836D01*
X356206Y-133920D01*
Y-134086D01*
X356039Y-134170D01*
G01Y-131920D02*
X355872Y-131836D01*
Y-131670D01*
X356039Y-131586D01*
X356206Y-131670D01*
Y-131836D01*
X356039Y-131920D01*
G01X364739Y-134003D02*
Y-130670D01*
G01Y-131586D02*
X364989Y-131170D01*
X365406Y-130836D01*
X365989Y-130670D01*
X366572Y-130836D01*
X366989Y-131170D01*
X367239Y-131586D01*
Y-134003D01*
G01Y-131586D02*
X367489Y-131170D01*
X367906Y-130836D01*
X368489Y-130670D01*
X369072Y-130836D01*
X369489Y-131170D01*
X369739Y-131670D01*
Y-134003D01*
G01X371422Y-130670D02*
Y-133003D01*
X371756Y-133586D01*
X372256Y-133920D01*
X372839Y-134003D01*
X373422Y-133920D01*
X373922Y-133586D01*
X374256Y-133003D01*
G01Y-134003D02*
Y-130670D01*
G01X377189Y-133420D02*
X377606Y-133753D01*
X378189Y-134003D01*
X378689D01*
X379189Y-133836D01*
X379522Y-133586D01*
X379689Y-133253D01*
X379606Y-132753D01*
X379272Y-132503D01*
X377772Y-132003D01*
X377439Y-131420D01*
X377606Y-131003D01*
X377939Y-130753D01*
X378439Y-130670D01*
X378939Y-130753D01*
X379439Y-131003D01*
G01X384039Y-129003D02*
Y-134003D01*
G01X382872Y-130670D02*
X385206D01*
G01X393739Y-134003D02*
Y-129003D01*
G01Y-131503D02*
X394156Y-131003D01*
X394656Y-130753D01*
X395156Y-130670D01*
X395906Y-130836D01*
X396406Y-131170D01*
X396739Y-131753D01*
Y-132420D01*
X396572Y-133086D01*
X396239Y-133586D01*
X395656Y-133920D01*
X395156Y-134003D01*
X394656Y-133920D01*
X394156Y-133670D01*
X393739Y-133253D01*
G01X399589Y-131753D02*
X402256D01*
X402006Y-131170D01*
X401589Y-130836D01*
X401006Y-130670D01*
X400422Y-130753D01*
X399922Y-131003D01*
X399589Y-131586D01*
X399422Y-132086D01*
Y-132586D01*
X399589Y-133086D01*
X400006Y-133586D01*
X400506Y-133920D01*
X401089Y-134003D01*
X401672Y-133836D01*
X402256Y-133336D01*
G01X410539Y-134003D02*
Y-129003D01*
G01Y-131503D02*
X410956Y-131003D01*
X411456Y-130753D01*
X411956Y-130670D01*
X412706Y-130836D01*
X413206Y-131170D01*
X413539Y-131753D01*
Y-132420D01*
X413372Y-133086D01*
X413039Y-133586D01*
X412456Y-133920D01*
X411956Y-134003D01*
X411456Y-133920D01*
X410956Y-133670D01*
X410539Y-133253D01*
G01X416472Y-134003D02*
Y-130670D01*
G01Y-131336D02*
X416889Y-131003D01*
X417306Y-130753D01*
X417889Y-130670D01*
X418306Y-130753D01*
X418806Y-131003D01*
G01X423239Y-134003D02*
X422739Y-133920D01*
X422239Y-133586D01*
X421906Y-133003D01*
X421739Y-132336D01*
X421906Y-131670D01*
X422239Y-131086D01*
X422739Y-130753D01*
X423239Y-130670D01*
X423739Y-130753D01*
X424239Y-131086D01*
X424572Y-131670D01*
X424656Y-132336D01*
X424572Y-133003D01*
X424239Y-133586D01*
X423739Y-133920D01*
X423239Y-134003D01*
G01X427422D02*
Y-129003D01*
G01X430089Y-130670D02*
X427422Y-132586D01*
G01X428506Y-131836D02*
X430256Y-134003D01*
G01X433189Y-131753D02*
X435856D01*
X435606Y-131170D01*
X435189Y-130836D01*
X434606Y-130670D01*
X434022Y-130753D01*
X433522Y-131003D01*
X433189Y-131586D01*
X433022Y-132086D01*
Y-132586D01*
X433189Y-133086D01*
X433606Y-133586D01*
X434106Y-133920D01*
X434689Y-134003D01*
X435272Y-133836D01*
X435856Y-133336D01*
G01X438622Y-134003D02*
Y-130670D01*
G01Y-131503D02*
X438956Y-131086D01*
X439456Y-130753D01*
X440122Y-130670D01*
X440706Y-130753D01*
X441206Y-131086D01*
X441456Y-131670D01*
Y-134003D01*
G01X451239D02*
Y-129003D01*
G01X458339Y-134003D02*
Y-130670D01*
G01Y-131253D02*
X458006Y-130920D01*
X457506Y-130753D01*
X456922Y-130670D01*
X456339Y-130836D01*
X455839Y-131170D01*
X455506Y-131670D01*
X455339Y-132336D01*
X455506Y-133003D01*
X455839Y-133503D01*
X456339Y-133836D01*
X456922Y-134003D01*
X457506Y-133920D01*
X458006Y-133670D01*
X458339Y-133336D01*
G01X460689Y-135503D02*
X461189Y-135670D01*
X461856Y-135503D01*
X462272Y-135170D01*
X462606Y-134753D01*
X463106Y-133420D01*
X464189Y-130670D01*
G01X461522D02*
X463106Y-133420D01*
G01X466789Y-131753D02*
X469456D01*
X469206Y-131170D01*
X468789Y-130836D01*
X468206Y-130670D01*
X467622Y-130753D01*
X467122Y-131003D01*
X466789Y-131586D01*
X466622Y-132086D01*
Y-132586D01*
X466789Y-133086D01*
X467206Y-133586D01*
X467706Y-133920D01*
X468289Y-134003D01*
X468872Y-133836D01*
X469456Y-133336D01*
G01X472472Y-134003D02*
Y-130670D01*
G01Y-131336D02*
X472889Y-131003D01*
X473306Y-130753D01*
X473889Y-130670D01*
X474306Y-130753D01*
X474806Y-131003D01*
G01X342572Y-117393D02*
Y-122393D01*
X345906D01*
G01X348422D02*
Y-119060D01*
G01Y-119893D02*
X348756Y-119476D01*
X349256Y-119143D01*
X349922Y-119060D01*
X350506Y-119143D01*
X351006Y-119476D01*
X351256Y-120060D01*
Y-122393D01*
G01X355439Y-122560D02*
X355272Y-122476D01*
Y-122310D01*
X355439Y-122226D01*
X355606Y-122310D01*
Y-122476D01*
X355439Y-122560D01*
G01Y-120310D02*
X355272Y-120226D01*
Y-120060D01*
X355439Y-119976D01*
X355606Y-120060D01*
Y-120226D01*
X355439Y-120310D01*
G01X367972Y-119476D02*
X367389Y-119143D01*
X366889Y-119060D01*
X366222Y-119226D01*
X365722Y-119560D01*
X365389Y-120143D01*
X365306Y-120726D01*
X365389Y-121310D01*
X365722Y-121810D01*
X366222Y-122226D01*
X366889Y-122393D01*
X367472Y-122226D01*
X367972Y-121893D01*
G01X373739Y-122393D02*
Y-119060D01*
G01Y-119643D02*
X373406Y-119310D01*
X372906Y-119143D01*
X372322Y-119060D01*
X371739Y-119226D01*
X371239Y-119560D01*
X370906Y-120060D01*
X370739Y-120726D01*
X370906Y-121393D01*
X371239Y-121893D01*
X371739Y-122226D01*
X372322Y-122393D01*
X372906Y-122310D01*
X373406Y-122060D01*
X373739Y-121726D01*
G01X376422Y-122393D02*
Y-119060D01*
G01Y-119893D02*
X376756Y-119476D01*
X377256Y-119143D01*
X377922Y-119060D01*
X378506Y-119143D01*
X379006Y-119476D01*
X379256Y-120060D01*
Y-122393D01*
G01X383439Y-119060D02*
X384272Y-118018D01*
Y-117393D01*
X383647D01*
Y-118018D01*
X384272D01*
G01X389039Y-117393D02*
Y-122393D01*
G01X387872Y-119060D02*
X390206D01*
G01X398739Y-122393D02*
Y-117393D01*
G01Y-119893D02*
X399156Y-119393D01*
X399656Y-119143D01*
X400156Y-119060D01*
X400906Y-119226D01*
X401406Y-119560D01*
X401739Y-120143D01*
Y-120810D01*
X401572Y-121476D01*
X401239Y-121976D01*
X400656Y-122310D01*
X400156Y-122393D01*
X399656Y-122310D01*
X399156Y-122060D01*
X398739Y-121643D01*
G01X404589Y-120143D02*
X407256D01*
X407006Y-119560D01*
X406589Y-119226D01*
X406006Y-119060D01*
X405422Y-119143D01*
X404922Y-119393D01*
X404589Y-119976D01*
X404422Y-120476D01*
Y-120976D01*
X404589Y-121476D01*
X405006Y-121976D01*
X405506Y-122310D01*
X406089Y-122393D01*
X406672Y-122226D01*
X407256Y-121726D01*
G01X415539Y-122393D02*
Y-117393D01*
G01Y-119893D02*
X415956Y-119393D01*
X416456Y-119143D01*
X416956Y-119060D01*
X417706Y-119226D01*
X418206Y-119560D01*
X418539Y-120143D01*
Y-120810D01*
X418372Y-121476D01*
X418039Y-121976D01*
X417456Y-122310D01*
X416956Y-122393D01*
X416456Y-122310D01*
X415956Y-122060D01*
X415539Y-121643D01*
G01X421472Y-122393D02*
Y-119060D01*
G01Y-119726D02*
X421889Y-119393D01*
X422306Y-119143D01*
X422889Y-119060D01*
X423306Y-119143D01*
X423806Y-119393D01*
G01X428239Y-122393D02*
X427739Y-122310D01*
X427239Y-121976D01*
X426906Y-121393D01*
X426739Y-120726D01*
X426906Y-120060D01*
X427239Y-119476D01*
X427739Y-119143D01*
X428239Y-119060D01*
X428739Y-119143D01*
X429239Y-119476D01*
X429572Y-120060D01*
X429656Y-120726D01*
X429572Y-121393D01*
X429239Y-121976D01*
X428739Y-122310D01*
X428239Y-122393D01*
G01X432422D02*
Y-117393D01*
G01X435089Y-119060D02*
X432422Y-120976D01*
G01X433506Y-120226D02*
X435256Y-122393D01*
G01X438189Y-120143D02*
X440856D01*
X440606Y-119560D01*
X440189Y-119226D01*
X439606Y-119060D01*
X439022Y-119143D01*
X438522Y-119393D01*
X438189Y-119976D01*
X438022Y-120476D01*
Y-120976D01*
X438189Y-121476D01*
X438606Y-121976D01*
X439106Y-122310D01*
X439689Y-122393D01*
X440272Y-122226D01*
X440856Y-121726D01*
G01X443622Y-122393D02*
Y-119060D01*
G01Y-119893D02*
X443956Y-119476D01*
X444456Y-119143D01*
X445122Y-119060D01*
X445706Y-119143D01*
X446206Y-119476D01*
X446456Y-120060D01*
Y-122393D01*
G01X456239D02*
Y-117393D01*
G01X463339Y-122393D02*
Y-119060D01*
G01Y-119643D02*
X463006Y-119310D01*
X462506Y-119143D01*
X461922Y-119060D01*
X461339Y-119226D01*
X460839Y-119560D01*
X460506Y-120060D01*
X460339Y-120726D01*
X460506Y-121393D01*
X460839Y-121893D01*
X461339Y-122226D01*
X461922Y-122393D01*
X462506Y-122310D01*
X463006Y-122060D01*
X463339Y-121726D01*
G01X465689Y-123893D02*
X466189Y-124060D01*
X466856Y-123893D01*
X467272Y-123560D01*
X467606Y-123143D01*
X468106Y-121810D01*
X469189Y-119060D01*
G01X466522D02*
X468106Y-121810D01*
G01X471789Y-120143D02*
X474456D01*
X474206Y-119560D01*
X473789Y-119226D01*
X473206Y-119060D01*
X472622Y-119143D01*
X472122Y-119393D01*
X471789Y-119976D01*
X471622Y-120476D01*
Y-120976D01*
X471789Y-121476D01*
X472206Y-121976D01*
X472706Y-122310D01*
X473289Y-122393D01*
X473872Y-122226D01*
X474456Y-121726D01*
G01X477472Y-122393D02*
Y-119060D01*
G01Y-119726D02*
X477889Y-119393D01*
X478306Y-119143D01*
X478889Y-119060D01*
X479306Y-119143D01*
X479806Y-119393D01*
G01X342756Y-110703D02*
Y-105703D01*
X344422D01*
X345089Y-105953D01*
X345589Y-106286D01*
X346006Y-106786D01*
X346339Y-107370D01*
X346422Y-108203D01*
X346339Y-109036D01*
X346006Y-109620D01*
X345589Y-110120D01*
X345089Y-110453D01*
X344422Y-110703D01*
X342756D01*
G01X349022D02*
Y-107370D01*
G01Y-108036D02*
X349439Y-107703D01*
X349856Y-107453D01*
X350439Y-107370D01*
X350856Y-107453D01*
X351356Y-107703D01*
G01X355789Y-107370D02*
Y-110703D01*
G01Y-106036D02*
X355622Y-105953D01*
Y-105786D01*
X355789Y-105703D01*
X355956Y-105786D01*
Y-105953D01*
X355789Y-106036D01*
G01X361389Y-110703D02*
Y-105703D01*
G01X366989Y-110703D02*
Y-105703D01*
G01X376606Y-110703D02*
Y-105703D01*
X379772D01*
G01X378606Y-108120D02*
X376606D01*
G01X382622Y-110703D02*
Y-107370D01*
G01Y-108036D02*
X383039Y-107703D01*
X383456Y-107453D01*
X384039Y-107370D01*
X384456Y-107453D01*
X384956Y-107703D01*
G01X389389Y-110703D02*
X388889Y-110620D01*
X388389Y-110286D01*
X388056Y-109703D01*
X387889Y-109036D01*
X388056Y-108370D01*
X388389Y-107786D01*
X388889Y-107453D01*
X389389Y-107370D01*
X389889Y-107453D01*
X390389Y-107786D01*
X390722Y-108370D01*
X390806Y-109036D01*
X390722Y-109703D01*
X390389Y-110286D01*
X389889Y-110620D01*
X389389Y-110703D01*
G01X392489D02*
Y-107370D01*
G01Y-108286D02*
X392739Y-107870D01*
X393156Y-107536D01*
X393739Y-107370D01*
X394322Y-107536D01*
X394739Y-107870D01*
X394989Y-108286D01*
Y-110703D01*
G01Y-108286D02*
X395239Y-107870D01*
X395656Y-107536D01*
X396239Y-107370D01*
X396822Y-107536D01*
X397239Y-107870D01*
X397489Y-108370D01*
Y-110703D01*
G01X404522Y-105703D02*
Y-110703D01*
X407856D01*
G01X411789D02*
Y-105703D01*
X410789Y-106703D01*
G01Y-110703D02*
X412789D01*
G01X422572Y-112370D02*
X421739Y-111536D01*
X421322Y-110703D01*
Y-107370D01*
X421739Y-106536D01*
X422572Y-105703D01*
G01X428589D02*
Y-110703D01*
G01X426672Y-105703D02*
X430506D01*
G01X434189Y-110703D02*
X433522Y-110620D01*
X432939Y-110286D01*
X432439Y-109786D01*
X432106Y-109203D01*
X431939Y-108536D01*
Y-107870D01*
X432106Y-107203D01*
X432439Y-106620D01*
X432939Y-106120D01*
X433522Y-105786D01*
X434189Y-105703D01*
X434856Y-105786D01*
X435439Y-106120D01*
X435939Y-106620D01*
X436272Y-107203D01*
X436439Y-107870D01*
Y-108536D01*
X436272Y-109203D01*
X435939Y-109786D01*
X435439Y-110286D01*
X434856Y-110620D01*
X434189Y-110703D01*
G01X438122D02*
Y-105703D01*
X440122D01*
X440789Y-105953D01*
X441289Y-106536D01*
X441456Y-107203D01*
X441289Y-107870D01*
X440872Y-108370D01*
X440122Y-108620D01*
X438122D01*
G01X445806Y-112370D02*
X446639Y-111536D01*
X447056Y-110703D01*
Y-107370D01*
X446639Y-106536D01*
X445806Y-105703D01*
G01X456589D02*
Y-110703D01*
G01X455422Y-107370D02*
X457756D01*
G01X462189Y-110703D02*
X461689Y-110620D01*
X461189Y-110286D01*
X460856Y-109703D01*
X460689Y-109036D01*
X460856Y-108370D01*
X461189Y-107786D01*
X461689Y-107453D01*
X462189Y-107370D01*
X462689Y-107453D01*
X463189Y-107786D01*
X463522Y-108370D01*
X463606Y-109036D01*
X463522Y-109703D01*
X463189Y-110286D01*
X462689Y-110620D01*
X462189Y-110703D01*
G01X471722Y-105703D02*
Y-110703D01*
X475056D01*
G01X477739Y-107370D02*
X480239Y-110703D01*
G01Y-107370D02*
X477739Y-110703D01*
G01X360089Y440797D02*
Y435797D01*
G01X358922Y439130D02*
X361256D01*
G01X364272Y435797D02*
Y440797D01*
G01Y438380D02*
X364689Y438797D01*
X365106Y439047D01*
X365772Y439130D01*
X366272Y439047D01*
X366856Y438714D01*
X367106Y438214D01*
Y435797D01*
G01X371289Y439130D02*
Y435797D01*
G01Y440464D02*
X371122Y440547D01*
Y440714D01*
X371289Y440797D01*
X371456Y440714D01*
Y440547D01*
X371289Y440464D01*
G01X378222Y438714D02*
X377639Y439047D01*
X377139Y439130D01*
X376472Y438964D01*
X375972Y438630D01*
X375639Y438047D01*
X375556Y437464D01*
X375639Y436880D01*
X375972Y436380D01*
X376472Y435964D01*
X377139Y435797D01*
X377722Y435964D01*
X378222Y436297D01*
G01X381072Y435797D02*
Y440797D01*
G01X383739Y439130D02*
X381072Y437214D01*
G01X382156Y437964D02*
X383906Y435797D01*
G01X386672D02*
Y439130D01*
G01Y438297D02*
X387006Y438714D01*
X387506Y439047D01*
X388172Y439130D01*
X388756Y439047D01*
X389256Y438714D01*
X389506Y438130D01*
Y435797D01*
G01X392439Y438047D02*
X395106D01*
X394856Y438630D01*
X394439Y438964D01*
X393856Y439130D01*
X393272Y439047D01*
X392772Y438797D01*
X392439Y438214D01*
X392272Y437714D01*
Y437214D01*
X392439Y436714D01*
X392856Y436214D01*
X393356Y435880D01*
X393939Y435797D01*
X394522Y435964D01*
X395106Y436464D01*
G01X398039Y436380D02*
X398456Y436047D01*
X399039Y435797D01*
X399539D01*
X400039Y435964D01*
X400372Y436214D01*
X400539Y436547D01*
X400456Y437047D01*
X400122Y437297D01*
X398622Y437797D01*
X398289Y438380D01*
X398456Y438797D01*
X398789Y439047D01*
X399289Y439130D01*
X399789Y439047D01*
X400289Y438797D01*
G01X403639Y436380D02*
X404056Y436047D01*
X404639Y435797D01*
X405139D01*
X405639Y435964D01*
X405972Y436214D01*
X406139Y436547D01*
X406056Y437047D01*
X405722Y437297D01*
X404222Y437797D01*
X403889Y438380D01*
X404056Y438797D01*
X404389Y439047D01*
X404889Y439130D01*
X405389Y439047D01*
X405889Y438797D01*
G01X364089Y561797D02*
Y556797D01*
G01X362172Y561797D02*
X366006D01*
G01X367606Y560130D02*
X368606Y556797D01*
X369689Y560130D01*
X370772Y556797D01*
X371772Y560130D01*
G01X375289D02*
Y556797D01*
G01Y561464D02*
X375122Y561547D01*
Y561714D01*
X375289Y561797D01*
X375456Y561714D01*
Y561547D01*
X375289Y561464D01*
G01X379639Y557380D02*
X380056Y557047D01*
X380639Y556797D01*
X381139D01*
X381639Y556964D01*
X381972Y557214D01*
X382139Y557547D01*
X382056Y558047D01*
X381722Y558297D01*
X380222Y558797D01*
X379889Y559380D01*
X380056Y559797D01*
X380389Y560047D01*
X380889Y560130D01*
X381389Y560047D01*
X381889Y559797D01*
G01X386489Y561797D02*
Y556797D01*
G01X385322Y560130D02*
X387656D01*
G01X399189Y556797D02*
Y560130D01*
G01Y559547D02*
X398856Y559880D01*
X398356Y560047D01*
X397772Y560130D01*
X397189Y559964D01*
X396689Y559630D01*
X396356Y559130D01*
X396189Y558464D01*
X396356Y557797D01*
X396689Y557297D01*
X397189Y556964D01*
X397772Y556797D01*
X398356Y556880D01*
X398856Y557130D01*
X399189Y557464D01*
G01X401872Y556797D02*
Y560130D01*
G01Y559297D02*
X402206Y559714D01*
X402706Y560047D01*
X403372Y560130D01*
X403956Y560047D01*
X404456Y559714D01*
X404706Y559130D01*
Y556797D01*
G01X410389Y561797D02*
Y556797D01*
G01Y557547D02*
X410056Y557130D01*
X409556Y556880D01*
X408972Y556797D01*
X408306Y556964D01*
X407806Y557380D01*
X407472Y557880D01*
X407389Y558464D01*
X407472Y559047D01*
X407806Y559547D01*
X408306Y559964D01*
X408972Y560130D01*
X409556Y560047D01*
X409972Y559880D01*
X410389Y559547D01*
G01X418589Y556797D02*
Y561797D01*
G01Y559297D02*
X419006Y559797D01*
X419506Y560047D01*
X420006Y560130D01*
X420756Y559964D01*
X421256Y559630D01*
X421589Y559047D01*
Y558380D01*
X421422Y557714D01*
X421089Y557214D01*
X420506Y556880D01*
X420006Y556797D01*
X419506Y556880D01*
X419006Y557130D01*
X418589Y557547D01*
G01X425689Y556797D02*
X425189Y556880D01*
X424689Y557214D01*
X424356Y557797D01*
X424189Y558464D01*
X424356Y559130D01*
X424689Y559714D01*
X425189Y560047D01*
X425689Y560130D01*
X426189Y560047D01*
X426689Y559714D01*
X427022Y559130D01*
X427106Y558464D01*
X427022Y557797D01*
X426689Y557214D01*
X426189Y556880D01*
X425689Y556797D01*
G01X429206Y560130D02*
X430206Y556797D01*
X431289Y560130D01*
X432372Y556797D01*
X433372Y560130D01*
G01X353589Y616907D02*
Y548407D01*
G01Y571797D02*
X908589D01*
G01X362422Y592797D02*
Y597797D01*
X364506D01*
X365172Y597547D01*
X365589Y597214D01*
X365756Y596547D01*
X365589Y595880D01*
X365089Y595464D01*
X364506Y595214D01*
X362422D01*
G01X364506D02*
X365756Y592797D01*
G01X369689D02*
X369189Y592880D01*
X368689Y593214D01*
X368356Y593797D01*
X368189Y594464D01*
X368356Y595130D01*
X368689Y595714D01*
X369189Y596047D01*
X369689Y596130D01*
X370189Y596047D01*
X370689Y595714D01*
X371022Y595130D01*
X371106Y594464D01*
X371022Y593797D01*
X370689Y593214D01*
X370189Y592880D01*
X369689Y592797D01*
G01X373872Y596130D02*
Y593797D01*
X374206Y593214D01*
X374706Y592880D01*
X375289Y592797D01*
X375872Y592880D01*
X376372Y593214D01*
X376706Y593797D01*
G01Y592797D02*
Y596130D01*
G01X380889Y597797D02*
Y592797D01*
G01X379722Y596130D02*
X382056D01*
G01X386489D02*
Y592797D01*
G01Y597464D02*
X386322Y597547D01*
Y597714D01*
X386489Y597797D01*
X386656Y597714D01*
Y597547D01*
X386489Y597464D01*
G01X390672Y592797D02*
Y596130D01*
G01Y595297D02*
X391006Y595714D01*
X391506Y596047D01*
X392172Y596130D01*
X392756Y596047D01*
X393256Y595714D01*
X393506Y595130D01*
Y592797D01*
G01X396522Y591547D02*
X397106Y591214D01*
X397772Y591130D01*
X398356Y591214D01*
X398856Y591630D01*
X399189Y592214D01*
Y596130D01*
G01Y595464D02*
X398856Y595797D01*
X398356Y596047D01*
X397772Y596130D01*
X397106Y595964D01*
X396689Y595630D01*
X396356Y595047D01*
X396189Y594464D01*
X396272Y593964D01*
X396606Y593380D01*
X397106Y592964D01*
X397772Y592797D01*
X398272Y592880D01*
X398856Y593214D01*
X399189Y593547D01*
G01X408889Y597797D02*
Y592797D01*
G01X407722Y596130D02*
X410056D01*
G01X414489Y592797D02*
X413989Y592880D01*
X413489Y593214D01*
X413156Y593797D01*
X412989Y594464D01*
X413156Y595130D01*
X413489Y595714D01*
X413989Y596047D01*
X414489Y596130D01*
X414989Y596047D01*
X415489Y595714D01*
X415822Y595130D01*
X415906Y594464D01*
X415822Y593797D01*
X415489Y593214D01*
X414989Y592880D01*
X414489Y592797D01*
G01X420089D02*
Y597797D01*
G01X424439Y595047D02*
X427106D01*
X426856Y595630D01*
X426439Y595964D01*
X425856Y596130D01*
X425272Y596047D01*
X424772Y595797D01*
X424439Y595214D01*
X424272Y594714D01*
Y594214D01*
X424439Y593714D01*
X424856Y593214D01*
X425356Y592880D01*
X425939Y592797D01*
X426522Y592964D01*
X427106Y593464D01*
G01X430122Y592797D02*
Y596130D01*
G01Y595464D02*
X430539Y595797D01*
X430956Y596047D01*
X431539Y596130D01*
X431956Y596047D01*
X432456Y595797D01*
G01X438389Y592797D02*
Y596130D01*
G01Y595547D02*
X438056Y595880D01*
X437556Y596047D01*
X436972Y596130D01*
X436389Y595964D01*
X435889Y595630D01*
X435556Y595130D01*
X435389Y594464D01*
X435556Y593797D01*
X435889Y593297D01*
X436389Y592964D01*
X436972Y592797D01*
X437556Y592880D01*
X438056Y593130D01*
X438389Y593464D01*
G01X441072Y592797D02*
Y596130D01*
G01Y595297D02*
X441406Y595714D01*
X441906Y596047D01*
X442572Y596130D01*
X443156Y596047D01*
X443656Y595714D01*
X443906Y595130D01*
Y592797D01*
G01X449422Y595714D02*
X448839Y596047D01*
X448339Y596130D01*
X447672Y595964D01*
X447172Y595630D01*
X446839Y595047D01*
X446756Y594464D01*
X446839Y593880D01*
X447172Y593380D01*
X447672Y592964D01*
X448339Y592797D01*
X448922Y592964D01*
X449422Y593297D01*
G01X452439Y595047D02*
X455106D01*
X454856Y595630D01*
X454439Y595964D01*
X453856Y596130D01*
X453272Y596047D01*
X452772Y595797D01*
X452439Y595214D01*
X452272Y594714D01*
Y594214D01*
X452439Y593714D01*
X452856Y593214D01*
X453356Y592880D01*
X453939Y592797D01*
X454522Y592964D01*
X455106Y593464D01*
G01X367756Y-249203D02*
Y-244203D01*
X369422D01*
X370089Y-244453D01*
X370589Y-244786D01*
X371006Y-245286D01*
X371339Y-245870D01*
X371422Y-246703D01*
X371339Y-247536D01*
X371006Y-248120D01*
X370589Y-248620D01*
X370089Y-248953D01*
X369422Y-249203D01*
X367756D01*
G01X375189D02*
Y-244203D01*
X374189Y-245203D01*
G01Y-249203D02*
X376189D01*
G01X379206Y-247120D02*
X379789Y-246536D01*
X380289Y-246203D01*
X380956Y-246036D01*
X381539Y-246203D01*
X381956Y-246536D01*
X382289Y-247036D01*
X382372Y-247620D01*
X382289Y-248120D01*
X381956Y-248620D01*
X381456Y-249036D01*
X380872Y-249203D01*
X380206Y-249036D01*
X379622Y-248536D01*
X379289Y-247786D01*
X379206Y-246953D01*
X379372Y-245870D01*
X379622Y-245286D01*
X380039Y-244703D01*
X380622Y-244286D01*
X381206Y-244203D01*
X381789Y-244370D01*
X382206Y-244786D01*
G01X387179Y142747D02*
Y146080D01*
G01Y145497D02*
X386846Y145830D01*
X386346Y145997D01*
X385762Y146080D01*
X385179Y145914D01*
X384679Y145580D01*
X384346Y145080D01*
X384179Y144414D01*
X384346Y143747D01*
X384679Y143247D01*
X385179Y142914D01*
X385762Y142747D01*
X386346Y142830D01*
X386846Y143080D01*
X387179Y143414D01*
G01X389862Y142747D02*
Y146080D01*
G01Y145247D02*
X390196Y145664D01*
X390696Y145997D01*
X391362Y146080D01*
X391946Y145997D01*
X392446Y145664D01*
X392696Y145080D01*
Y142747D01*
G01X398379Y147747D02*
Y142747D01*
G01Y143497D02*
X398046Y143080D01*
X397546Y142830D01*
X396962Y142747D01*
X396296Y142914D01*
X395796Y143330D01*
X395462Y143830D01*
X395379Y144414D01*
X395462Y144997D01*
X395796Y145497D01*
X396296Y145914D01*
X396962Y146080D01*
X397546Y145997D01*
X397962Y145830D01*
X398379Y145497D01*
G01X409412Y145664D02*
X408829Y145997D01*
X408329Y146080D01*
X407662Y145914D01*
X407162Y145580D01*
X406829Y144997D01*
X406746Y144414D01*
X406829Y143830D01*
X407162Y143330D01*
X407662Y142914D01*
X408329Y142747D01*
X408912Y142914D01*
X409412Y143247D01*
G01X413679Y142747D02*
X413179Y142830D01*
X412679Y143164D01*
X412346Y143747D01*
X412179Y144414D01*
X412346Y145080D01*
X412679Y145664D01*
X413179Y145997D01*
X413679Y146080D01*
X414179Y145997D01*
X414679Y145664D01*
X415012Y145080D01*
X415096Y144414D01*
X415012Y143747D01*
X414679Y143164D01*
X414179Y142830D01*
X413679Y142747D01*
G01X417779Y146080D02*
X419279Y142747D01*
X420779Y146080D01*
G01X423629Y144997D02*
X426296D01*
X426046Y145580D01*
X425629Y145914D01*
X425046Y146080D01*
X424462Y145997D01*
X423962Y145747D01*
X423629Y145164D01*
X423462Y144664D01*
Y144164D01*
X423629Y143664D01*
X424046Y143164D01*
X424546Y142830D01*
X425129Y142747D01*
X425712Y142914D01*
X426296Y143414D01*
G01X429312Y142747D02*
Y146080D01*
G01Y145414D02*
X429729Y145747D01*
X430146Y145997D01*
X430729Y146080D01*
X431146Y145997D01*
X431646Y145747D01*
G01X434829Y144997D02*
X437496D01*
X437246Y145580D01*
X436829Y145914D01*
X436246Y146080D01*
X435662Y145997D01*
X435162Y145747D01*
X434829Y145164D01*
X434662Y144664D01*
Y144164D01*
X434829Y143664D01*
X435246Y143164D01*
X435746Y142830D01*
X436329Y142747D01*
X436912Y142914D01*
X437496Y143414D01*
G01X443179Y147747D02*
Y142747D01*
G01Y143497D02*
X442846Y143080D01*
X442346Y142830D01*
X441762Y142747D01*
X441096Y142914D01*
X440596Y143330D01*
X440262Y143830D01*
X440179Y144414D01*
X440262Y144997D01*
X440596Y145497D01*
X441096Y145914D01*
X441762Y146080D01*
X442346Y145997D01*
X442762Y145830D01*
X443179Y145497D01*
G01X450796Y146080D02*
X451796Y142747D01*
X452879Y146080D01*
X453962Y142747D01*
X454962Y146080D01*
G01X458479D02*
Y142747D01*
G01Y147414D02*
X458312Y147497D01*
Y147664D01*
X458479Y147747D01*
X458646Y147664D01*
Y147497D01*
X458479Y147414D01*
G01X464079Y147747D02*
Y142747D01*
G01X462912Y146080D02*
X465246D01*
G01X468262Y142747D02*
Y147747D01*
G01Y145330D02*
X468679Y145747D01*
X469096Y145997D01*
X469762Y146080D01*
X470262Y145997D01*
X470846Y145664D01*
X471096Y145164D01*
Y142747D01*
G01X482212Y145664D02*
X481629Y145997D01*
X481129Y146080D01*
X480462Y145914D01*
X479962Y145580D01*
X479629Y144997D01*
X479546Y144414D01*
X479629Y143830D01*
X479962Y143330D01*
X480462Y142914D01*
X481129Y142747D01*
X481712Y142914D01*
X482212Y143247D01*
G01X486479Y142747D02*
X485979Y142830D01*
X485479Y143164D01*
X485146Y143747D01*
X484979Y144414D01*
X485146Y145080D01*
X485479Y145664D01*
X485979Y145997D01*
X486479Y146080D01*
X486979Y145997D01*
X487479Y145664D01*
X487812Y145080D01*
X487896Y144414D01*
X487812Y143747D01*
X487479Y143164D01*
X486979Y142830D01*
X486479Y142747D01*
G01X490579Y141080D02*
Y146080D01*
G01Y145330D02*
X490996Y145747D01*
X491412Y145997D01*
X492079Y146080D01*
X492662Y145997D01*
X493246Y145580D01*
X493496Y144997D01*
X493579Y144414D01*
X493496Y143830D01*
X493246Y143247D01*
X492746Y142914D01*
X492079Y142747D01*
X491496Y142830D01*
X490912Y143080D01*
X490579Y143414D01*
G01X496179Y141080D02*
Y146080D01*
G01Y145330D02*
X496596Y145747D01*
X497012Y145997D01*
X497679Y146080D01*
X498262Y145997D01*
X498846Y145580D01*
X499096Y144997D01*
X499179Y144414D01*
X499096Y143830D01*
X498846Y143247D01*
X498346Y142914D01*
X497679Y142747D01*
X497096Y142830D01*
X496512Y143080D01*
X496179Y143414D01*
G01X502029Y144997D02*
X504696D01*
X504446Y145580D01*
X504029Y145914D01*
X503446Y146080D01*
X502862Y145997D01*
X502362Y145747D01*
X502029Y145164D01*
X501862Y144664D01*
Y144164D01*
X502029Y143664D01*
X502446Y143164D01*
X502946Y142830D01*
X503529Y142747D01*
X504112Y142914D01*
X504696Y143414D01*
G01X507712Y142747D02*
Y146080D01*
G01Y145414D02*
X508129Y145747D01*
X508546Y145997D01*
X509129Y146080D01*
X509546Y145997D01*
X510046Y145747D01*
G01X377589Y370797D02*
Y132297D01*
G01X385179Y156107D02*
Y160357D01*
X385346Y160774D01*
X385679Y161024D01*
X386179Y161107D01*
X386679Y160940D01*
X386929Y160524D01*
G01X385929Y159107D02*
X384262D01*
G01X391279Y156107D02*
X390779Y156190D01*
X390279Y156524D01*
X389946Y157107D01*
X389779Y157774D01*
X389946Y158440D01*
X390279Y159024D01*
X390779Y159357D01*
X391279Y159440D01*
X391779Y159357D01*
X392279Y159024D01*
X392612Y158440D01*
X392696Y157774D01*
X392612Y157107D01*
X392279Y156524D01*
X391779Y156190D01*
X391279Y156107D01*
G01X396879D02*
Y161107D01*
G01X402479Y156107D02*
Y161107D01*
G01X408079Y156107D02*
X407579Y156190D01*
X407079Y156524D01*
X406746Y157107D01*
X406579Y157774D01*
X406746Y158440D01*
X407079Y159024D01*
X407579Y159357D01*
X408079Y159440D01*
X408579Y159357D01*
X409079Y159024D01*
X409412Y158440D01*
X409496Y157774D01*
X409412Y157107D01*
X409079Y156524D01*
X408579Y156190D01*
X408079Y156107D01*
G01X411596Y159440D02*
X412596Y156107D01*
X413679Y159440D01*
X414762Y156107D01*
X415762Y159440D01*
G01X425379Y158607D02*
X427046D01*
Y157107D01*
X426546Y156607D01*
X425962Y156274D01*
X425129Y156107D01*
X424296Y156274D01*
X423712Y156607D01*
X423212Y157107D01*
X422879Y157690D01*
X422712Y158357D01*
Y158940D01*
X422879Y159440D01*
X423212Y160024D01*
X423712Y160524D01*
X424212Y160857D01*
X424879Y161107D01*
X425462D01*
X426129Y160940D01*
X426629Y160607D01*
G01X429229Y158357D02*
X431896D01*
X431646Y158940D01*
X431229Y159274D01*
X430646Y159440D01*
X430062Y159357D01*
X429562Y159107D01*
X429229Y158524D01*
X429062Y158024D01*
Y157524D01*
X429229Y157024D01*
X429646Y156524D01*
X430146Y156190D01*
X430729Y156107D01*
X431312Y156274D01*
X431896Y156774D01*
G01X434912Y156107D02*
Y159440D01*
G01Y158774D02*
X435329Y159107D01*
X435746Y159357D01*
X436329Y159440D01*
X436746Y159357D01*
X437246Y159107D01*
G01X440179Y156107D02*
Y161107D01*
G01Y158607D02*
X440596Y159107D01*
X441096Y159357D01*
X441596Y159440D01*
X442346Y159274D01*
X442846Y158940D01*
X443179Y158357D01*
Y157690D01*
X443012Y157024D01*
X442679Y156524D01*
X442096Y156190D01*
X441596Y156107D01*
X441096Y156190D01*
X440596Y156440D01*
X440179Y156857D01*
G01X446029Y158357D02*
X448696D01*
X448446Y158940D01*
X448029Y159274D01*
X447446Y159440D01*
X446862Y159357D01*
X446362Y159107D01*
X446029Y158524D01*
X445862Y158024D01*
Y157524D01*
X446029Y157024D01*
X446446Y156524D01*
X446946Y156190D01*
X447529Y156107D01*
X448112Y156274D01*
X448696Y156774D01*
G01X451712Y156107D02*
Y159440D01*
G01Y158774D02*
X452129Y159107D01*
X452546Y159357D01*
X453129Y159440D01*
X453546Y159357D01*
X454046Y159107D01*
G01X465579Y156107D02*
Y159440D01*
G01Y158857D02*
X465246Y159190D01*
X464746Y159357D01*
X464162Y159440D01*
X463579Y159274D01*
X463079Y158940D01*
X462746Y158440D01*
X462579Y157774D01*
X462746Y157107D01*
X463079Y156607D01*
X463579Y156274D01*
X464162Y156107D01*
X464746Y156190D01*
X465246Y156440D01*
X465579Y156774D01*
G01X468262Y156107D02*
Y159440D01*
G01Y158607D02*
X468596Y159024D01*
X469096Y159357D01*
X469762Y159440D01*
X470346Y159357D01*
X470846Y159024D01*
X471096Y158440D01*
Y156107D01*
G01X476779Y161107D02*
Y156107D01*
G01Y156857D02*
X476446Y156440D01*
X475946Y156190D01*
X475362Y156107D01*
X474696Y156274D01*
X474196Y156690D01*
X473862Y157190D01*
X473779Y157774D01*
X473862Y158357D01*
X474196Y158857D01*
X474696Y159274D01*
X475362Y159440D01*
X475946Y159357D01*
X476362Y159190D01*
X476779Y158857D01*
G01X484979Y154440D02*
Y159440D01*
G01Y158690D02*
X485396Y159107D01*
X485812Y159357D01*
X486479Y159440D01*
X487062Y159357D01*
X487646Y158940D01*
X487896Y158357D01*
X487979Y157774D01*
X487896Y157190D01*
X487646Y156607D01*
X487146Y156274D01*
X486479Y156107D01*
X485896Y156190D01*
X485312Y156440D01*
X484979Y156774D01*
G01X492079Y156107D02*
Y161107D01*
G01X496262Y159440D02*
Y157107D01*
X496596Y156524D01*
X497096Y156190D01*
X497679Y156107D01*
X498262Y156190D01*
X498762Y156524D01*
X499096Y157107D01*
G01Y156107D02*
Y159440D01*
G01X502112Y154857D02*
X502696Y154524D01*
X503362Y154440D01*
X503946Y154524D01*
X504446Y154940D01*
X504779Y155524D01*
Y159440D01*
G01Y158774D02*
X504446Y159107D01*
X503946Y159357D01*
X503362Y159440D01*
X502696Y159274D01*
X502279Y158940D01*
X501946Y158357D01*
X501779Y157774D01*
X501862Y157274D01*
X502196Y156690D01*
X502696Y156274D01*
X503362Y156107D01*
X503862Y156190D01*
X504446Y156524D01*
X504779Y156857D01*
G01X512396Y159440D02*
X513396Y156107D01*
X514479Y159440D01*
X515562Y156107D01*
X516562Y159440D01*
G01X520079D02*
Y156107D01*
G01Y160774D02*
X519912Y160857D01*
Y161024D01*
X520079Y161107D01*
X520246Y161024D01*
Y160857D01*
X520079Y160774D01*
G01X525679Y161107D02*
Y156107D01*
G01X524512Y159440D02*
X526846D01*
G01X529862Y156107D02*
Y161107D01*
G01Y158690D02*
X530279Y159107D01*
X530696Y159357D01*
X531362Y159440D01*
X531862Y159357D01*
X532446Y159024D01*
X532696Y158524D01*
Y156107D01*
G01X541312D02*
Y159440D01*
G01Y158774D02*
X541729Y159107D01*
X542146Y159357D01*
X542729Y159440D01*
X543146Y159357D01*
X543646Y159107D01*
G01X546829Y158357D02*
X549496D01*
X549246Y158940D01*
X548829Y159274D01*
X548246Y159440D01*
X547662Y159357D01*
X547162Y159107D01*
X546829Y158524D01*
X546662Y158024D01*
Y157524D01*
X546829Y157024D01*
X547246Y156524D01*
X547746Y156190D01*
X548329Y156107D01*
X548912Y156274D01*
X549496Y156774D01*
G01X552429Y156690D02*
X552846Y156357D01*
X553429Y156107D01*
X553929D01*
X554429Y156274D01*
X554762Y156524D01*
X554929Y156857D01*
X554846Y157357D01*
X554512Y157607D01*
X553012Y158107D01*
X552679Y158690D01*
X552846Y159107D01*
X553179Y159357D01*
X553679Y159440D01*
X554179Y159357D01*
X554679Y159107D01*
G01X559279Y159440D02*
Y156107D01*
G01Y160774D02*
X559112Y160857D01*
Y161024D01*
X559279Y161107D01*
X559446Y161024D01*
Y160857D01*
X559279Y160774D01*
G01X563462Y156107D02*
Y159440D01*
G01Y158607D02*
X563796Y159024D01*
X564296Y159357D01*
X564962Y159440D01*
X565546Y159357D01*
X566046Y159024D01*
X566296Y158440D01*
Y156107D01*
G01X387089Y185797D02*
Y190047D01*
X387256Y190464D01*
X387589Y190714D01*
X388089Y190797D01*
X388589Y190630D01*
X388839Y190214D01*
G01X387839Y188797D02*
X386172D01*
G01X393189Y185797D02*
X392689Y185880D01*
X392189Y186214D01*
X391856Y186797D01*
X391689Y187464D01*
X391856Y188130D01*
X392189Y188714D01*
X392689Y189047D01*
X393189Y189130D01*
X393689Y189047D01*
X394189Y188714D01*
X394522Y188130D01*
X394606Y187464D01*
X394522Y186797D01*
X394189Y186214D01*
X393689Y185880D01*
X393189Y185797D01*
G01X398789D02*
Y190797D01*
G01X404389Y185797D02*
Y190797D01*
G01X409989Y185797D02*
X409489Y185880D01*
X408989Y186214D01*
X408656Y186797D01*
X408489Y187464D01*
X408656Y188130D01*
X408989Y188714D01*
X409489Y189047D01*
X409989Y189130D01*
X410489Y189047D01*
X410989Y188714D01*
X411322Y188130D01*
X411406Y187464D01*
X411322Y186797D01*
X410989Y186214D01*
X410489Y185880D01*
X409989Y185797D01*
G01X413506Y189130D02*
X414506Y185797D01*
X415589Y189130D01*
X416672Y185797D01*
X417672Y189130D01*
G01X427289Y188297D02*
X428956D01*
Y186797D01*
X428456Y186297D01*
X427872Y185964D01*
X427039Y185797D01*
X426206Y185964D01*
X425622Y186297D01*
X425122Y186797D01*
X424789Y187380D01*
X424622Y188047D01*
Y188630D01*
X424789Y189130D01*
X425122Y189714D01*
X425622Y190214D01*
X426122Y190547D01*
X426789Y190797D01*
X427372D01*
X428039Y190630D01*
X428539Y190297D01*
G01X431139Y188047D02*
X433806D01*
X433556Y188630D01*
X433139Y188964D01*
X432556Y189130D01*
X431972Y189047D01*
X431472Y188797D01*
X431139Y188214D01*
X430972Y187714D01*
Y187214D01*
X431139Y186714D01*
X431556Y186214D01*
X432056Y185880D01*
X432639Y185797D01*
X433222Y185964D01*
X433806Y186464D01*
G01X436822Y185797D02*
Y189130D01*
G01Y188464D02*
X437239Y188797D01*
X437656Y189047D01*
X438239Y189130D01*
X438656Y189047D01*
X439156Y188797D01*
G01X442089Y185797D02*
Y190797D01*
G01Y188297D02*
X442506Y188797D01*
X443006Y189047D01*
X443506Y189130D01*
X444256Y188964D01*
X444756Y188630D01*
X445089Y188047D01*
Y187380D01*
X444922Y186714D01*
X444589Y186214D01*
X444006Y185880D01*
X443506Y185797D01*
X443006Y185880D01*
X442506Y186130D01*
X442089Y186547D01*
G01X447939Y188047D02*
X450606D01*
X450356Y188630D01*
X449939Y188964D01*
X449356Y189130D01*
X448772Y189047D01*
X448272Y188797D01*
X447939Y188214D01*
X447772Y187714D01*
Y187214D01*
X447939Y186714D01*
X448356Y186214D01*
X448856Y185880D01*
X449439Y185797D01*
X450022Y185964D01*
X450606Y186464D01*
G01X453622Y185797D02*
Y189130D01*
G01Y188464D02*
X454039Y188797D01*
X454456Y189047D01*
X455039Y189130D01*
X455456Y189047D01*
X455956Y188797D01*
G01X467489Y185797D02*
Y189130D01*
G01Y188547D02*
X467156Y188880D01*
X466656Y189047D01*
X466072Y189130D01*
X465489Y188964D01*
X464989Y188630D01*
X464656Y188130D01*
X464489Y187464D01*
X464656Y186797D01*
X464989Y186297D01*
X465489Y185964D01*
X466072Y185797D01*
X466656Y185880D01*
X467156Y186130D01*
X467489Y186464D01*
G01X470172Y185797D02*
Y189130D01*
G01Y188297D02*
X470506Y188714D01*
X471006Y189047D01*
X471672Y189130D01*
X472256Y189047D01*
X472756Y188714D01*
X473006Y188130D01*
Y185797D01*
G01X478689Y190797D02*
Y185797D01*
G01Y186547D02*
X478356Y186130D01*
X477856Y185880D01*
X477272Y185797D01*
X476606Y185964D01*
X476106Y186380D01*
X475772Y186880D01*
X475689Y187464D01*
X475772Y188047D01*
X476106Y188547D01*
X476606Y188964D01*
X477272Y189130D01*
X477856Y189047D01*
X478272Y188880D01*
X478689Y188547D01*
G01X486889Y184130D02*
Y189130D01*
G01Y188380D02*
X487306Y188797D01*
X487722Y189047D01*
X488389Y189130D01*
X488972Y189047D01*
X489556Y188630D01*
X489806Y188047D01*
X489889Y187464D01*
X489806Y186880D01*
X489556Y186297D01*
X489056Y185964D01*
X488389Y185797D01*
X487806Y185880D01*
X487222Y186130D01*
X486889Y186464D01*
G01X493989Y185797D02*
Y190797D01*
G01X498172Y189130D02*
Y186797D01*
X498506Y186214D01*
X499006Y185880D01*
X499589Y185797D01*
X500172Y185880D01*
X500672Y186214D01*
X501006Y186797D01*
G01Y185797D02*
Y189130D01*
G01X504022Y184547D02*
X504606Y184214D01*
X505272Y184130D01*
X505856Y184214D01*
X506356Y184630D01*
X506689Y185214D01*
Y189130D01*
G01Y188464D02*
X506356Y188797D01*
X505856Y189047D01*
X505272Y189130D01*
X504606Y188964D01*
X504189Y188630D01*
X503856Y188047D01*
X503689Y187464D01*
X503772Y186964D01*
X504106Y186380D01*
X504606Y185964D01*
X505272Y185797D01*
X505772Y185880D01*
X506356Y186214D01*
X506689Y186547D01*
G01X514306Y189130D02*
X515306Y185797D01*
X516389Y189130D01*
X517472Y185797D01*
X518472Y189130D01*
G01X521989D02*
Y185797D01*
G01Y190464D02*
X521822Y190547D01*
Y190714D01*
X521989Y190797D01*
X522156Y190714D01*
Y190547D01*
X521989Y190464D01*
G01X527589Y190797D02*
Y185797D01*
G01X526422Y189130D02*
X528756D01*
G01X531772Y185797D02*
Y190797D01*
G01Y188380D02*
X532189Y188797D01*
X532606Y189047D01*
X533272Y189130D01*
X533772Y189047D01*
X534356Y188714D01*
X534606Y188214D01*
Y185797D01*
G01X543222D02*
Y189130D01*
G01Y188464D02*
X543639Y188797D01*
X544056Y189047D01*
X544639Y189130D01*
X545056Y189047D01*
X545556Y188797D01*
G01X548739Y188047D02*
X551406D01*
X551156Y188630D01*
X550739Y188964D01*
X550156Y189130D01*
X549572Y189047D01*
X549072Y188797D01*
X548739Y188214D01*
X548572Y187714D01*
Y187214D01*
X548739Y186714D01*
X549156Y186214D01*
X549656Y185880D01*
X550239Y185797D01*
X550822Y185964D01*
X551406Y186464D01*
G01X554339Y186380D02*
X554756Y186047D01*
X555339Y185797D01*
X555839D01*
X556339Y185964D01*
X556672Y186214D01*
X556839Y186547D01*
X556756Y187047D01*
X556422Y187297D01*
X554922Y187797D01*
X554589Y188380D01*
X554756Y188797D01*
X555089Y189047D01*
X555589Y189130D01*
X556089Y189047D01*
X556589Y188797D01*
G01X561189Y189130D02*
Y185797D01*
G01Y190464D02*
X561022Y190547D01*
Y190714D01*
X561189Y190797D01*
X561356Y190714D01*
Y190547D01*
X561189Y190464D01*
G01X565372Y185797D02*
Y189130D01*
G01Y188297D02*
X565706Y188714D01*
X566206Y189047D01*
X566872Y189130D01*
X567456Y189047D01*
X567956Y188714D01*
X568206Y188130D01*
Y185797D01*
G01X387089Y206797D02*
Y211047D01*
X387256Y211464D01*
X387589Y211714D01*
X388089Y211797D01*
X388589Y211630D01*
X388839Y211214D01*
G01X387839Y209797D02*
X386172D01*
G01X393189Y206797D02*
X392689Y206880D01*
X392189Y207214D01*
X391856Y207797D01*
X391689Y208464D01*
X391856Y209130D01*
X392189Y209714D01*
X392689Y210047D01*
X393189Y210130D01*
X393689Y210047D01*
X394189Y209714D01*
X394522Y209130D01*
X394606Y208464D01*
X394522Y207797D01*
X394189Y207214D01*
X393689Y206880D01*
X393189Y206797D01*
G01X398789D02*
Y211797D01*
G01X404389Y206797D02*
Y211797D01*
G01X409989Y206797D02*
X409489Y206880D01*
X408989Y207214D01*
X408656Y207797D01*
X408489Y208464D01*
X408656Y209130D01*
X408989Y209714D01*
X409489Y210047D01*
X409989Y210130D01*
X410489Y210047D01*
X410989Y209714D01*
X411322Y209130D01*
X411406Y208464D01*
X411322Y207797D01*
X410989Y207214D01*
X410489Y206880D01*
X409989Y206797D01*
G01X413506Y210130D02*
X414506Y206797D01*
X415589Y210130D01*
X416672Y206797D01*
X417672Y210130D01*
G01X427289Y209297D02*
X428956D01*
Y207797D01*
X428456Y207297D01*
X427872Y206964D01*
X427039Y206797D01*
X426206Y206964D01*
X425622Y207297D01*
X425122Y207797D01*
X424789Y208380D01*
X424622Y209047D01*
Y209630D01*
X424789Y210130D01*
X425122Y210714D01*
X425622Y211214D01*
X426122Y211547D01*
X426789Y211797D01*
X427372D01*
X428039Y211630D01*
X428539Y211297D01*
G01X431139Y209047D02*
X433806D01*
X433556Y209630D01*
X433139Y209964D01*
X432556Y210130D01*
X431972Y210047D01*
X431472Y209797D01*
X431139Y209214D01*
X430972Y208714D01*
Y208214D01*
X431139Y207714D01*
X431556Y207214D01*
X432056Y206880D01*
X432639Y206797D01*
X433222Y206964D01*
X433806Y207464D01*
G01X436822Y206797D02*
Y210130D01*
G01Y209464D02*
X437239Y209797D01*
X437656Y210047D01*
X438239Y210130D01*
X438656Y210047D01*
X439156Y209797D01*
G01X442089Y206797D02*
Y211797D01*
G01Y209297D02*
X442506Y209797D01*
X443006Y210047D01*
X443506Y210130D01*
X444256Y209964D01*
X444756Y209630D01*
X445089Y209047D01*
Y208380D01*
X444922Y207714D01*
X444589Y207214D01*
X444006Y206880D01*
X443506Y206797D01*
X443006Y206880D01*
X442506Y207130D01*
X442089Y207547D01*
G01X447939Y209047D02*
X450606D01*
X450356Y209630D01*
X449939Y209964D01*
X449356Y210130D01*
X448772Y210047D01*
X448272Y209797D01*
X447939Y209214D01*
X447772Y208714D01*
Y208214D01*
X447939Y207714D01*
X448356Y207214D01*
X448856Y206880D01*
X449439Y206797D01*
X450022Y206964D01*
X450606Y207464D01*
G01X453622Y206797D02*
Y210130D01*
G01Y209464D02*
X454039Y209797D01*
X454456Y210047D01*
X455039Y210130D01*
X455456Y210047D01*
X455956Y209797D01*
G01X389089Y221797D02*
Y225130D01*
G01Y224547D02*
X388756Y224880D01*
X388256Y225047D01*
X387672Y225130D01*
X387089Y224964D01*
X386589Y224630D01*
X386256Y224130D01*
X386089Y223464D01*
X386256Y222797D01*
X386589Y222297D01*
X387089Y221964D01*
X387672Y221797D01*
X388256Y221880D01*
X388756Y222130D01*
X389089Y222464D01*
G01X391772Y221797D02*
Y225130D01*
G01Y224297D02*
X392106Y224714D01*
X392606Y225047D01*
X393272Y225130D01*
X393856Y225047D01*
X394356Y224714D01*
X394606Y224130D01*
Y221797D01*
G01X400289Y226797D02*
Y221797D01*
G01Y222547D02*
X399956Y222130D01*
X399456Y221880D01*
X398872Y221797D01*
X398206Y221964D01*
X397706Y222380D01*
X397372Y222880D01*
X397289Y223464D01*
X397372Y224047D01*
X397706Y224547D01*
X398206Y224964D01*
X398872Y225130D01*
X399456Y225047D01*
X399872Y224880D01*
X400289Y224547D01*
G01X408489Y221797D02*
Y226797D01*
G01Y224297D02*
X408906Y224797D01*
X409406Y225047D01*
X409906Y225130D01*
X410656Y224964D01*
X411156Y224630D01*
X411489Y224047D01*
Y223380D01*
X411322Y222714D01*
X410989Y222214D01*
X410406Y221880D01*
X409906Y221797D01*
X409406Y221880D01*
X408906Y222130D01*
X408489Y222547D01*
G01X415589Y221797D02*
X415089Y221880D01*
X414589Y222214D01*
X414256Y222797D01*
X414089Y223464D01*
X414256Y224130D01*
X414589Y224714D01*
X415089Y225047D01*
X415589Y225130D01*
X416089Y225047D01*
X416589Y224714D01*
X416922Y224130D01*
X417006Y223464D01*
X416922Y222797D01*
X416589Y222214D01*
X416089Y221880D01*
X415589Y221797D01*
G01X421189Y226797D02*
Y221797D01*
G01X420022Y225130D02*
X422356D01*
G01X426789Y226797D02*
Y221797D01*
G01X425622Y225130D02*
X427956D01*
G01X432389Y221797D02*
X431889Y221880D01*
X431389Y222214D01*
X431056Y222797D01*
X430889Y223464D01*
X431056Y224130D01*
X431389Y224714D01*
X431889Y225047D01*
X432389Y225130D01*
X432889Y225047D01*
X433389Y224714D01*
X433722Y224130D01*
X433806Y223464D01*
X433722Y222797D01*
X433389Y222214D01*
X432889Y221880D01*
X432389Y221797D01*
G01X435489D02*
Y225130D01*
G01Y224214D02*
X435739Y224630D01*
X436156Y224964D01*
X436739Y225130D01*
X437322Y224964D01*
X437739Y224630D01*
X437989Y224214D01*
Y221797D01*
G01Y224214D02*
X438239Y224630D01*
X438656Y224964D01*
X439239Y225130D01*
X439822Y224964D01*
X440239Y224630D01*
X440489Y224130D01*
Y221797D01*
G01X447939Y222380D02*
X448356Y222047D01*
X448939Y221797D01*
X449439D01*
X449939Y221964D01*
X450272Y222214D01*
X450439Y222547D01*
X450356Y223047D01*
X450022Y223297D01*
X448522Y223797D01*
X448189Y224380D01*
X448356Y224797D01*
X448689Y225047D01*
X449189Y225130D01*
X449689Y225047D01*
X450189Y224797D01*
G01X454789Y225130D02*
Y221797D01*
G01Y226464D02*
X454622Y226547D01*
Y226714D01*
X454789Y226797D01*
X454956Y226714D01*
Y226547D01*
X454789Y226464D01*
G01X461889Y226797D02*
Y221797D01*
G01Y222547D02*
X461556Y222130D01*
X461056Y221880D01*
X460472Y221797D01*
X459806Y221964D01*
X459306Y222380D01*
X458972Y222880D01*
X458889Y223464D01*
X458972Y224047D01*
X459306Y224547D01*
X459806Y224964D01*
X460472Y225130D01*
X461056Y225047D01*
X461472Y224880D01*
X461889Y224547D01*
G01X464739Y224047D02*
X467406D01*
X467156Y224630D01*
X466739Y224964D01*
X466156Y225130D01*
X465572Y225047D01*
X465072Y224797D01*
X464739Y224214D01*
X464572Y223714D01*
Y223214D01*
X464739Y222714D01*
X465156Y222214D01*
X465656Y221880D01*
X466239Y221797D01*
X466822Y221964D01*
X467406Y222464D01*
G01X385506Y237130D02*
X386506Y233797D01*
X387589Y237130D01*
X388672Y233797D01*
X389672Y237130D01*
G01X393189D02*
Y233797D01*
G01Y238464D02*
X393022Y238547D01*
Y238714D01*
X393189Y238797D01*
X393356Y238714D01*
Y238547D01*
X393189Y238464D01*
G01X398789Y238797D02*
Y233797D01*
G01X397622Y237130D02*
X399956D01*
G01X402972Y233797D02*
Y238797D01*
G01Y236380D02*
X403389Y236797D01*
X403806Y237047D01*
X404472Y237130D01*
X404972Y237047D01*
X405556Y236714D01*
X405806Y236214D01*
Y233797D01*
G01X409989D02*
X409489Y233880D01*
X408989Y234214D01*
X408656Y234797D01*
X408489Y235464D01*
X408656Y236130D01*
X408989Y236714D01*
X409489Y237047D01*
X409989Y237130D01*
X410489Y237047D01*
X410989Y236714D01*
X411322Y236130D01*
X411406Y235464D01*
X411322Y234797D01*
X410989Y234214D01*
X410489Y233880D01*
X409989Y233797D01*
G01X414172Y237130D02*
Y234797D01*
X414506Y234214D01*
X415006Y233880D01*
X415589Y233797D01*
X416172Y233880D01*
X416672Y234214D01*
X417006Y234797D01*
G01Y233797D02*
Y237130D01*
G01X421189Y238797D02*
Y233797D01*
G01X420022Y237130D02*
X422356D01*
G01X431139Y234380D02*
X431556Y234047D01*
X432139Y233797D01*
X432639D01*
X433139Y233964D01*
X433472Y234214D01*
X433639Y234547D01*
X433556Y235047D01*
X433222Y235297D01*
X431722Y235797D01*
X431389Y236380D01*
X431556Y236797D01*
X431889Y237047D01*
X432389Y237130D01*
X432889Y237047D01*
X433389Y236797D01*
G01X437989Y233797D02*
X437489Y233880D01*
X436989Y234214D01*
X436656Y234797D01*
X436489Y235464D01*
X436656Y236130D01*
X436989Y236714D01*
X437489Y237047D01*
X437989Y237130D01*
X438489Y237047D01*
X438989Y236714D01*
X439322Y236130D01*
X439406Y235464D01*
X439322Y234797D01*
X438989Y234214D01*
X438489Y233880D01*
X437989Y233797D01*
G01X443589D02*
Y238797D01*
G01X450689D02*
Y233797D01*
G01Y234547D02*
X450356Y234130D01*
X449856Y233880D01*
X449272Y233797D01*
X448606Y233964D01*
X448106Y234380D01*
X447772Y234880D01*
X447689Y235464D01*
X447772Y236047D01*
X448106Y236547D01*
X448606Y236964D01*
X449272Y237130D01*
X449856Y237047D01*
X450272Y236880D01*
X450689Y236547D01*
G01X453539Y236047D02*
X456206D01*
X455956Y236630D01*
X455539Y236964D01*
X454956Y237130D01*
X454372Y237047D01*
X453872Y236797D01*
X453539Y236214D01*
X453372Y235714D01*
Y235214D01*
X453539Y234714D01*
X453956Y234214D01*
X454456Y233880D01*
X455039Y233797D01*
X455622Y233964D01*
X456206Y234464D01*
G01X459222Y233797D02*
Y237130D01*
G01Y236464D02*
X459639Y236797D01*
X460056Y237047D01*
X460639Y237130D01*
X461056Y237047D01*
X461556Y236797D01*
G01X469089Y233797D02*
Y237130D01*
G01Y236214D02*
X469339Y236630D01*
X469756Y236964D01*
X470339Y237130D01*
X470922Y236964D01*
X471339Y236630D01*
X471589Y236214D01*
Y233797D01*
G01Y236214D02*
X471839Y236630D01*
X472256Y236964D01*
X472839Y237130D01*
X473422Y236964D01*
X473839Y236630D01*
X474089Y236130D01*
Y233797D01*
G01X478689D02*
Y237130D01*
G01Y236547D02*
X478356Y236880D01*
X477856Y237047D01*
X477272Y237130D01*
X476689Y236964D01*
X476189Y236630D01*
X475856Y236130D01*
X475689Y235464D01*
X475856Y234797D01*
X476189Y234297D01*
X476689Y233964D01*
X477272Y233797D01*
X477856Y233880D01*
X478356Y234130D01*
X478689Y234464D01*
G01X481539Y234380D02*
X481956Y234047D01*
X482539Y233797D01*
X483039D01*
X483539Y233964D01*
X483872Y234214D01*
X484039Y234547D01*
X483956Y235047D01*
X483622Y235297D01*
X482122Y235797D01*
X481789Y236380D01*
X481956Y236797D01*
X482289Y237047D01*
X482789Y237130D01*
X483289Y237047D01*
X483789Y236797D01*
G01X486972Y233797D02*
Y238797D01*
G01X489639Y237130D02*
X486972Y235214D01*
G01X488056Y235964D02*
X489806Y233797D01*
G01X498089Y232130D02*
Y237130D01*
G01Y236380D02*
X498506Y236797D01*
X498922Y237047D01*
X499589Y237130D01*
X500172Y237047D01*
X500756Y236630D01*
X501006Y236047D01*
X501089Y235464D01*
X501006Y234880D01*
X500756Y234297D01*
X500256Y233964D01*
X499589Y233797D01*
X499006Y233880D01*
X498422Y234130D01*
X498089Y234464D01*
G01X506689Y233797D02*
Y237130D01*
G01Y236547D02*
X506356Y236880D01*
X505856Y237047D01*
X505272Y237130D01*
X504689Y236964D01*
X504189Y236630D01*
X503856Y236130D01*
X503689Y235464D01*
X503856Y234797D01*
X504189Y234297D01*
X504689Y233964D01*
X505272Y233797D01*
X505856Y233880D01*
X506356Y234130D01*
X506689Y234464D01*
G01X512289Y238797D02*
Y233797D01*
G01Y234547D02*
X511956Y234130D01*
X511456Y233880D01*
X510872Y233797D01*
X510206Y233964D01*
X509706Y234380D01*
X509372Y234880D01*
X509289Y235464D01*
X509372Y236047D01*
X509706Y236547D01*
X510206Y236964D01*
X510872Y237130D01*
X511456Y237047D01*
X511872Y236880D01*
X512289Y236547D01*
G01X521989Y233797D02*
X521489Y233880D01*
X520989Y234214D01*
X520656Y234797D01*
X520489Y235464D01*
X520656Y236130D01*
X520989Y236714D01*
X521489Y237047D01*
X521989Y237130D01*
X522489Y237047D01*
X522989Y236714D01*
X523322Y236130D01*
X523406Y235464D01*
X523322Y234797D01*
X522989Y234214D01*
X522489Y233880D01*
X521989Y233797D01*
G01X526172D02*
Y237130D01*
G01Y236297D02*
X526506Y236714D01*
X527006Y237047D01*
X527672Y237130D01*
X528256Y237047D01*
X528756Y236714D01*
X529006Y236130D01*
Y233797D01*
G01X538789Y238797D02*
Y233797D01*
G01X537622Y237130D02*
X539956D01*
G01X544389Y233797D02*
X543889Y233880D01*
X543389Y234214D01*
X543056Y234797D01*
X542889Y235464D01*
X543056Y236130D01*
X543389Y236714D01*
X543889Y237047D01*
X544389Y237130D01*
X544889Y237047D01*
X545389Y236714D01*
X545722Y236130D01*
X545806Y235464D01*
X545722Y234797D01*
X545389Y234214D01*
X544889Y233880D01*
X544389Y233797D01*
G01X548489Y232130D02*
Y237130D01*
G01Y236380D02*
X548906Y236797D01*
X549322Y237047D01*
X549989Y237130D01*
X550572Y237047D01*
X551156Y236630D01*
X551406Y236047D01*
X551489Y235464D01*
X551406Y234880D01*
X551156Y234297D01*
X550656Y233964D01*
X549989Y233797D01*
X549406Y233880D01*
X548822Y234130D01*
X548489Y234464D01*
G01X387589Y335297D02*
Y340297D01*
X386589Y339297D01*
G01Y335297D02*
X388589D01*
G01X393189Y335130D02*
X393022Y335214D01*
Y335380D01*
X393189Y335464D01*
X393356Y335380D01*
Y335214D01*
X393189Y335130D01*
G01X398789Y335297D02*
X398122Y335380D01*
X397539Y335714D01*
X397039Y336214D01*
X396706Y336797D01*
X396539Y337464D01*
Y338130D01*
X396706Y338797D01*
X397039Y339380D01*
X397539Y339880D01*
X398122Y340214D01*
X398789Y340297D01*
X399456Y340214D01*
X400039Y339880D01*
X400539Y339380D01*
X400872Y338797D01*
X401039Y338130D01*
Y337464D01*
X400872Y336797D01*
X400539Y336214D01*
X400039Y335714D01*
X399456Y335380D01*
X398789Y335297D01*
G01X402972D02*
Y338630D01*
G01Y337797D02*
X403306Y338214D01*
X403806Y338547D01*
X404472Y338630D01*
X405056Y338547D01*
X405556Y338214D01*
X405806Y337630D01*
Y335297D01*
G01X408739Y337547D02*
X411406D01*
X411156Y338130D01*
X410739Y338464D01*
X410156Y338630D01*
X409572Y338547D01*
X409072Y338297D01*
X408739Y337714D01*
X408572Y337214D01*
Y336714D01*
X408739Y336214D01*
X409156Y335714D01*
X409656Y335380D01*
X410239Y335297D01*
X410822Y335464D01*
X411406Y335964D01*
G01X419939Y335880D02*
X420356Y335547D01*
X420939Y335297D01*
X421439D01*
X421939Y335464D01*
X422272Y335714D01*
X422439Y336047D01*
X422356Y336547D01*
X422022Y336797D01*
X420522Y337297D01*
X420189Y337880D01*
X420356Y338297D01*
X420689Y338547D01*
X421189Y338630D01*
X421689Y338547D01*
X422189Y338297D01*
G01X426789Y338630D02*
Y335297D01*
G01Y339964D02*
X426622Y340047D01*
Y340214D01*
X426789Y340297D01*
X426956Y340214D01*
Y340047D01*
X426789Y339964D01*
G01X433889Y340297D02*
Y335297D01*
G01Y336047D02*
X433556Y335630D01*
X433056Y335380D01*
X432472Y335297D01*
X431806Y335464D01*
X431306Y335880D01*
X430972Y336380D01*
X430889Y336964D01*
X430972Y337547D01*
X431306Y338047D01*
X431806Y338464D01*
X432472Y338630D01*
X433056Y338547D01*
X433472Y338380D01*
X433889Y338047D01*
G01X436739Y337547D02*
X439406D01*
X439156Y338130D01*
X438739Y338464D01*
X438156Y338630D01*
X437572Y338547D01*
X437072Y338297D01*
X436739Y337714D01*
X436572Y337214D01*
Y336714D01*
X436739Y336214D01*
X437156Y335714D01*
X437656Y335380D01*
X438239Y335297D01*
X438822Y335464D01*
X439406Y335964D01*
G01X447106Y338630D02*
X448106Y335297D01*
X449189Y338630D01*
X450272Y335297D01*
X451272Y338630D01*
G01X454789D02*
Y335297D01*
G01Y339964D02*
X454622Y340047D01*
Y340214D01*
X454789Y340297D01*
X454956Y340214D01*
Y340047D01*
X454789Y339964D01*
G01X460389Y340297D02*
Y335297D01*
G01X459222Y338630D02*
X461556D01*
G01X464572Y335297D02*
Y340297D01*
G01Y337880D02*
X464989Y338297D01*
X465406Y338547D01*
X466072Y338630D01*
X466572Y338547D01*
X467156Y338214D01*
X467406Y337714D01*
Y335297D01*
G01X475939Y335880D02*
X476356Y335547D01*
X476939Y335297D01*
X477439D01*
X477939Y335464D01*
X478272Y335714D01*
X478439Y336047D01*
X478356Y336547D01*
X478022Y336797D01*
X476522Y337297D01*
X476189Y337880D01*
X476356Y338297D01*
X476689Y338547D01*
X477189Y338630D01*
X477689Y338547D01*
X478189Y338297D01*
G01X482789Y335297D02*
X482289Y335380D01*
X481789Y335714D01*
X481456Y336297D01*
X481289Y336964D01*
X481456Y337630D01*
X481789Y338214D01*
X482289Y338547D01*
X482789Y338630D01*
X483289Y338547D01*
X483789Y338214D01*
X484122Y337630D01*
X484206Y336964D01*
X484122Y336297D01*
X483789Y335714D01*
X483289Y335380D01*
X482789Y335297D01*
G01X488389D02*
Y340297D01*
G01X495489D02*
Y335297D01*
G01Y336047D02*
X495156Y335630D01*
X494656Y335380D01*
X494072Y335297D01*
X493406Y335464D01*
X492906Y335880D01*
X492572Y336380D01*
X492489Y336964D01*
X492572Y337547D01*
X492906Y338047D01*
X493406Y338464D01*
X494072Y338630D01*
X494656Y338547D01*
X495072Y338380D01*
X495489Y338047D01*
G01X498339Y337547D02*
X501006D01*
X500756Y338130D01*
X500339Y338464D01*
X499756Y338630D01*
X499172Y338547D01*
X498672Y338297D01*
X498339Y337714D01*
X498172Y337214D01*
Y336714D01*
X498339Y336214D01*
X498756Y335714D01*
X499256Y335380D01*
X499839Y335297D01*
X500422Y335464D01*
X501006Y335964D01*
G01X504022Y335297D02*
Y338630D01*
G01Y337964D02*
X504439Y338297D01*
X504856Y338547D01*
X505439Y338630D01*
X505856Y338547D01*
X506356Y338297D01*
G01X513889Y335297D02*
Y338630D01*
G01Y337714D02*
X514139Y338130D01*
X514556Y338464D01*
X515139Y338630D01*
X515722Y338464D01*
X516139Y338130D01*
X516389Y337714D01*
Y335297D01*
G01Y337714D02*
X516639Y338130D01*
X517056Y338464D01*
X517639Y338630D01*
X518222Y338464D01*
X518639Y338130D01*
X518889Y337630D01*
Y335297D01*
G01X523489D02*
Y338630D01*
G01Y338047D02*
X523156Y338380D01*
X522656Y338547D01*
X522072Y338630D01*
X521489Y338464D01*
X520989Y338130D01*
X520656Y337630D01*
X520489Y336964D01*
X520656Y336297D01*
X520989Y335797D01*
X521489Y335464D01*
X522072Y335297D01*
X522656Y335380D01*
X523156Y335630D01*
X523489Y335964D01*
G01X526339Y335880D02*
X526756Y335547D01*
X527339Y335297D01*
X527839D01*
X528339Y335464D01*
X528672Y335714D01*
X528839Y336047D01*
X528756Y336547D01*
X528422Y336797D01*
X526922Y337297D01*
X526589Y337880D01*
X526756Y338297D01*
X527089Y338547D01*
X527589Y338630D01*
X528089Y338547D01*
X528589Y338297D01*
G01X531772Y335297D02*
Y340297D01*
G01X534439Y338630D02*
X531772Y336714D01*
G01X532856Y337464D02*
X534606Y335297D01*
G01X542889Y333630D02*
Y338630D01*
G01Y337880D02*
X543306Y338297D01*
X543722Y338547D01*
X544389Y338630D01*
X544972Y338547D01*
X545556Y338130D01*
X545806Y337547D01*
X545889Y336964D01*
X545806Y336380D01*
X545556Y335797D01*
X545056Y335464D01*
X544389Y335297D01*
X543806Y335380D01*
X543222Y335630D01*
X542889Y335964D01*
G01X551489Y335297D02*
Y338630D01*
G01Y338047D02*
X551156Y338380D01*
X550656Y338547D01*
X550072Y338630D01*
X549489Y338464D01*
X548989Y338130D01*
X548656Y337630D01*
X548489Y336964D01*
X548656Y336297D01*
X548989Y335797D01*
X549489Y335464D01*
X550072Y335297D01*
X550656Y335380D01*
X551156Y335630D01*
X551489Y335964D01*
G01X557089Y340297D02*
Y335297D01*
G01Y336047D02*
X556756Y335630D01*
X556256Y335380D01*
X555672Y335297D01*
X555006Y335464D01*
X554506Y335880D01*
X554172Y336380D01*
X554089Y336964D01*
X554172Y337547D01*
X554506Y338047D01*
X555006Y338464D01*
X555672Y338630D01*
X556256Y338547D01*
X556672Y338380D01*
X557089Y338047D01*
G01X374589Y452797D02*
Y457797D01*
G01Y455297D02*
X375006Y455797D01*
X375506Y456047D01*
X376006Y456130D01*
X376756Y455964D01*
X377256Y455630D01*
X377589Y455047D01*
Y454380D01*
X377422Y453714D01*
X377089Y453214D01*
X376506Y452880D01*
X376006Y452797D01*
X375506Y452880D01*
X375006Y453130D01*
X374589Y453547D01*
G01X381689Y452797D02*
X381189Y452880D01*
X380689Y453214D01*
X380356Y453797D01*
X380189Y454464D01*
X380356Y455130D01*
X380689Y455714D01*
X381189Y456047D01*
X381689Y456130D01*
X382189Y456047D01*
X382689Y455714D01*
X383022Y455130D01*
X383106Y454464D01*
X383022Y453797D01*
X382689Y453214D01*
X382189Y452880D01*
X381689Y452797D01*
G01X388789D02*
Y456130D01*
G01Y455547D02*
X388456Y455880D01*
X387956Y456047D01*
X387372Y456130D01*
X386789Y455964D01*
X386289Y455630D01*
X385956Y455130D01*
X385789Y454464D01*
X385956Y453797D01*
X386289Y453297D01*
X386789Y452964D01*
X387372Y452797D01*
X387956Y452880D01*
X388456Y453130D01*
X388789Y453464D01*
G01X391722Y452797D02*
Y456130D01*
G01Y455464D02*
X392139Y455797D01*
X392556Y456047D01*
X393139Y456130D01*
X393556Y456047D01*
X394056Y455797D01*
G01X399989Y457797D02*
Y452797D01*
G01Y453547D02*
X399656Y453130D01*
X399156Y452880D01*
X398572Y452797D01*
X397906Y452964D01*
X397406Y453380D01*
X397072Y453880D01*
X396989Y454464D01*
X397072Y455047D01*
X397406Y455547D01*
X397906Y455964D01*
X398572Y456130D01*
X399156Y456047D01*
X399572Y455880D01*
X399989Y455547D01*
G01X393256Y-83203D02*
Y-78203D01*
X394922D01*
X395589Y-78453D01*
X396089Y-78786D01*
X396506Y-79286D01*
X396839Y-79870D01*
X396922Y-80703D01*
X396839Y-81536D01*
X396506Y-82120D01*
X396089Y-82620D01*
X395589Y-82953D01*
X394922Y-83203D01*
X393256D01*
G01X400689D02*
Y-78203D01*
X399689Y-79203D01*
G01Y-83203D02*
X401689D01*
G01X391256Y80797D02*
Y85797D01*
X392922D01*
X393589Y85547D01*
X394089Y85214D01*
X394506Y84714D01*
X394839Y84130D01*
X394922Y83297D01*
X394839Y82464D01*
X394506Y81880D01*
X394089Y81380D01*
X393589Y81047D01*
X392922Y80797D01*
X391256D01*
G01X397106Y84964D02*
X397606Y85464D01*
X398189Y85714D01*
X398856Y85797D01*
X399689Y85630D01*
X400272Y85214D01*
X400439Y84714D01*
X400356Y84214D01*
X400022Y83797D01*
X398356Y82964D01*
X397606Y82380D01*
X397106Y81547D01*
X396939Y80797D01*
X400439D01*
G01X395339Y308880D02*
X395756Y308547D01*
X396339Y308297D01*
X396839D01*
X397339Y308464D01*
X397672Y308714D01*
X397839Y309047D01*
X397756Y309547D01*
X397422Y309797D01*
X395922Y310297D01*
X395589Y310880D01*
X395756Y311297D01*
X396089Y311547D01*
X396589Y311630D01*
X397089Y311547D01*
X397589Y311297D01*
G01X402189Y308297D02*
X401689Y308380D01*
X401189Y308714D01*
X400856Y309297D01*
X400689Y309964D01*
X400856Y310630D01*
X401189Y311214D01*
X401689Y311547D01*
X402189Y311630D01*
X402689Y311547D01*
X403189Y311214D01*
X403522Y310630D01*
X403606Y309964D01*
X403522Y309297D01*
X403189Y308714D01*
X402689Y308380D01*
X402189Y308297D01*
G01X407789D02*
Y313297D01*
G01X414889D02*
Y308297D01*
G01Y309047D02*
X414556Y308630D01*
X414056Y308380D01*
X413472Y308297D01*
X412806Y308464D01*
X412306Y308880D01*
X411972Y309380D01*
X411889Y309964D01*
X411972Y310547D01*
X412306Y311047D01*
X412806Y311464D01*
X413472Y311630D01*
X414056Y311547D01*
X414472Y311380D01*
X414889Y311047D01*
G01X417739Y310547D02*
X420406D01*
X420156Y311130D01*
X419739Y311464D01*
X419156Y311630D01*
X418572Y311547D01*
X418072Y311297D01*
X417739Y310714D01*
X417572Y310214D01*
Y309714D01*
X417739Y309214D01*
X418156Y308714D01*
X418656Y308380D01*
X419239Y308297D01*
X419822Y308464D01*
X420406Y308964D01*
G01X423422Y308297D02*
Y311630D01*
G01Y310964D02*
X423839Y311297D01*
X424256Y311547D01*
X424839Y311630D01*
X425256Y311547D01*
X425756Y311297D01*
G01X433289Y308297D02*
Y311630D01*
G01Y310714D02*
X433539Y311130D01*
X433956Y311464D01*
X434539Y311630D01*
X435122Y311464D01*
X435539Y311130D01*
X435789Y310714D01*
Y308297D01*
G01Y310714D02*
X436039Y311130D01*
X436456Y311464D01*
X437039Y311630D01*
X437622Y311464D01*
X438039Y311130D01*
X438289Y310630D01*
Y308297D01*
G01X442889D02*
Y311630D01*
G01Y311047D02*
X442556Y311380D01*
X442056Y311547D01*
X441472Y311630D01*
X440889Y311464D01*
X440389Y311130D01*
X440056Y310630D01*
X439889Y309964D01*
X440056Y309297D01*
X440389Y308797D01*
X440889Y308464D01*
X441472Y308297D01*
X442056Y308380D01*
X442556Y308630D01*
X442889Y308964D01*
G01X445739Y308880D02*
X446156Y308547D01*
X446739Y308297D01*
X447239D01*
X447739Y308464D01*
X448072Y308714D01*
X448239Y309047D01*
X448156Y309547D01*
X447822Y309797D01*
X446322Y310297D01*
X445989Y310880D01*
X446156Y311297D01*
X446489Y311547D01*
X446989Y311630D01*
X447489Y311547D01*
X447989Y311297D01*
G01X451172Y308297D02*
Y313297D01*
G01X453839Y311630D02*
X451172Y309714D01*
G01X452256Y310464D02*
X454006Y308297D01*
G01X462289Y306630D02*
Y311630D01*
G01Y310880D02*
X462706Y311297D01*
X463122Y311547D01*
X463789Y311630D01*
X464372Y311547D01*
X464956Y311130D01*
X465206Y310547D01*
X465289Y309964D01*
X465206Y309380D01*
X464956Y308797D01*
X464456Y308464D01*
X463789Y308297D01*
X463206Y308380D01*
X462622Y308630D01*
X462289Y308964D01*
G01X470889Y308297D02*
Y311630D01*
G01Y311047D02*
X470556Y311380D01*
X470056Y311547D01*
X469472Y311630D01*
X468889Y311464D01*
X468389Y311130D01*
X468056Y310630D01*
X467889Y309964D01*
X468056Y309297D01*
X468389Y308797D01*
X468889Y308464D01*
X469472Y308297D01*
X470056Y308380D01*
X470556Y308630D01*
X470889Y308964D01*
G01X476489Y313297D02*
Y308297D01*
G01Y309047D02*
X476156Y308630D01*
X475656Y308380D01*
X475072Y308297D01*
X474406Y308464D01*
X473906Y308880D01*
X473572Y309380D01*
X473489Y309964D01*
X473572Y310547D01*
X473906Y311047D01*
X474406Y311464D01*
X475072Y311630D01*
X475656Y311547D01*
X476072Y311380D01*
X476489Y311047D01*
G01X395506Y329630D02*
X396506Y326297D01*
X397589Y329630D01*
X398672Y326297D01*
X399672Y329630D01*
G01X401772Y326297D02*
Y331297D01*
G01Y328880D02*
X402189Y329297D01*
X402606Y329547D01*
X403272Y329630D01*
X403772Y329547D01*
X404356Y329214D01*
X404606Y328714D01*
Y326297D01*
G01X408789Y329630D02*
Y326297D01*
G01Y330964D02*
X408622Y331047D01*
Y331214D01*
X408789Y331297D01*
X408956Y331214D01*
Y331047D01*
X408789Y330964D01*
G01X415722Y329214D02*
X415139Y329547D01*
X414639Y329630D01*
X413972Y329464D01*
X413472Y329130D01*
X413139Y328547D01*
X413056Y327964D01*
X413139Y327380D01*
X413472Y326880D01*
X413972Y326464D01*
X414639Y326297D01*
X415222Y326464D01*
X415722Y326797D01*
G01X418572Y326297D02*
Y331297D01*
G01Y328880D02*
X418989Y329297D01*
X419406Y329547D01*
X420072Y329630D01*
X420572Y329547D01*
X421156Y329214D01*
X421406Y328714D01*
Y326297D01*
G01X429939Y326880D02*
X430356Y326547D01*
X430939Y326297D01*
X431439D01*
X431939Y326464D01*
X432272Y326714D01*
X432439Y327047D01*
X432356Y327547D01*
X432022Y327797D01*
X430522Y328297D01*
X430189Y328880D01*
X430356Y329297D01*
X430689Y329547D01*
X431189Y329630D01*
X431689Y329547D01*
X432189Y329297D01*
G01X436789Y329630D02*
Y326297D01*
G01Y330964D02*
X436622Y331047D01*
Y331214D01*
X436789Y331297D01*
X436956Y331214D01*
Y331047D01*
X436789Y330964D01*
G01X441139Y329630D02*
X443639D01*
X441139Y326297D01*
X443639D01*
G01X446739Y328547D02*
X449406D01*
X449156Y329130D01*
X448739Y329464D01*
X448156Y329630D01*
X447572Y329547D01*
X447072Y329297D01*
X446739Y328714D01*
X446572Y328214D01*
Y327714D01*
X446739Y327214D01*
X447156Y326714D01*
X447656Y326380D01*
X448239Y326297D01*
X448822Y326464D01*
X449406Y326964D01*
G01X459189Y329630D02*
Y326297D01*
G01Y330964D02*
X459022Y331047D01*
Y331214D01*
X459189Y331297D01*
X459356Y331214D01*
Y331047D01*
X459189Y330964D01*
G01X463539Y326880D02*
X463956Y326547D01*
X464539Y326297D01*
X465039D01*
X465539Y326464D01*
X465872Y326714D01*
X466039Y327047D01*
X465956Y327547D01*
X465622Y327797D01*
X464122Y328297D01*
X463789Y328880D01*
X463956Y329297D01*
X464289Y329547D01*
X464789Y329630D01*
X465289Y329547D01*
X465789Y329297D01*
G01X474489Y326297D02*
Y331297D01*
G01Y328797D02*
X474906Y329297D01*
X475406Y329547D01*
X475906Y329630D01*
X476656Y329464D01*
X477156Y329130D01*
X477489Y328547D01*
Y327880D01*
X477322Y327214D01*
X476989Y326714D01*
X476406Y326380D01*
X475906Y326297D01*
X475406Y326380D01*
X474906Y326630D01*
X474489Y327047D01*
G01X481589Y329630D02*
Y326297D01*
G01Y330964D02*
X481422Y331047D01*
Y331214D01*
X481589Y331297D01*
X481756Y331214D01*
Y331047D01*
X481589Y330964D01*
G01X486022Y325047D02*
X486606Y324714D01*
X487272Y324630D01*
X487856Y324714D01*
X488356Y325130D01*
X488689Y325714D01*
Y329630D01*
G01Y328964D02*
X488356Y329297D01*
X487856Y329547D01*
X487272Y329630D01*
X486606Y329464D01*
X486189Y329130D01*
X485856Y328547D01*
X485689Y327964D01*
X485772Y327464D01*
X486106Y326880D01*
X486606Y326464D01*
X487272Y326297D01*
X487772Y326380D01*
X488356Y326714D01*
X488689Y327047D01*
G01X491622Y325047D02*
X492206Y324714D01*
X492872Y324630D01*
X493456Y324714D01*
X493956Y325130D01*
X494289Y325714D01*
Y329630D01*
G01Y328964D02*
X493956Y329297D01*
X493456Y329547D01*
X492872Y329630D01*
X492206Y329464D01*
X491789Y329130D01*
X491456Y328547D01*
X491289Y327964D01*
X491372Y327464D01*
X491706Y326880D01*
X492206Y326464D01*
X492872Y326297D01*
X493372Y326380D01*
X493956Y326714D01*
X494289Y327047D01*
G01X497139Y328547D02*
X499806D01*
X499556Y329130D01*
X499139Y329464D01*
X498556Y329630D01*
X497972Y329547D01*
X497472Y329297D01*
X497139Y328714D01*
X496972Y328214D01*
Y327714D01*
X497139Y327214D01*
X497556Y326714D01*
X498056Y326380D01*
X498639Y326297D01*
X499222Y326464D01*
X499806Y326964D01*
G01X502822Y326297D02*
Y329630D01*
G01Y328964D02*
X503239Y329297D01*
X503656Y329547D01*
X504239Y329630D01*
X504656Y329547D01*
X505156Y329297D01*
G01X515189Y331297D02*
Y326297D01*
G01X514022Y329630D02*
X516356D01*
G01X519372Y326297D02*
Y331297D01*
G01Y328880D02*
X519789Y329297D01*
X520206Y329547D01*
X520872Y329630D01*
X521372Y329547D01*
X521956Y329214D01*
X522206Y328714D01*
Y326297D01*
G01X527889D02*
Y329630D01*
G01Y329047D02*
X527556Y329380D01*
X527056Y329547D01*
X526472Y329630D01*
X525889Y329464D01*
X525389Y329130D01*
X525056Y328630D01*
X524889Y327964D01*
X525056Y327297D01*
X525389Y326797D01*
X525889Y326464D01*
X526472Y326297D01*
X527056Y326380D01*
X527556Y326630D01*
X527889Y326964D01*
G01X530572Y326297D02*
Y329630D01*
G01Y328797D02*
X530906Y329214D01*
X531406Y329547D01*
X532072Y329630D01*
X532656Y329547D01*
X533156Y329214D01*
X533406Y328630D01*
Y326297D01*
G01X544689D02*
Y329630D01*
G01Y329047D02*
X544356Y329380D01*
X543856Y329547D01*
X543272Y329630D01*
X542689Y329464D01*
X542189Y329130D01*
X541856Y328630D01*
X541689Y327964D01*
X541856Y327297D01*
X542189Y326797D01*
X542689Y326464D01*
X543272Y326297D01*
X543856Y326380D01*
X544356Y326630D01*
X544689Y326964D01*
G01X547372Y326297D02*
Y329630D01*
G01Y328797D02*
X547706Y329214D01*
X548206Y329547D01*
X548872Y329630D01*
X549456Y329547D01*
X549956Y329214D01*
X550206Y328630D01*
Y326297D01*
G01X552972D02*
Y329630D01*
G01Y328797D02*
X553306Y329214D01*
X553806Y329547D01*
X554472Y329630D01*
X555056Y329547D01*
X555556Y329214D01*
X555806Y328630D01*
Y326297D01*
G01X558572Y329630D02*
Y327297D01*
X558906Y326714D01*
X559406Y326380D01*
X559989Y326297D01*
X560572Y326380D01*
X561072Y326714D01*
X561406Y327297D01*
G01Y326297D02*
Y329630D01*
G01X567089Y326297D02*
Y329630D01*
G01Y329047D02*
X566756Y329380D01*
X566256Y329547D01*
X565672Y329630D01*
X565089Y329464D01*
X564589Y329130D01*
X564256Y328630D01*
X564089Y327964D01*
X564256Y327297D01*
X564589Y326797D01*
X565089Y326464D01*
X565672Y326297D01*
X566256Y326380D01*
X566756Y326630D01*
X567089Y326964D01*
G01X571189Y326297D02*
Y331297D01*
G01X396922Y317297D02*
Y320630D01*
G01Y319964D02*
X397339Y320297D01*
X397756Y320547D01*
X398339Y320630D01*
X398756Y320547D01*
X399256Y320297D01*
G01X403689Y320630D02*
Y317297D01*
G01Y321964D02*
X403522Y322047D01*
Y322214D01*
X403689Y322297D01*
X403856Y322214D01*
Y322047D01*
X403689Y321964D01*
G01X407872Y317297D02*
Y320630D01*
G01Y319797D02*
X408206Y320214D01*
X408706Y320547D01*
X409372Y320630D01*
X409956Y320547D01*
X410456Y320214D01*
X410706Y319630D01*
Y317297D01*
G01X413722Y316047D02*
X414306Y315714D01*
X414972Y315630D01*
X415556Y315714D01*
X416056Y316130D01*
X416389Y316714D01*
Y320630D01*
G01Y319964D02*
X416056Y320297D01*
X415556Y320547D01*
X414972Y320630D01*
X414306Y320464D01*
X413889Y320130D01*
X413556Y319547D01*
X413389Y318964D01*
X413472Y318464D01*
X413806Y317880D01*
X414306Y317464D01*
X414972Y317297D01*
X415472Y317380D01*
X416056Y317714D01*
X416389Y318047D01*
G01X424839Y317880D02*
X425256Y317547D01*
X425839Y317297D01*
X426339D01*
X426839Y317464D01*
X427172Y317714D01*
X427339Y318047D01*
X427256Y318547D01*
X426922Y318797D01*
X425422Y319297D01*
X425089Y319880D01*
X425256Y320297D01*
X425589Y320547D01*
X426089Y320630D01*
X426589Y320547D01*
X427089Y320297D01*
G01X431689Y320630D02*
Y317297D01*
G01Y321964D02*
X431522Y322047D01*
Y322214D01*
X431689Y322297D01*
X431856Y322214D01*
Y322047D01*
X431689Y321964D01*
G01X436039Y320630D02*
X438539D01*
X436039Y317297D01*
X438539D01*
G01X441639Y319547D02*
X444306D01*
X444056Y320130D01*
X443639Y320464D01*
X443056Y320630D01*
X442472Y320547D01*
X441972Y320297D01*
X441639Y319714D01*
X441472Y319214D01*
Y318714D01*
X441639Y318214D01*
X442056Y317714D01*
X442556Y317380D01*
X443139Y317297D01*
X443722Y317464D01*
X444306Y317964D01*
G01X453922Y316380D02*
X454256Y317464D01*
G01X408672Y500797D02*
Y505797D01*
G01Y503380D02*
X409089Y503797D01*
X409506Y504047D01*
X410172Y504130D01*
X410672Y504047D01*
X411256Y503714D01*
X411506Y503214D01*
Y500797D01*
G01X417189D02*
Y504130D01*
G01Y503547D02*
X416856Y503880D01*
X416356Y504047D01*
X415772Y504130D01*
X415189Y503964D01*
X414689Y503630D01*
X414356Y503130D01*
X414189Y502464D01*
X414356Y501797D01*
X414689Y501297D01*
X415189Y500964D01*
X415772Y500797D01*
X416356Y500880D01*
X416856Y501130D01*
X417189Y501464D01*
G01X421289Y500797D02*
Y505797D01*
G01X426389Y500797D02*
Y505047D01*
X426556Y505464D01*
X426889Y505714D01*
X427389Y505797D01*
X427889Y505630D01*
X428139Y505214D01*
G01X427139Y503797D02*
X425472D01*
G01X436589Y499130D02*
Y504130D01*
G01Y503380D02*
X437006Y503797D01*
X437422Y504047D01*
X438089Y504130D01*
X438672Y504047D01*
X439256Y503630D01*
X439506Y503047D01*
X439589Y502464D01*
X439506Y501880D01*
X439256Y501297D01*
X438756Y500964D01*
X438089Y500797D01*
X437506Y500880D01*
X436922Y501130D01*
X436589Y501464D01*
G01X443689Y500797D02*
Y505797D01*
G01X447872Y504130D02*
Y501797D01*
X448206Y501214D01*
X448706Y500880D01*
X449289Y500797D01*
X449872Y500880D01*
X450372Y501214D01*
X450706Y501797D01*
G01Y500797D02*
Y504130D01*
G01X453722Y499547D02*
X454306Y499214D01*
X454972Y499130D01*
X455556Y499214D01*
X456056Y499630D01*
X456389Y500214D01*
Y504130D01*
G01Y503464D02*
X456056Y503797D01*
X455556Y504047D01*
X454972Y504130D01*
X454306Y503964D01*
X453889Y503630D01*
X453556Y503047D01*
X453389Y502464D01*
X453472Y501964D01*
X453806Y501380D01*
X454306Y500964D01*
X454972Y500797D01*
X455472Y500880D01*
X456056Y501214D01*
X456389Y501547D01*
G01X459322Y499547D02*
X459906Y499214D01*
X460572Y499130D01*
X461156Y499214D01*
X461656Y499630D01*
X461989Y500214D01*
Y504130D01*
G01Y503464D02*
X461656Y503797D01*
X461156Y504047D01*
X460572Y504130D01*
X459906Y503964D01*
X459489Y503630D01*
X459156Y503047D01*
X458989Y502464D01*
X459072Y501964D01*
X459406Y501380D01*
X459906Y500964D01*
X460572Y500797D01*
X461072Y500880D01*
X461656Y501214D01*
X461989Y501547D01*
G01X466089Y504130D02*
Y500797D01*
G01Y505464D02*
X465922Y505547D01*
Y505714D01*
X466089Y505797D01*
X466256Y505714D01*
Y505547D01*
X466089Y505464D01*
G01X470272Y500797D02*
Y504130D01*
G01Y503297D02*
X470606Y503714D01*
X471106Y504047D01*
X471772Y504130D01*
X472356Y504047D01*
X472856Y503714D01*
X473106Y503130D01*
Y500797D01*
G01X476122Y499547D02*
X476706Y499214D01*
X477372Y499130D01*
X477956Y499214D01*
X478456Y499630D01*
X478789Y500214D01*
Y504130D01*
G01Y503464D02*
X478456Y503797D01*
X477956Y504047D01*
X477372Y504130D01*
X476706Y503964D01*
X476289Y503630D01*
X475956Y503047D01*
X475789Y502464D01*
X475872Y501964D01*
X476206Y501380D01*
X476706Y500964D01*
X477372Y500797D01*
X477872Y500880D01*
X478456Y501214D01*
X478789Y501547D01*
G01X433839Y-81703D02*
Y-76703D01*
G01X437339D02*
Y-81703D01*
G01Y-79203D02*
X433839D01*
G01X441189Y-81703D02*
X440522Y-81620D01*
X439939Y-81286D01*
X439439Y-80786D01*
X439106Y-80203D01*
X438939Y-79536D01*
Y-78870D01*
X439106Y-78203D01*
X439439Y-77620D01*
X439939Y-77120D01*
X440522Y-76786D01*
X441189Y-76703D01*
X441856Y-76786D01*
X442439Y-77120D01*
X442939Y-77620D01*
X443272Y-78203D01*
X443439Y-78870D01*
Y-79536D01*
X443272Y-80203D01*
X442939Y-80786D01*
X442439Y-81286D01*
X441856Y-81620D01*
X441189Y-81703D01*
G01X445122Y-76703D02*
Y-81703D01*
X448456D01*
G01X454056D02*
X450722D01*
Y-76703D01*
X454056D01*
G01X452722Y-79120D02*
X450722D01*
G01X477889Y-81703D02*
Y-78370D01*
G01Y-79286D02*
X478139Y-78870D01*
X478556Y-78536D01*
X479139Y-78370D01*
X479722Y-78536D01*
X480139Y-78870D01*
X480389Y-79286D01*
Y-81703D01*
G01Y-79286D02*
X480639Y-78870D01*
X481056Y-78536D01*
X481639Y-78370D01*
X482222Y-78536D01*
X482639Y-78870D01*
X482889Y-79370D01*
Y-81703D01*
G01X485989Y-78370D02*
Y-81703D01*
G01Y-77036D02*
X485822Y-76953D01*
Y-76786D01*
X485989Y-76703D01*
X486156Y-76786D01*
Y-76953D01*
X485989Y-77036D01*
G01X491589Y-81703D02*
Y-76703D01*
G01X495939Y-81120D02*
X496356Y-81453D01*
X496939Y-81703D01*
X497439D01*
X497939Y-81536D01*
X498272Y-81286D01*
X498439Y-80953D01*
X498356Y-80453D01*
X498022Y-80203D01*
X496522Y-79703D01*
X496189Y-79120D01*
X496356Y-78703D01*
X496689Y-78453D01*
X497189Y-78370D01*
X497689Y-78453D01*
X498189Y-78703D01*
G01X502372Y-83370D02*
X501539Y-82536D01*
X501122Y-81703D01*
Y-78370D01*
X501539Y-77536D01*
X502372Y-76703D01*
G01X506722Y-81703D02*
Y-76703D01*
X508722D01*
X509389Y-76953D01*
X509889Y-77536D01*
X510056Y-78203D01*
X509889Y-78870D01*
X509472Y-79370D01*
X508722Y-79620D01*
X506722D01*
G01X513989Y-76703D02*
Y-81703D01*
G01X512072Y-76703D02*
X515906D01*
G01X517839Y-81703D02*
Y-76703D01*
G01X521339D02*
Y-81703D01*
G01Y-79203D02*
X517839D01*
G01X525606Y-83370D02*
X526439Y-82536D01*
X526856Y-81703D01*
Y-78370D01*
X526439Y-77536D01*
X525606Y-76703D01*
G01X433756Y74464D02*
X434089Y74714D01*
X434339Y75130D01*
X434506Y75714D01*
X434339Y76214D01*
X434006Y76547D01*
X433422Y76797D01*
X431172D01*
Y71797D01*
X433922D01*
X434506Y72130D01*
X434839Y72630D01*
X435006Y73214D01*
X434839Y73797D01*
X434339Y74297D01*
X433756Y74464D01*
X431172D01*
G01X436606Y71797D02*
X438689Y76797D01*
X440772Y71797D01*
G01X440022Y73547D02*
X437356D01*
G01X446122Y76380D02*
X445622Y76630D01*
X445039Y76797D01*
X444372D01*
X443622Y76547D01*
X443039Y76130D01*
X442622Y75630D01*
X442289Y74797D01*
X442206Y74047D01*
X442372Y73297D01*
X442622Y72797D01*
X443122Y72297D01*
X443706Y71964D01*
X444289Y71797D01*
X444872D01*
X445456Y71964D01*
X445956Y72214D01*
X446372Y72547D01*
G01X448056Y71797D02*
Y76797D01*
G01X451222D02*
X448056Y73714D01*
G01X451722Y71797D02*
X449472Y75130D01*
G01X459256Y71797D02*
Y76797D01*
X460922D01*
X461589Y76547D01*
X462089Y76214D01*
X462506Y75714D01*
X462839Y75130D01*
X462922Y74297D01*
X462839Y73464D01*
X462506Y72880D01*
X462089Y72380D01*
X461589Y72047D01*
X460922Y71797D01*
X459256D01*
G01X465022D02*
Y76797D01*
X467106D01*
X467772Y76547D01*
X468189Y76214D01*
X468356Y75547D01*
X468189Y74880D01*
X467689Y74464D01*
X467106Y74214D01*
X465022D01*
G01X467106D02*
X468356Y71797D01*
G01X471289Y76797D02*
X473289D01*
G01X472289D02*
Y71797D01*
G01X471289D02*
X473289D01*
G01X476222Y76797D02*
Y71797D01*
X479556D01*
G01X481822Y76797D02*
Y71797D01*
X485156D01*
G01X508989D02*
Y75130D01*
G01Y74214D02*
X509239Y74630D01*
X509656Y74964D01*
X510239Y75130D01*
X510822Y74964D01*
X511239Y74630D01*
X511489Y74214D01*
Y71797D01*
G01Y74214D02*
X511739Y74630D01*
X512156Y74964D01*
X512739Y75130D01*
X513322Y74964D01*
X513739Y74630D01*
X513989Y74130D01*
Y71797D01*
G01X517089Y75130D02*
Y71797D01*
G01Y76464D02*
X516922Y76547D01*
Y76714D01*
X517089Y76797D01*
X517256Y76714D01*
Y76547D01*
X517089Y76464D01*
G01X522689Y71797D02*
Y76797D01*
G01X527039Y72380D02*
X527456Y72047D01*
X528039Y71797D01*
X528539D01*
X529039Y71964D01*
X529372Y72214D01*
X529539Y72547D01*
X529456Y73047D01*
X529122Y73297D01*
X527622Y73797D01*
X527289Y74380D01*
X527456Y74797D01*
X527789Y75047D01*
X528289Y75130D01*
X528789Y75047D01*
X529289Y74797D01*
G01X533472Y70130D02*
X532639Y70964D01*
X532222Y71797D01*
Y75130D01*
X532639Y75964D01*
X533472Y76797D01*
G01X537572Y71797D02*
Y76797D01*
X541406Y71797D01*
Y76797D01*
G01X543422Y71797D02*
Y76797D01*
X545422D01*
X546089Y76547D01*
X546589Y75964D01*
X546756Y75297D01*
X546589Y74630D01*
X546172Y74130D01*
X545422Y73880D01*
X543422D01*
G01X550689Y76797D02*
Y71797D01*
G01X548772Y76797D02*
X552606D01*
G01X554539Y71797D02*
Y76797D01*
G01X558039D02*
Y71797D01*
G01Y74297D02*
X554539D01*
G01X562306Y70130D02*
X563139Y70964D01*
X563556Y71797D01*
Y75130D01*
X563139Y75964D01*
X562306Y76797D01*
G01X454856Y115370D02*
X458522Y119037D01*
G01X456689Y119704D02*
Y114704D01*
G01X458522Y115370D02*
X454856Y119037D01*
G01X454189Y117204D02*
X459189D01*
G01X461872Y113870D02*
X461039Y114704D01*
X460622Y115537D01*
Y118870D01*
X461039Y119704D01*
X461872Y120537D01*
G01X466056Y116287D02*
X466556Y115870D01*
X467139Y115620D01*
X467889Y115537D01*
X468639Y115704D01*
X469222Y116037D01*
X469639Y116620D01*
X469722Y117287D01*
X469556Y117954D01*
X469139Y118370D01*
X468556Y118704D01*
X467972Y118787D01*
X467389Y118704D01*
X466639Y118370D01*
X466889Y120537D01*
X469139D01*
G01X473489Y115370D02*
X473322Y115454D01*
Y115620D01*
X473489Y115704D01*
X473656Y115620D01*
Y115454D01*
X473489Y115370D01*
G01X479089Y115537D02*
Y120537D01*
X478089Y119537D01*
G01Y115537D02*
X480089D01*
G01X485106Y113870D02*
X485939Y114704D01*
X486356Y115537D01*
Y118870D01*
X485939Y119704D01*
X485106Y120537D01*
G01X459589Y322297D02*
Y317297D01*
G01X458422Y320630D02*
X460756D01*
G01X463772Y317297D02*
Y322297D01*
G01Y319880D02*
X464189Y320297D01*
X464606Y320547D01*
X465272Y320630D01*
X465772Y320547D01*
X466356Y320214D01*
X466606Y319714D01*
Y317297D01*
G01X469539Y319547D02*
X472206D01*
X471956Y320130D01*
X471539Y320464D01*
X470956Y320630D01*
X470372Y320547D01*
X469872Y320297D01*
X469539Y319714D01*
X469372Y319214D01*
Y318714D01*
X469539Y318214D01*
X469956Y317714D01*
X470456Y317380D01*
X471039Y317297D01*
X471622Y317464D01*
X472206Y317964D01*
G01X481989Y317297D02*
X481489Y317380D01*
X480989Y317714D01*
X480656Y318297D01*
X480489Y318964D01*
X480656Y319630D01*
X480989Y320214D01*
X481489Y320547D01*
X481989Y320630D01*
X482489Y320547D01*
X482989Y320214D01*
X483322Y319630D01*
X483406Y318964D01*
X483322Y318297D01*
X482989Y317714D01*
X482489Y317380D01*
X481989Y317297D01*
G01X487589Y322297D02*
Y317297D01*
G01X486422Y320630D02*
X488756D01*
G01X491772Y317297D02*
Y322297D01*
G01Y319880D02*
X492189Y320297D01*
X492606Y320547D01*
X493272Y320630D01*
X493772Y320547D01*
X494356Y320214D01*
X494606Y319714D01*
Y317297D01*
G01X497539Y319547D02*
X500206D01*
X499956Y320130D01*
X499539Y320464D01*
X498956Y320630D01*
X498372Y320547D01*
X497872Y320297D01*
X497539Y319714D01*
X497372Y319214D01*
Y318714D01*
X497539Y318214D01*
X497956Y317714D01*
X498456Y317380D01*
X499039Y317297D01*
X499622Y317464D01*
X500206Y317964D01*
G01X503222Y317297D02*
Y320630D01*
G01Y319964D02*
X503639Y320297D01*
X504056Y320547D01*
X504639Y320630D01*
X505056Y320547D01*
X505556Y320297D01*
G01X514339Y317880D02*
X514756Y317547D01*
X515339Y317297D01*
X515839D01*
X516339Y317464D01*
X516672Y317714D01*
X516839Y318047D01*
X516756Y318547D01*
X516422Y318797D01*
X514922Y319297D01*
X514589Y319880D01*
X514756Y320297D01*
X515089Y320547D01*
X515589Y320630D01*
X516089Y320547D01*
X516589Y320297D01*
G01X521189Y320630D02*
Y317297D01*
G01Y321964D02*
X521022Y322047D01*
Y322214D01*
X521189Y322297D01*
X521356Y322214D01*
Y322047D01*
X521189Y321964D01*
G01X528289Y322297D02*
Y317297D01*
G01Y318047D02*
X527956Y317630D01*
X527456Y317380D01*
X526872Y317297D01*
X526206Y317464D01*
X525706Y317880D01*
X525372Y318380D01*
X525289Y318964D01*
X525372Y319547D01*
X525706Y320047D01*
X526206Y320464D01*
X526872Y320630D01*
X527456Y320547D01*
X527872Y320380D01*
X528289Y320047D01*
G01X531139Y319547D02*
X533806D01*
X533556Y320130D01*
X533139Y320464D01*
X532556Y320630D01*
X531972Y320547D01*
X531472Y320297D01*
X531139Y319714D01*
X530972Y319214D01*
Y318714D01*
X531139Y318214D01*
X531556Y317714D01*
X532056Y317380D01*
X532639Y317297D01*
X533222Y317464D01*
X533806Y317964D01*
G01X541506Y320630D02*
X542506Y317297D01*
X543589Y320630D01*
X544672Y317297D01*
X545672Y320630D01*
G01X549189D02*
Y317297D01*
G01Y321964D02*
X549022Y322047D01*
Y322214D01*
X549189Y322297D01*
X549356Y322214D01*
Y322047D01*
X549189Y321964D01*
G01X554789Y322297D02*
Y317297D01*
G01X553622Y320630D02*
X555956D01*
G01X558972Y317297D02*
Y322297D01*
G01Y319880D02*
X559389Y320297D01*
X559806Y320547D01*
X560472Y320630D01*
X560972Y320547D01*
X561556Y320214D01*
X561806Y319714D01*
Y317297D01*
G01X565989D02*
X565489Y317380D01*
X564989Y317714D01*
X564656Y318297D01*
X564489Y318964D01*
X564656Y319630D01*
X564989Y320214D01*
X565489Y320547D01*
X565989Y320630D01*
X566489Y320547D01*
X566989Y320214D01*
X567322Y319630D01*
X567406Y318964D01*
X567322Y318297D01*
X566989Y317714D01*
X566489Y317380D01*
X565989Y317297D01*
G01X570172Y320630D02*
Y318297D01*
X570506Y317714D01*
X571006Y317380D01*
X571589Y317297D01*
X572172Y317380D01*
X572672Y317714D01*
X573006Y318297D01*
G01Y317297D02*
Y320630D01*
G01X577189Y322297D02*
Y317297D01*
G01X576022Y320630D02*
X578356D01*
G01X443589Y357797D02*
X445256D01*
Y356297D01*
X444756Y355797D01*
X444172Y355464D01*
X443339Y355297D01*
X442506Y355464D01*
X441922Y355797D01*
X441422Y356297D01*
X441089Y356880D01*
X440922Y357547D01*
Y358130D01*
X441089Y358630D01*
X441422Y359214D01*
X441922Y359714D01*
X442422Y360047D01*
X443089Y360297D01*
X443672D01*
X444339Y360130D01*
X444839Y359797D01*
G01X447439Y357547D02*
X450106D01*
X449856Y358130D01*
X449439Y358464D01*
X448856Y358630D01*
X448272Y358547D01*
X447772Y358297D01*
X447439Y357714D01*
X447272Y357214D01*
Y356714D01*
X447439Y356214D01*
X447856Y355714D01*
X448356Y355380D01*
X448939Y355297D01*
X449522Y355464D01*
X450106Y355964D01*
G01X453122Y355297D02*
Y358630D01*
G01Y357964D02*
X453539Y358297D01*
X453956Y358547D01*
X454539Y358630D01*
X454956Y358547D01*
X455456Y358297D01*
G01X458389Y355297D02*
Y360297D01*
G01Y357797D02*
X458806Y358297D01*
X459306Y358547D01*
X459806Y358630D01*
X460556Y358464D01*
X461056Y358130D01*
X461389Y357547D01*
Y356880D01*
X461222Y356214D01*
X460889Y355714D01*
X460306Y355380D01*
X459806Y355297D01*
X459306Y355380D01*
X458806Y355630D01*
X458389Y356047D01*
G01X464239Y357547D02*
X466906D01*
X466656Y358130D01*
X466239Y358464D01*
X465656Y358630D01*
X465072Y358547D01*
X464572Y358297D01*
X464239Y357714D01*
X464072Y357214D01*
Y356714D01*
X464239Y356214D01*
X464656Y355714D01*
X465156Y355380D01*
X465739Y355297D01*
X466322Y355464D01*
X466906Y355964D01*
G01X469922Y355297D02*
Y358630D01*
G01Y357964D02*
X470339Y358297D01*
X470756Y358547D01*
X471339Y358630D01*
X471756Y358547D01*
X472256Y358297D01*
G01X483789Y360297D02*
Y355297D01*
G01Y356047D02*
X483456Y355630D01*
X482956Y355380D01*
X482372Y355297D01*
X481706Y355464D01*
X481206Y355880D01*
X480872Y356380D01*
X480789Y356964D01*
X480872Y357547D01*
X481206Y358047D01*
X481706Y358464D01*
X482372Y358630D01*
X482956Y358547D01*
X483372Y358380D01*
X483789Y358047D01*
G01X486639Y357547D02*
X489306D01*
X489056Y358130D01*
X488639Y358464D01*
X488056Y358630D01*
X487472Y358547D01*
X486972Y358297D01*
X486639Y357714D01*
X486472Y357214D01*
Y356714D01*
X486639Y356214D01*
X487056Y355714D01*
X487556Y355380D01*
X488139Y355297D01*
X488722Y355464D01*
X489306Y355964D01*
G01X492239Y355880D02*
X492656Y355547D01*
X493239Y355297D01*
X493739D01*
X494239Y355464D01*
X494572Y355714D01*
X494739Y356047D01*
X494656Y356547D01*
X494322Y356797D01*
X492822Y357297D01*
X492489Y357880D01*
X492656Y358297D01*
X492989Y358547D01*
X493489Y358630D01*
X493989Y358547D01*
X494489Y358297D01*
G01X499089Y358630D02*
Y355297D01*
G01Y359964D02*
X498922Y360047D01*
Y360214D01*
X499089Y360297D01*
X499256Y360214D01*
Y360047D01*
X499089Y359964D01*
G01X503522Y354047D02*
X504106Y353714D01*
X504772Y353630D01*
X505356Y353714D01*
X505856Y354130D01*
X506189Y354714D01*
Y358630D01*
G01Y357964D02*
X505856Y358297D01*
X505356Y358547D01*
X504772Y358630D01*
X504106Y358464D01*
X503689Y358130D01*
X503356Y357547D01*
X503189Y356964D01*
X503272Y356464D01*
X503606Y355880D01*
X504106Y355464D01*
X504772Y355297D01*
X505272Y355380D01*
X505856Y355714D01*
X506189Y356047D01*
G01X508872Y355297D02*
Y358630D01*
G01Y357797D02*
X509206Y358214D01*
X509706Y358547D01*
X510372Y358630D01*
X510956Y358547D01*
X511456Y358214D01*
X511706Y357630D01*
Y355297D01*
G01X474589Y-166203D02*
Y-161203D01*
X471506Y-164786D01*
X475672D01*
G01X477356Y-165453D02*
X477856Y-165870D01*
X478439Y-166120D01*
X479189Y-166203D01*
X479939Y-166036D01*
X480522Y-165703D01*
X480939Y-165120D01*
X481022Y-164453D01*
X480856Y-163786D01*
X480439Y-163370D01*
X479856Y-163036D01*
X479272Y-162953D01*
X478689Y-163036D01*
X477939Y-163370D01*
X478189Y-161203D01*
X480439D01*
G01X474839Y-49620D02*
X475256Y-49953D01*
X475839Y-50203D01*
X476339D01*
X476839Y-50036D01*
X477172Y-49786D01*
X477339Y-49453D01*
X477256Y-48953D01*
X476922Y-48703D01*
X475422Y-48203D01*
X475089Y-47620D01*
X475256Y-47203D01*
X475589Y-46953D01*
X476089Y-46870D01*
X476589Y-46953D01*
X477089Y-47203D01*
G01X481689Y-45203D02*
Y-50203D01*
G01X480522Y-46870D02*
X482856D01*
G01X485872D02*
Y-49203D01*
X486206Y-49786D01*
X486706Y-50120D01*
X487289Y-50203D01*
X487872Y-50120D01*
X488372Y-49786D01*
X488706Y-49203D01*
G01Y-50203D02*
Y-46870D01*
G01X491389Y-50203D02*
Y-45203D01*
G01Y-47703D02*
X491806Y-47203D01*
X492306Y-46953D01*
X492806Y-46870D01*
X493556Y-47036D01*
X494056Y-47370D01*
X494389Y-47953D01*
Y-48620D01*
X494222Y-49286D01*
X493889Y-49786D01*
X493306Y-50120D01*
X492806Y-50203D01*
X492306Y-50120D01*
X491806Y-49870D01*
X491389Y-49453D01*
G01X504089Y-50203D02*
Y-45203D01*
G01X508439Y-47953D02*
X511106D01*
X510856Y-47370D01*
X510439Y-47036D01*
X509856Y-46870D01*
X509272Y-46953D01*
X508772Y-47203D01*
X508439Y-47786D01*
X508272Y-48286D01*
Y-48786D01*
X508439Y-49286D01*
X508856Y-49786D01*
X509356Y-50120D01*
X509939Y-50203D01*
X510522Y-50036D01*
X511106Y-49536D01*
G01X513872Y-50203D02*
Y-46870D01*
G01Y-47703D02*
X514206Y-47286D01*
X514706Y-46953D01*
X515372Y-46870D01*
X515956Y-46953D01*
X516456Y-47286D01*
X516706Y-47870D01*
Y-50203D01*
G01X519722Y-51453D02*
X520306Y-51786D01*
X520972Y-51870D01*
X521556Y-51786D01*
X522056Y-51370D01*
X522389Y-50786D01*
Y-46870D01*
G01Y-47536D02*
X522056Y-47203D01*
X521556Y-46953D01*
X520972Y-46870D01*
X520306Y-47036D01*
X519889Y-47370D01*
X519556Y-47953D01*
X519389Y-48536D01*
X519472Y-49036D01*
X519806Y-49620D01*
X520306Y-50036D01*
X520972Y-50203D01*
X521472Y-50120D01*
X522056Y-49786D01*
X522389Y-49453D01*
G01X526489Y-45203D02*
Y-50203D01*
G01X525322Y-46870D02*
X527656D01*
G01X530672Y-50203D02*
Y-45203D01*
G01Y-47620D02*
X531089Y-47203D01*
X531506Y-46953D01*
X532172Y-46870D01*
X532672Y-46953D01*
X533256Y-47286D01*
X533506Y-47786D01*
Y-50203D01*
G01X536606Y-49286D02*
X538772D01*
G01Y-47786D02*
X536606D01*
G01X541706Y-48120D02*
X542289Y-47536D01*
X542789Y-47203D01*
X543456Y-47036D01*
X544039Y-47203D01*
X544456Y-47536D01*
X544789Y-48036D01*
X544872Y-48620D01*
X544789Y-49120D01*
X544456Y-49620D01*
X543956Y-50036D01*
X543372Y-50203D01*
X542706Y-50036D01*
X542122Y-49536D01*
X541789Y-48786D01*
X541706Y-47953D01*
X541872Y-46870D01*
X542122Y-46286D01*
X542539Y-45703D01*
X543122Y-45286D01*
X543706Y-45203D01*
X544289Y-45370D01*
X544706Y-45786D01*
G01X547972Y-48536D02*
X549972D01*
G01X548889Y-47453D02*
Y-49620D01*
G01X552989Y-50370D02*
X555989Y-45203D01*
G01X559006Y-48536D02*
X561172D01*
G01X563856Y-49453D02*
X564356Y-49870D01*
X564939Y-50120D01*
X565689Y-50203D01*
X566439Y-50036D01*
X567022Y-49703D01*
X567439Y-49120D01*
X567522Y-48453D01*
X567356Y-47786D01*
X566939Y-47370D01*
X566356Y-47036D01*
X565772Y-46953D01*
X565189Y-47036D01*
X564439Y-47370D01*
X564689Y-45203D01*
X566939D01*
G01X568789Y-50203D02*
Y-46870D01*
G01Y-47786D02*
X569039Y-47370D01*
X569456Y-47036D01*
X570039Y-46870D01*
X570622Y-47036D01*
X571039Y-47370D01*
X571289Y-47786D01*
Y-50203D01*
G01Y-47786D02*
X571539Y-47370D01*
X571956Y-47036D01*
X572539Y-46870D01*
X573122Y-47036D01*
X573539Y-47370D01*
X573789Y-47870D01*
Y-50203D01*
G01X576889Y-46870D02*
Y-50203D01*
G01Y-45536D02*
X576722Y-45453D01*
Y-45286D01*
X576889Y-45203D01*
X577056Y-45286D01*
Y-45453D01*
X576889Y-45536D01*
G01X582489Y-50203D02*
Y-45203D01*
G01X466422Y-19203D02*
Y-24203D01*
X469756D01*
G01X472272D02*
Y-20870D01*
G01Y-21703D02*
X472606Y-21286D01*
X473106Y-20953D01*
X473772Y-20870D01*
X474356Y-20953D01*
X474856Y-21286D01*
X475106Y-21870D01*
Y-24203D01*
G01X468422Y21797D02*
Y16797D01*
X471756D01*
G01X474439Y20130D02*
X476939Y16797D01*
G01Y20130D02*
X474439Y16797D01*
G01X494172Y-210620D02*
X494756Y-211036D01*
X495422Y-211203D01*
X496089Y-211036D01*
X496672Y-210536D01*
X497089Y-209786D01*
X497256Y-209036D01*
Y-208120D01*
X497089Y-207370D01*
X496672Y-206703D01*
X496172Y-206370D01*
X495589Y-206203D01*
X494922Y-206370D01*
X494422Y-206703D01*
X494089Y-207203D01*
X493922Y-207870D01*
X494089Y-208453D01*
X494506Y-209036D01*
X495006Y-209370D01*
X495589Y-209453D01*
X496256Y-209286D01*
X496756Y-208870D01*
X497256Y-208120D01*
G01X499606Y-209120D02*
X500189Y-208536D01*
X500689Y-208203D01*
X501356Y-208036D01*
X501939Y-208203D01*
X502356Y-208536D01*
X502689Y-209036D01*
X502772Y-209620D01*
X502689Y-210120D01*
X502356Y-210620D01*
X501856Y-211036D01*
X501272Y-211203D01*
X500606Y-211036D01*
X500022Y-210536D01*
X499689Y-209786D01*
X499606Y-208953D01*
X499772Y-207870D01*
X500022Y-207286D01*
X500439Y-206703D01*
X501022Y-206286D01*
X501606Y-206203D01*
X502189Y-206370D01*
X502606Y-206786D01*
G01X494589Y500797D02*
Y505047D01*
X494756Y505464D01*
X495089Y505714D01*
X495589Y505797D01*
X496089Y505630D01*
X496339Y505214D01*
G01X495339Y503797D02*
X493672D01*
G01X499272Y504130D02*
Y501797D01*
X499606Y501214D01*
X500106Y500880D01*
X500689Y500797D01*
X501272Y500880D01*
X501772Y501214D01*
X502106Y501797D01*
G01Y500797D02*
Y504130D01*
G01X506289Y500797D02*
Y505797D01*
G01X511889Y500797D02*
Y505797D01*
G01X521589Y499130D02*
Y504130D01*
G01Y503380D02*
X522006Y503797D01*
X522422Y504047D01*
X523089Y504130D01*
X523672Y504047D01*
X524256Y503630D01*
X524506Y503047D01*
X524589Y502464D01*
X524506Y501880D01*
X524256Y501297D01*
X523756Y500964D01*
X523089Y500797D01*
X522506Y500880D01*
X521922Y501130D01*
X521589Y501464D01*
G01X528689Y500797D02*
Y505797D01*
G01X532872Y504130D02*
Y501797D01*
X533206Y501214D01*
X533706Y500880D01*
X534289Y500797D01*
X534872Y500880D01*
X535372Y501214D01*
X535706Y501797D01*
G01Y500797D02*
Y504130D01*
G01X538722Y499547D02*
X539306Y499214D01*
X539972Y499130D01*
X540556Y499214D01*
X541056Y499630D01*
X541389Y500214D01*
Y504130D01*
G01Y503464D02*
X541056Y503797D01*
X540556Y504047D01*
X539972Y504130D01*
X539306Y503964D01*
X538889Y503630D01*
X538556Y503047D01*
X538389Y502464D01*
X538472Y501964D01*
X538806Y501380D01*
X539306Y500964D01*
X539972Y500797D01*
X540472Y500880D01*
X541056Y501214D01*
X541389Y501547D01*
G01X544322Y499547D02*
X544906Y499214D01*
X545572Y499130D01*
X546156Y499214D01*
X546656Y499630D01*
X546989Y500214D01*
Y504130D01*
G01Y503464D02*
X546656Y503797D01*
X546156Y504047D01*
X545572Y504130D01*
X544906Y503964D01*
X544489Y503630D01*
X544156Y503047D01*
X543989Y502464D01*
X544072Y501964D01*
X544406Y501380D01*
X544906Y500964D01*
X545572Y500797D01*
X546072Y500880D01*
X546656Y501214D01*
X546989Y501547D01*
G01X551089Y504130D02*
Y500797D01*
G01Y505464D02*
X550922Y505547D01*
Y505714D01*
X551089Y505797D01*
X551256Y505714D01*
Y505547D01*
X551089Y505464D01*
G01X555272Y500797D02*
Y504130D01*
G01Y503297D02*
X555606Y503714D01*
X556106Y504047D01*
X556772Y504130D01*
X557356Y504047D01*
X557856Y503714D01*
X558106Y503130D01*
Y500797D01*
G01X561122Y499547D02*
X561706Y499214D01*
X562372Y499130D01*
X562956Y499214D01*
X563456Y499630D01*
X563789Y500214D01*
Y504130D01*
G01Y503464D02*
X563456Y503797D01*
X562956Y504047D01*
X562372Y504130D01*
X561706Y503964D01*
X561289Y503630D01*
X560956Y503047D01*
X560789Y502464D01*
X560872Y501964D01*
X561206Y501380D01*
X561706Y500964D01*
X562372Y500797D01*
X562872Y500880D01*
X563456Y501214D01*
X563789Y501547D01*
G01X521589Y562277D02*
Y557277D01*
G01X519672Y562277D02*
X523506D01*
G01X525106Y560610D02*
X526106Y557277D01*
X527189Y560610D01*
X528272Y557277D01*
X529272Y560610D01*
G01X532789D02*
Y557277D01*
G01Y561944D02*
X532622Y562027D01*
Y562194D01*
X532789Y562277D01*
X532956Y562194D01*
Y562027D01*
X532789Y561944D01*
G01X537139Y557860D02*
X537556Y557527D01*
X538139Y557277D01*
X538639D01*
X539139Y557444D01*
X539472Y557694D01*
X539639Y558027D01*
X539556Y558527D01*
X539222Y558777D01*
X537722Y559277D01*
X537389Y559860D01*
X537556Y560277D01*
X537889Y560527D01*
X538389Y560610D01*
X538889Y560527D01*
X539389Y560277D01*
G01X543989Y562277D02*
Y557277D01*
G01X542822Y560610D02*
X545156D01*
G01X556689Y557277D02*
Y560610D01*
G01Y560027D02*
X556356Y560360D01*
X555856Y560527D01*
X555272Y560610D01*
X554689Y560444D01*
X554189Y560110D01*
X553856Y559610D01*
X553689Y558944D01*
X553856Y558277D01*
X554189Y557777D01*
X554689Y557444D01*
X555272Y557277D01*
X555856Y557360D01*
X556356Y557610D01*
X556689Y557944D01*
G01X559372Y557277D02*
Y560610D01*
G01Y559777D02*
X559706Y560194D01*
X560206Y560527D01*
X560872Y560610D01*
X561456Y560527D01*
X561956Y560194D01*
X562206Y559610D01*
Y557277D01*
G01X567889Y562277D02*
Y557277D01*
G01Y558027D02*
X567556Y557610D01*
X567056Y557360D01*
X566472Y557277D01*
X565806Y557444D01*
X565306Y557860D01*
X564972Y558360D01*
X564889Y558944D01*
X564972Y559527D01*
X565306Y560027D01*
X565806Y560444D01*
X566472Y560610D01*
X567056Y560527D01*
X567472Y560360D01*
X567889Y560027D01*
G01X576089Y557277D02*
Y562277D01*
G01Y559777D02*
X576506Y560277D01*
X577006Y560527D01*
X577506Y560610D01*
X578256Y560444D01*
X578756Y560110D01*
X579089Y559527D01*
Y558860D01*
X578922Y558194D01*
X578589Y557694D01*
X578006Y557360D01*
X577506Y557277D01*
X577006Y557360D01*
X576506Y557610D01*
X576089Y558027D01*
G01X583189Y557277D02*
X582689Y557360D01*
X582189Y557694D01*
X581856Y558277D01*
X581689Y558944D01*
X581856Y559610D01*
X582189Y560194D01*
X582689Y560527D01*
X583189Y560610D01*
X583689Y560527D01*
X584189Y560194D01*
X584522Y559610D01*
X584606Y558944D01*
X584522Y558277D01*
X584189Y557694D01*
X583689Y557360D01*
X583189Y557277D01*
G01X586706Y560610D02*
X587706Y557277D01*
X588789Y560610D01*
X589872Y557277D01*
X590872Y560610D01*
G01X513589Y616907D02*
Y548407D01*
G01X523089Y577797D02*
X524756D01*
Y576297D01*
X524256Y575797D01*
X523672Y575464D01*
X522839Y575297D01*
X522006Y575464D01*
X521422Y575797D01*
X520922Y576297D01*
X520589Y576880D01*
X520422Y577547D01*
Y578130D01*
X520589Y578630D01*
X520922Y579214D01*
X521422Y579714D01*
X521922Y580047D01*
X522589Y580297D01*
X523172D01*
X523839Y580130D01*
X524339Y579797D01*
G01X526689Y575130D02*
X529689Y580297D01*
G01X532206Y575297D02*
Y580297D01*
X535372D01*
G01X534206Y577880D02*
X532206D01*
G01X543239Y575964D02*
X543906Y575547D01*
X544656Y575297D01*
X545322D01*
X545989Y575547D01*
X546489Y575964D01*
X546739Y576547D01*
X546572Y577130D01*
X546156Y577630D01*
X545406Y577964D01*
X544406Y578130D01*
X543822Y578464D01*
X543572Y579047D01*
X543739Y579630D01*
X544156Y580047D01*
X544739Y580297D01*
X545322D01*
X545906Y580130D01*
X546406Y579714D01*
G01X550589Y575297D02*
Y580297D01*
G01X556189Y575297D02*
X555689Y575380D01*
X555189Y575714D01*
X554856Y576297D01*
X554689Y576964D01*
X554856Y577630D01*
X555189Y578214D01*
X555689Y578547D01*
X556189Y578630D01*
X556689Y578547D01*
X557189Y578214D01*
X557522Y577630D01*
X557606Y576964D01*
X557522Y576297D01*
X557189Y575714D01*
X556689Y575380D01*
X556189Y575297D01*
G01X561789Y580297D02*
Y575297D01*
G01X560622Y578630D02*
X562956D01*
G01X521339Y592547D02*
X524006D01*
X523756Y593130D01*
X523339Y593464D01*
X522756Y593630D01*
X522172Y593547D01*
X521672Y593297D01*
X521339Y592714D01*
X521172Y592214D01*
Y591714D01*
X521339Y591214D01*
X521756Y590714D01*
X522256Y590380D01*
X522839Y590297D01*
X523422Y590464D01*
X524006Y590964D01*
G01X529689Y595297D02*
Y590297D01*
G01Y591047D02*
X529356Y590630D01*
X528856Y590380D01*
X528272Y590297D01*
X527606Y590464D01*
X527106Y590880D01*
X526772Y591380D01*
X526689Y591964D01*
X526772Y592547D01*
X527106Y593047D01*
X527606Y593464D01*
X528272Y593630D01*
X528856Y593547D01*
X529272Y593380D01*
X529689Y593047D01*
G01X532622Y589047D02*
X533206Y588714D01*
X533872Y588630D01*
X534456Y588714D01*
X534956Y589130D01*
X535289Y589714D01*
Y593630D01*
G01Y592964D02*
X534956Y593297D01*
X534456Y593547D01*
X533872Y593630D01*
X533206Y593464D01*
X532789Y593130D01*
X532456Y592547D01*
X532289Y591964D01*
X532372Y591464D01*
X532706Y590880D01*
X533206Y590464D01*
X533872Y590297D01*
X534372Y590380D01*
X534956Y590714D01*
X535289Y591047D01*
G01X538139Y592547D02*
X540806D01*
X540556Y593130D01*
X540139Y593464D01*
X539556Y593630D01*
X538972Y593547D01*
X538472Y593297D01*
X538139Y592714D01*
X537972Y592214D01*
Y591714D01*
X538139Y591214D01*
X538556Y590714D01*
X539056Y590380D01*
X539639Y590297D01*
X540222Y590464D01*
X540806Y590964D01*
G01X550589Y595297D02*
Y590297D01*
G01X549422Y593630D02*
X551756D01*
G01X556189Y590297D02*
X555689Y590380D01*
X555189Y590714D01*
X554856Y591297D01*
X554689Y591964D01*
X554856Y592630D01*
X555189Y593214D01*
X555689Y593547D01*
X556189Y593630D01*
X556689Y593547D01*
X557189Y593214D01*
X557522Y592630D01*
X557606Y591964D01*
X557522Y591297D01*
X557189Y590714D01*
X556689Y590380D01*
X556189Y590297D01*
G01X565972D02*
Y595297D01*
G01Y592880D02*
X566389Y593297D01*
X566806Y593547D01*
X567472Y593630D01*
X567972Y593547D01*
X568556Y593214D01*
X568806Y592714D01*
Y590297D01*
G01X572989D02*
X572489Y590380D01*
X571989Y590714D01*
X571656Y591297D01*
X571489Y591964D01*
X571656Y592630D01*
X571989Y593214D01*
X572489Y593547D01*
X572989Y593630D01*
X573489Y593547D01*
X573989Y593214D01*
X574322Y592630D01*
X574406Y591964D01*
X574322Y591297D01*
X573989Y590714D01*
X573489Y590380D01*
X572989Y590297D01*
G01X578589D02*
Y595297D01*
G01X582939Y592547D02*
X585606D01*
X585356Y593130D01*
X584939Y593464D01*
X584356Y593630D01*
X583772Y593547D01*
X583272Y593297D01*
X582939Y592714D01*
X582772Y592214D01*
Y591714D01*
X582939Y591214D01*
X583356Y590714D01*
X583856Y590380D01*
X584439Y590297D01*
X585022Y590464D01*
X585606Y590964D01*
G01X514089Y585797D02*
X908589D01*
G01X514089Y600797D02*
X908589D01*
G01X521339Y609047D02*
X524006D01*
X523756Y609630D01*
X523339Y609964D01*
X522756Y610130D01*
X522172Y610047D01*
X521672Y609797D01*
X521339Y609214D01*
X521172Y608714D01*
Y608214D01*
X521339Y607714D01*
X521756Y607214D01*
X522256Y606880D01*
X522839Y606797D01*
X523422Y606964D01*
X524006Y607464D01*
G01X529689Y611797D02*
Y606797D01*
G01Y607547D02*
X529356Y607130D01*
X528856Y606880D01*
X528272Y606797D01*
X527606Y606964D01*
X527106Y607380D01*
X526772Y607880D01*
X526689Y608464D01*
X526772Y609047D01*
X527106Y609547D01*
X527606Y609964D01*
X528272Y610130D01*
X528856Y610047D01*
X529272Y609880D01*
X529689Y609547D01*
G01X532622Y605547D02*
X533206Y605214D01*
X533872Y605130D01*
X534456Y605214D01*
X534956Y605630D01*
X535289Y606214D01*
Y610130D01*
G01Y609464D02*
X534956Y609797D01*
X534456Y610047D01*
X533872Y610130D01*
X533206Y609964D01*
X532789Y609630D01*
X532456Y609047D01*
X532289Y608464D01*
X532372Y607964D01*
X532706Y607380D01*
X533206Y606964D01*
X533872Y606797D01*
X534372Y606880D01*
X534956Y607214D01*
X535289Y607547D01*
G01X538139Y609047D02*
X540806D01*
X540556Y609630D01*
X540139Y609964D01*
X539556Y610130D01*
X538972Y610047D01*
X538472Y609797D01*
X538139Y609214D01*
X537972Y608714D01*
Y608214D01*
X538139Y607714D01*
X538556Y607214D01*
X539056Y606880D01*
X539639Y606797D01*
X540222Y606964D01*
X540806Y607464D01*
G01X550589Y611797D02*
Y606797D01*
G01X549422Y610130D02*
X551756D01*
G01X556189Y606797D02*
X555689Y606880D01*
X555189Y607214D01*
X554856Y607797D01*
X554689Y608464D01*
X554856Y609130D01*
X555189Y609714D01*
X555689Y610047D01*
X556189Y610130D01*
X556689Y610047D01*
X557189Y609714D01*
X557522Y609130D01*
X557606Y608464D01*
X557522Y607797D01*
X557189Y607214D01*
X556689Y606880D01*
X556189Y606797D01*
G01X566139Y609047D02*
X568806D01*
X568556Y609630D01*
X568139Y609964D01*
X567556Y610130D01*
X566972Y610047D01*
X566472Y609797D01*
X566139Y609214D01*
X565972Y608714D01*
Y608214D01*
X566139Y607714D01*
X566556Y607214D01*
X567056Y606880D01*
X567639Y606797D01*
X568222Y606964D01*
X568806Y607464D01*
G01X574489Y611797D02*
Y606797D01*
G01Y607547D02*
X574156Y607130D01*
X573656Y606880D01*
X573072Y606797D01*
X572406Y606964D01*
X571906Y607380D01*
X571572Y607880D01*
X571489Y608464D01*
X571572Y609047D01*
X571906Y609547D01*
X572406Y609964D01*
X573072Y610130D01*
X573656Y610047D01*
X574072Y609880D01*
X574489Y609547D01*
G01X577422Y605547D02*
X578006Y605214D01*
X578672Y605130D01*
X579256Y605214D01*
X579756Y605630D01*
X580089Y606214D01*
Y610130D01*
G01Y609464D02*
X579756Y609797D01*
X579256Y610047D01*
X578672Y610130D01*
X578006Y609964D01*
X577589Y609630D01*
X577256Y609047D01*
X577089Y608464D01*
X577172Y607964D01*
X577506Y607380D01*
X578006Y606964D01*
X578672Y606797D01*
X579172Y606880D01*
X579756Y607214D01*
X580089Y607547D01*
G01X582939Y609047D02*
X585606D01*
X585356Y609630D01*
X584939Y609964D01*
X584356Y610130D01*
X583772Y610047D01*
X583272Y609797D01*
X582939Y609214D01*
X582772Y608714D01*
Y608214D01*
X582939Y607714D01*
X583356Y607214D01*
X583856Y606880D01*
X584439Y606797D01*
X585022Y606964D01*
X585606Y607464D01*
G01X546256Y-217203D02*
X542922D01*
Y-212203D01*
X546256D01*
G01X544922Y-214620D02*
X542922D01*
G01X548939Y-213870D02*
X551439Y-217203D01*
G01Y-213870D02*
X548939Y-217203D01*
G01X555789Y-217370D02*
X555622Y-217286D01*
Y-217120D01*
X555789Y-217036D01*
X555956Y-217120D01*
Y-217286D01*
X555789Y-217370D01*
G01X559639Y-217203D02*
Y-212203D01*
G01X563139D02*
Y-217203D01*
G01Y-214703D02*
X559639D01*
G01X565322Y-217203D02*
Y-212203D01*
X567406D01*
X568072Y-212453D01*
X568489Y-212786D01*
X568656Y-213453D01*
X568489Y-214120D01*
X567989Y-214536D01*
X567406Y-214786D01*
X565322D01*
G01X567406D02*
X568656Y-217203D01*
G01X574256D02*
X570922D01*
Y-212203D01*
X574256D01*
G01X572922Y-214620D02*
X570922D01*
G01X579189Y-217203D02*
Y-212203D01*
X576106Y-215786D01*
X580272D01*
G01X581956Y-216453D02*
X582456Y-216870D01*
X583039Y-217120D01*
X583789Y-217203D01*
X584539Y-217036D01*
X585122Y-216703D01*
X585539Y-216120D01*
X585622Y-215453D01*
X585456Y-214786D01*
X585039Y-214370D01*
X584456Y-214036D01*
X583872Y-213953D01*
X583289Y-214036D01*
X582539Y-214370D01*
X582789Y-212203D01*
X585039D01*
G01X587639Y-217203D02*
X591139Y-212203D01*
G01X587639D02*
X591139Y-217203D01*
G01X593572Y-216620D02*
X594156Y-217036D01*
X594822Y-217203D01*
X595489Y-217036D01*
X596072Y-216536D01*
X596489Y-215786D01*
X596656Y-215036D01*
Y-214120D01*
X596489Y-213370D01*
X596072Y-212703D01*
X595572Y-212370D01*
X594989Y-212203D01*
X594322Y-212370D01*
X593822Y-212703D01*
X593489Y-213203D01*
X593322Y-213870D01*
X593489Y-214453D01*
X593906Y-215036D01*
X594406Y-215370D01*
X594989Y-215453D01*
X595656Y-215286D01*
X596156Y-214870D01*
X596656Y-214120D01*
G01X599006Y-215120D02*
X599589Y-214536D01*
X600089Y-214203D01*
X600756Y-214036D01*
X601339Y-214203D01*
X601756Y-214536D01*
X602089Y-215036D01*
X602172Y-215620D01*
X602089Y-216120D01*
X601756Y-216620D01*
X601256Y-217036D01*
X600672Y-217203D01*
X600006Y-217036D01*
X599422Y-216536D01*
X599089Y-215786D01*
X599006Y-214953D01*
X599172Y-213870D01*
X599422Y-213286D01*
X599839Y-212703D01*
X600422Y-212286D01*
X601006Y-212203D01*
X601589Y-212370D01*
X602006Y-212786D01*
G01X605772Y-218870D02*
X604939Y-218036D01*
X604522Y-217203D01*
Y-213870D01*
X604939Y-213036D01*
X605772Y-212203D01*
G01X609956Y-217203D02*
Y-212203D01*
X611622D01*
X612289Y-212453D01*
X612789Y-212786D01*
X613206Y-213286D01*
X613539Y-213870D01*
X613622Y-214703D01*
X613539Y-215536D01*
X613206Y-216120D01*
X612789Y-216620D01*
X612289Y-216953D01*
X611622Y-217203D01*
X609956D01*
G01X617389D02*
Y-212203D01*
X616389Y-213203D01*
G01Y-217203D02*
X618389D01*
G01X621406Y-215120D02*
X621989Y-214536D01*
X622489Y-214203D01*
X623156Y-214036D01*
X623739Y-214203D01*
X624156Y-214536D01*
X624489Y-215036D01*
X624572Y-215620D01*
X624489Y-216120D01*
X624156Y-216620D01*
X623656Y-217036D01*
X623072Y-217203D01*
X622406Y-217036D01*
X621822Y-216536D01*
X621489Y-215786D01*
X621406Y-214953D01*
X621572Y-213870D01*
X621822Y-213286D01*
X622239Y-212703D01*
X622822Y-212286D01*
X623406Y-212203D01*
X623989Y-212370D01*
X624406Y-212786D01*
G01X626839Y-217203D02*
X630339Y-212203D01*
G01X626839D02*
X630339Y-217203D01*
G01X635189D02*
Y-212203D01*
X632106Y-215786D01*
X636272D01*
G01X640206Y-218870D02*
X641039Y-218036D01*
X641456Y-217203D01*
Y-213870D01*
X641039Y-213036D01*
X640206Y-212203D01*
G01X542922Y-168203D02*
Y-163203D01*
X545006D01*
X545672Y-163453D01*
X546089Y-163786D01*
X546256Y-164453D01*
X546089Y-165120D01*
X545589Y-165536D01*
X545006Y-165786D01*
X542922D01*
G01X545006D02*
X546256Y-168203D01*
G01X551856D02*
X548522D01*
Y-163203D01*
X551856D01*
G01X550522Y-165620D02*
X548522D01*
G01X557622Y-163620D02*
X557122Y-163370D01*
X556539Y-163203D01*
X555872D01*
X555122Y-163453D01*
X554539Y-163870D01*
X554122Y-164370D01*
X553789Y-165203D01*
X553706Y-165953D01*
X553872Y-166703D01*
X554122Y-167203D01*
X554622Y-167703D01*
X555206Y-168036D01*
X555789Y-168203D01*
X556372D01*
X556956Y-168036D01*
X557456Y-167786D01*
X557872Y-167453D01*
G01X561389Y-163203D02*
Y-168203D01*
G01X559472Y-163203D02*
X563306D01*
G01X564906Y-168203D02*
X566989Y-163203D01*
X569072Y-168203D01*
G01X568322Y-166453D02*
X565656D01*
G01X570672Y-168203D02*
Y-163203D01*
X574506Y-168203D01*
Y-163203D01*
G01X578689Y-165703D02*
X580356D01*
Y-167203D01*
X579856Y-167703D01*
X579272Y-168036D01*
X578439Y-168203D01*
X577606Y-168036D01*
X577022Y-167703D01*
X576522Y-167203D01*
X576189Y-166620D01*
X576022Y-165953D01*
Y-165370D01*
X576189Y-164870D01*
X576522Y-164286D01*
X577022Y-163786D01*
X577522Y-163453D01*
X578189Y-163203D01*
X578772D01*
X579439Y-163370D01*
X579939Y-163703D01*
G01X582122Y-163203D02*
Y-168203D01*
X585456D01*
G01X591056D02*
X587722D01*
Y-163203D01*
X591056D01*
G01X589722Y-165620D02*
X587722D01*
G01X598756Y-168203D02*
Y-163203D01*
X600422D01*
X601089Y-163453D01*
X601589Y-163786D01*
X602006Y-164286D01*
X602339Y-164870D01*
X602422Y-165703D01*
X602339Y-166536D01*
X602006Y-167120D01*
X601589Y-167620D01*
X601089Y-167953D01*
X600422Y-168203D01*
X598756D01*
G01X604522D02*
Y-163203D01*
X606606D01*
X607272Y-163453D01*
X607689Y-163786D01*
X607856Y-164453D01*
X607689Y-165120D01*
X607189Y-165536D01*
X606606Y-165786D01*
X604522D01*
G01X606606D02*
X607856Y-168203D01*
G01X610789Y-163203D02*
X612789D01*
G01X611789D02*
Y-168203D01*
G01X610789D02*
X612789D01*
G01X615722Y-163203D02*
Y-168203D01*
X619056D01*
G01X621322Y-163203D02*
Y-168203D01*
X624656D01*
G01X632439D02*
Y-163203D01*
G01X635939D02*
Y-168203D01*
G01Y-165703D02*
X632439D01*
G01X639789Y-168203D02*
X639122Y-168120D01*
X638539Y-167786D01*
X638039Y-167286D01*
X637706Y-166703D01*
X637539Y-166036D01*
Y-165370D01*
X637706Y-164703D01*
X638039Y-164120D01*
X638539Y-163620D01*
X639122Y-163286D01*
X639789Y-163203D01*
X640456Y-163286D01*
X641039Y-163620D01*
X641539Y-164120D01*
X641872Y-164703D01*
X642039Y-165370D01*
Y-166036D01*
X641872Y-166703D01*
X641539Y-167286D01*
X641039Y-167786D01*
X640456Y-168120D01*
X639789Y-168203D01*
G01X643722Y-163203D02*
Y-168203D01*
X647056D01*
G01X652656D02*
X649322D01*
Y-163203D01*
X652656D01*
G01X651322Y-165620D02*
X649322D01*
G01X660356Y-168203D02*
Y-163203D01*
X662022D01*
X662689Y-163453D01*
X663189Y-163786D01*
X663606Y-164286D01*
X663939Y-164870D01*
X664022Y-165703D01*
X663939Y-166536D01*
X663606Y-167120D01*
X663189Y-167620D01*
X662689Y-167953D01*
X662022Y-168203D01*
X660356D01*
G01X669456D02*
X666122D01*
Y-163203D01*
X669456D01*
G01X668122Y-165620D02*
X666122D01*
G01X671806Y-168203D02*
Y-163203D01*
X674972D01*
G01X673806Y-165620D02*
X671806D01*
G01X677989Y-163203D02*
X679989D01*
G01X678989D02*
Y-168203D01*
G01X677989D02*
X679989D01*
G01X682672D02*
Y-163203D01*
X686506Y-168203D01*
Y-163203D01*
G01X691856Y-168203D02*
X688522D01*
Y-163203D01*
X691856D01*
G01X690522Y-165620D02*
X688522D01*
G01X561256Y-228203D02*
Y-223203D01*
X562922D01*
X563589Y-223453D01*
X564089Y-223786D01*
X564506Y-224286D01*
X564839Y-224870D01*
X564922Y-225703D01*
X564839Y-226536D01*
X564506Y-227120D01*
X564089Y-227620D01*
X563589Y-227953D01*
X562922Y-228203D01*
X561256D01*
G01X568689D02*
Y-223203D01*
X567689Y-224203D01*
G01Y-228203D02*
X569689D01*
G01X572706Y-226120D02*
X573289Y-225536D01*
X573789Y-225203D01*
X574456Y-225036D01*
X575039Y-225203D01*
X575456Y-225536D01*
X575789Y-226036D01*
X575872Y-226620D01*
X575789Y-227120D01*
X575456Y-227620D01*
X574956Y-228036D01*
X574372Y-228203D01*
X573706Y-228036D01*
X573122Y-227536D01*
X572789Y-226786D01*
X572706Y-225953D01*
X572872Y-224870D01*
X573122Y-224286D01*
X573539Y-223703D01*
X574122Y-223286D01*
X574706Y-223203D01*
X575289Y-223370D01*
X575706Y-223786D01*
G01X579889Y-228370D02*
X579722Y-228286D01*
Y-228120D01*
X579889Y-228036D01*
X580056Y-228120D01*
Y-228286D01*
X579889Y-228370D01*
G01Y-226120D02*
X579722Y-226036D01*
Y-225870D01*
X579889Y-225786D01*
X580056Y-225870D01*
Y-226036D01*
X579889Y-226120D01*
G01X583656Y-228203D02*
Y-223203D01*
X585322D01*
X585989Y-223453D01*
X586489Y-223786D01*
X586906Y-224286D01*
X587239Y-224870D01*
X587322Y-225703D01*
X587239Y-226536D01*
X586906Y-227120D01*
X586489Y-227620D01*
X585989Y-227953D01*
X585322Y-228203D01*
X583656D01*
G01X591089Y-224870D02*
Y-228203D01*
G01Y-223536D02*
X590922Y-223453D01*
Y-223286D01*
X591089Y-223203D01*
X591256Y-223286D01*
Y-223453D01*
X591089Y-223536D01*
G01X598189Y-228203D02*
Y-224870D01*
G01Y-225453D02*
X597856Y-225120D01*
X597356Y-224953D01*
X596772Y-224870D01*
X596189Y-225036D01*
X595689Y-225370D01*
X595356Y-225870D01*
X595189Y-226536D01*
X595356Y-227203D01*
X595689Y-227703D01*
X596189Y-228036D01*
X596772Y-228203D01*
X597356Y-228120D01*
X597856Y-227870D01*
X598189Y-227536D01*
G01X599789Y-228203D02*
Y-224870D01*
G01Y-225786D02*
X600039Y-225370D01*
X600456Y-225036D01*
X601039Y-224870D01*
X601622Y-225036D01*
X602039Y-225370D01*
X602289Y-225786D01*
Y-228203D01*
G01Y-225786D02*
X602539Y-225370D01*
X602956Y-225036D01*
X603539Y-224870D01*
X604122Y-225036D01*
X604539Y-225370D01*
X604789Y-225870D01*
Y-228203D01*
G01X606639Y-225953D02*
X609306D01*
X609056Y-225370D01*
X608639Y-225036D01*
X608056Y-224870D01*
X607472Y-224953D01*
X606972Y-225203D01*
X606639Y-225786D01*
X606472Y-226286D01*
Y-226786D01*
X606639Y-227286D01*
X607056Y-227786D01*
X607556Y-228120D01*
X608139Y-228203D01*
X608722Y-228036D01*
X609306Y-227536D01*
G01X613489Y-223203D02*
Y-228203D01*
G01X612322Y-224870D02*
X614656D01*
G01X617839Y-225953D02*
X620506D01*
X620256Y-225370D01*
X619839Y-225036D01*
X619256Y-224870D01*
X618672Y-224953D01*
X618172Y-225203D01*
X617839Y-225786D01*
X617672Y-226286D01*
Y-226786D01*
X617839Y-227286D01*
X618256Y-227786D01*
X618756Y-228120D01*
X619339Y-228203D01*
X619922Y-228036D01*
X620506Y-227536D01*
G01X623522Y-228203D02*
Y-224870D01*
G01Y-225536D02*
X623939Y-225203D01*
X624356Y-224953D01*
X624939Y-224870D01*
X625356Y-224953D01*
X625856Y-225203D01*
G01X635889Y-228203D02*
Y-223203D01*
X634889Y-224203D01*
G01Y-228203D02*
X636889D01*
G01X639906Y-226120D02*
X640489Y-225536D01*
X640989Y-225203D01*
X641656Y-225036D01*
X642239Y-225203D01*
X642656Y-225536D01*
X642989Y-226036D01*
X643072Y-226620D01*
X642989Y-227120D01*
X642656Y-227620D01*
X642156Y-228036D01*
X641572Y-228203D01*
X640906Y-228036D01*
X640322Y-227536D01*
X639989Y-226786D01*
X639906Y-225953D01*
X640072Y-224870D01*
X640322Y-224286D01*
X640739Y-223703D01*
X641322Y-223286D01*
X641906Y-223203D01*
X642489Y-223370D01*
X642906Y-223786D01*
G01X644589Y-228203D02*
Y-224870D01*
G01Y-225786D02*
X644839Y-225370D01*
X645256Y-225036D01*
X645839Y-224870D01*
X646422Y-225036D01*
X646839Y-225370D01*
X647089Y-225786D01*
Y-228203D01*
G01Y-225786D02*
X647339Y-225370D01*
X647756Y-225036D01*
X648339Y-224870D01*
X648922Y-225036D01*
X649339Y-225370D01*
X649589Y-225870D01*
Y-228203D01*
G01X652689Y-224870D02*
Y-228203D01*
G01Y-223536D02*
X652522Y-223453D01*
Y-223286D01*
X652689Y-223203D01*
X652856Y-223286D01*
Y-223453D01*
X652689Y-223536D01*
G01X658289Y-228203D02*
Y-223203D01*
G01X591589Y102297D02*
Y-147703D01*
G01X587006Y149964D02*
X587506Y150464D01*
X588089Y150714D01*
X588756Y150797D01*
X589589Y150630D01*
X590172Y150214D01*
X590339Y149714D01*
X590256Y149214D01*
X589922Y148797D01*
X588256Y147964D01*
X587506Y147380D01*
X587006Y146547D01*
X586839Y145797D01*
X590339D01*
G01X594189Y145630D02*
X594022Y145714D01*
Y145880D01*
X594189Y145964D01*
X594356Y145880D01*
Y145714D01*
X594189Y145630D01*
G01X597706Y150797D02*
X599789Y145797D01*
X601872Y150797D01*
G01X605389Y149130D02*
Y145797D01*
G01Y150464D02*
X605222Y150547D01*
Y150714D01*
X605389Y150797D01*
X605556Y150714D01*
Y150547D01*
X605389Y150464D01*
G01X612489Y145797D02*
Y149130D01*
G01Y148547D02*
X612156Y148880D01*
X611656Y149047D01*
X611072Y149130D01*
X610489Y148964D01*
X609989Y148630D01*
X609656Y148130D01*
X609489Y147464D01*
X609656Y146797D01*
X609989Y146297D01*
X610489Y145964D01*
X611072Y145797D01*
X611656Y145880D01*
X612156Y146130D01*
X612489Y146464D01*
G01X620939Y146380D02*
X621356Y146047D01*
X621939Y145797D01*
X622439D01*
X622939Y145964D01*
X623272Y146214D01*
X623439Y146547D01*
X623356Y147047D01*
X623022Y147297D01*
X621522Y147797D01*
X621189Y148380D01*
X621356Y148797D01*
X621689Y149047D01*
X622189Y149130D01*
X622689Y149047D01*
X623189Y148797D01*
G01X626372Y145797D02*
Y150797D01*
G01Y148380D02*
X626789Y148797D01*
X627206Y149047D01*
X627872Y149130D01*
X628372Y149047D01*
X628956Y148714D01*
X629206Y148214D01*
Y145797D01*
G01X633389D02*
X632889Y145880D01*
X632389Y146214D01*
X632056Y146797D01*
X631889Y147464D01*
X632056Y148130D01*
X632389Y148714D01*
X632889Y149047D01*
X633389Y149130D01*
X633889Y149047D01*
X634389Y148714D01*
X634722Y148130D01*
X634806Y147464D01*
X634722Y146797D01*
X634389Y146214D01*
X633889Y145880D01*
X633389Y145797D01*
G01X637572Y149130D02*
Y146797D01*
X637906Y146214D01*
X638406Y145880D01*
X638989Y145797D01*
X639572Y145880D01*
X640072Y146214D01*
X640406Y146797D01*
G01Y145797D02*
Y149130D01*
G01X644589Y145797D02*
Y150797D01*
G01X651689D02*
Y145797D01*
G01Y146547D02*
X651356Y146130D01*
X650856Y145880D01*
X650272Y145797D01*
X649606Y145964D01*
X649106Y146380D01*
X648772Y146880D01*
X648689Y147464D01*
X648772Y148047D01*
X649106Y148547D01*
X649606Y148964D01*
X650272Y149130D01*
X650856Y149047D01*
X651272Y148880D01*
X651689Y148547D01*
G01X659889Y145797D02*
Y150797D01*
G01Y148297D02*
X660306Y148797D01*
X660806Y149047D01*
X661306Y149130D01*
X662056Y148964D01*
X662556Y148630D01*
X662889Y148047D01*
Y147380D01*
X662722Y146714D01*
X662389Y146214D01*
X661806Y145880D01*
X661306Y145797D01*
X660806Y145880D01*
X660306Y146130D01*
X659889Y146547D01*
G01X665739Y148047D02*
X668406D01*
X668156Y148630D01*
X667739Y148964D01*
X667156Y149130D01*
X666572Y149047D01*
X666072Y148797D01*
X665739Y148214D01*
X665572Y147714D01*
Y147214D01*
X665739Y146714D01*
X666156Y146214D01*
X666656Y145880D01*
X667239Y145797D01*
X667822Y145964D01*
X668406Y146464D01*
G01X676689Y144130D02*
Y149130D01*
G01Y148380D02*
X677106Y148797D01*
X677522Y149047D01*
X678189Y149130D01*
X678772Y149047D01*
X679356Y148630D01*
X679606Y148047D01*
X679689Y147464D01*
X679606Y146880D01*
X679356Y146297D01*
X678856Y145964D01*
X678189Y145797D01*
X677606Y145880D01*
X677022Y146130D01*
X676689Y146464D01*
G01X683789Y145797D02*
Y150797D01*
G01X687972Y149130D02*
Y146797D01*
X688306Y146214D01*
X688806Y145880D01*
X689389Y145797D01*
X689972Y145880D01*
X690472Y146214D01*
X690806Y146797D01*
G01Y145797D02*
Y149130D01*
G01X693822Y144547D02*
X694406Y144214D01*
X695072Y144130D01*
X695656Y144214D01*
X696156Y144630D01*
X696489Y145214D01*
Y149130D01*
G01Y148464D02*
X696156Y148797D01*
X695656Y149047D01*
X695072Y149130D01*
X694406Y148964D01*
X693989Y148630D01*
X693656Y148047D01*
X693489Y147464D01*
X693572Y146964D01*
X693906Y146380D01*
X694406Y145964D01*
X695072Y145797D01*
X695572Y145880D01*
X696156Y146214D01*
X696489Y146547D01*
G01X699422Y144547D02*
X700006Y144214D01*
X700672Y144130D01*
X701256Y144214D01*
X701756Y144630D01*
X702089Y145214D01*
Y149130D01*
G01Y148464D02*
X701756Y148797D01*
X701256Y149047D01*
X700672Y149130D01*
X700006Y148964D01*
X699589Y148630D01*
X699256Y148047D01*
X699089Y147464D01*
X699172Y146964D01*
X699506Y146380D01*
X700006Y145964D01*
X700672Y145797D01*
X701172Y145880D01*
X701756Y146214D01*
X702089Y146547D01*
G01X704939Y148047D02*
X707606D01*
X707356Y148630D01*
X706939Y148964D01*
X706356Y149130D01*
X705772Y149047D01*
X705272Y148797D01*
X704939Y148214D01*
X704772Y147714D01*
Y147214D01*
X704939Y146714D01*
X705356Y146214D01*
X705856Y145880D01*
X706439Y145797D01*
X707022Y145964D01*
X707606Y146464D01*
G01X713289Y150797D02*
Y145797D01*
G01Y146547D02*
X712956Y146130D01*
X712456Y145880D01*
X711872Y145797D01*
X711206Y145964D01*
X710706Y146380D01*
X710372Y146880D01*
X710289Y147464D01*
X710372Y148047D01*
X710706Y148547D01*
X711206Y148964D01*
X711872Y149130D01*
X712456Y149047D01*
X712872Y148880D01*
X713289Y148547D01*
G01X720906Y149130D02*
X721906Y145797D01*
X722989Y149130D01*
X724072Y145797D01*
X725072Y149130D01*
G01X728589D02*
Y145797D01*
G01Y150464D02*
X728422Y150547D01*
Y150714D01*
X728589Y150797D01*
X728756Y150714D01*
Y150547D01*
X728589Y150464D01*
G01X734189Y150797D02*
Y145797D01*
G01X733022Y149130D02*
X735356D01*
G01X738372Y145797D02*
Y150797D01*
G01Y148380D02*
X738789Y148797D01*
X739206Y149047D01*
X739872Y149130D01*
X740372Y149047D01*
X740956Y148714D01*
X741206Y148214D01*
Y145797D01*
G01X749322D02*
X752656Y147464D01*
X749322Y149130D01*
G01X755172Y146380D02*
X755756Y145964D01*
X756422Y145797D01*
X757089Y145964D01*
X757672Y146464D01*
X758089Y147214D01*
X758256Y147964D01*
Y148880D01*
X758089Y149630D01*
X757672Y150297D01*
X757172Y150630D01*
X756589Y150797D01*
X755922Y150630D01*
X755422Y150297D01*
X755089Y149797D01*
X754922Y149130D01*
X755089Y148547D01*
X755506Y147964D01*
X756006Y147630D01*
X756589Y147547D01*
X757256Y147714D01*
X757756Y148130D01*
X758256Y148880D01*
G01X762189Y150797D02*
X761522Y150630D01*
X761022Y150214D01*
X760689Y149714D01*
X760439Y149047D01*
X760356Y148297D01*
X760439Y147547D01*
X760689Y146880D01*
X761022Y146380D01*
X761522Y145964D01*
X762189Y145797D01*
X762856Y145964D01*
X763356Y146380D01*
X763689Y146880D01*
X763939Y147547D01*
X764022Y148297D01*
X763939Y149047D01*
X763689Y149714D01*
X763356Y150214D01*
X762856Y150630D01*
X762189Y150797D01*
G01X766289Y145630D02*
X769289Y150797D01*
G01X766289D02*
X765789Y150630D01*
X765539Y150380D01*
X765372Y149880D01*
X765539Y149380D01*
X765789Y149130D01*
X766289Y148964D01*
X766789Y149130D01*
X767039Y149380D01*
X767206Y149880D01*
X767039Y150380D01*
X766789Y150630D01*
X766289Y150797D01*
G01X769289Y147464D02*
X768789Y147297D01*
X768539Y147047D01*
X768372Y146547D01*
X768539Y146047D01*
X768789Y145797D01*
X769289Y145630D01*
X769789Y145797D01*
X770039Y146047D01*
X770206Y146547D01*
X770039Y147047D01*
X769789Y147297D01*
X769289Y147464D01*
G01X777822Y145797D02*
Y149130D01*
G01Y148464D02*
X778239Y148797D01*
X778656Y149047D01*
X779239Y149130D01*
X779656Y149047D01*
X780156Y148797D01*
G01X783339Y148047D02*
X786006D01*
X785756Y148630D01*
X785339Y148964D01*
X784756Y149130D01*
X784172Y149047D01*
X783672Y148797D01*
X783339Y148214D01*
X783172Y147714D01*
Y147214D01*
X783339Y146714D01*
X783756Y146214D01*
X784256Y145880D01*
X784839Y145797D01*
X785422Y145964D01*
X786006Y146464D01*
G01X788939Y146380D02*
X789356Y146047D01*
X789939Y145797D01*
X790439D01*
X790939Y145964D01*
X791272Y146214D01*
X791439Y146547D01*
X791356Y147047D01*
X791022Y147297D01*
X789522Y147797D01*
X789189Y148380D01*
X789356Y148797D01*
X789689Y149047D01*
X790189Y149130D01*
X790689Y149047D01*
X791189Y148797D01*
G01X795789Y149130D02*
Y145797D01*
G01Y150464D02*
X795622Y150547D01*
Y150714D01*
X795789Y150797D01*
X795956Y150714D01*
Y150547D01*
X795789Y150464D01*
G01X799972Y145797D02*
Y149130D01*
G01Y148297D02*
X800306Y148714D01*
X800806Y149047D01*
X801472Y149130D01*
X802056Y149047D01*
X802556Y148714D01*
X802806Y148130D01*
Y145797D01*
G01X812006Y144297D02*
X813172Y145464D01*
Y146630D01*
X812006D01*
Y145464D01*
X813172D01*
G01Y147464D02*
Y148630D01*
X812006D01*
Y147464D01*
X813172D01*
G01X816356Y145797D02*
Y150797D01*
X818022D01*
X818689Y150547D01*
X819189Y150214D01*
X819606Y149714D01*
X819939Y149130D01*
X820022Y148297D01*
X819939Y147464D01*
X819606Y146880D01*
X819189Y146380D01*
X818689Y146047D01*
X818022Y145797D01*
X816356D01*
G01X823789D02*
X823289Y145880D01*
X822789Y146214D01*
X822456Y146797D01*
X822289Y147464D01*
X822456Y148130D01*
X822789Y148714D01*
X823289Y149047D01*
X823789Y149130D01*
X824289Y149047D01*
X824789Y148714D01*
X825122Y148130D01*
X825206Y147464D01*
X825122Y146797D01*
X824789Y146214D01*
X824289Y145880D01*
X823789Y145797D01*
G01X833572D02*
Y149130D01*
G01Y148297D02*
X833906Y148714D01*
X834406Y149047D01*
X835072Y149130D01*
X835656Y149047D01*
X836156Y148714D01*
X836406Y148130D01*
Y145797D01*
G01X840589D02*
X840089Y145880D01*
X839589Y146214D01*
X839256Y146797D01*
X839089Y147464D01*
X839256Y148130D01*
X839589Y148714D01*
X840089Y149047D01*
X840589Y149130D01*
X841089Y149047D01*
X841589Y148714D01*
X841922Y148130D01*
X842006Y147464D01*
X841922Y146797D01*
X841589Y146214D01*
X841089Y145880D01*
X840589Y145797D01*
G01X846189Y150797D02*
Y145797D01*
G01X845022Y149130D02*
X847356D01*
G01X858889Y145797D02*
Y149130D01*
G01Y148547D02*
X858556Y148880D01*
X858056Y149047D01*
X857472Y149130D01*
X856889Y148964D01*
X856389Y148630D01*
X856056Y148130D01*
X855889Y147464D01*
X856056Y146797D01*
X856389Y146297D01*
X856889Y145964D01*
X857472Y145797D01*
X858056Y145880D01*
X858556Y146130D01*
X858889Y146464D01*
G01X862989Y145797D02*
Y150797D01*
G01X868589Y145797D02*
Y150797D01*
G01X874189Y145797D02*
X873689Y145880D01*
X873189Y146214D01*
X872856Y146797D01*
X872689Y147464D01*
X872856Y148130D01*
X873189Y148714D01*
X873689Y149047D01*
X874189Y149130D01*
X874689Y149047D01*
X875189Y148714D01*
X875522Y148130D01*
X875606Y147464D01*
X875522Y146797D01*
X875189Y146214D01*
X874689Y145880D01*
X874189Y145797D01*
G01X877706Y149130D02*
X878706Y145797D01*
X879789Y149130D01*
X880872Y145797D01*
X881872Y149130D01*
G01X581589Y370797D02*
Y132297D01*
G01X588589Y156297D02*
Y161297D01*
X587589Y160297D01*
G01Y156297D02*
X589589D01*
G01X594189Y156130D02*
X594022Y156214D01*
Y156380D01*
X594189Y156464D01*
X594356Y156380D01*
Y156214D01*
X594189Y156130D01*
G01X597956Y156297D02*
Y161297D01*
X599622D01*
X600289Y161047D01*
X600789Y160714D01*
X601206Y160214D01*
X601539Y159630D01*
X601622Y158797D01*
X601539Y157964D01*
X601206Y157380D01*
X600789Y156880D01*
X600289Y156547D01*
X599622Y156297D01*
X597956D01*
G01X605389Y159630D02*
Y156297D01*
G01Y160964D02*
X605222Y161047D01*
Y161214D01*
X605389Y161297D01*
X605556Y161214D01*
Y161047D01*
X605389Y160964D01*
G01X608489Y156297D02*
Y159630D01*
G01Y158714D02*
X608739Y159130D01*
X609156Y159464D01*
X609739Y159630D01*
X610322Y159464D01*
X610739Y159130D01*
X610989Y158714D01*
Y156297D01*
G01Y158714D02*
X611239Y159130D01*
X611656Y159464D01*
X612239Y159630D01*
X612822Y159464D01*
X613239Y159130D01*
X613489Y158630D01*
Y156297D01*
G01X615089Y154630D02*
Y159630D01*
G01Y158880D02*
X615506Y159297D01*
X615922Y159547D01*
X616589Y159630D01*
X617172Y159547D01*
X617756Y159130D01*
X618006Y158547D01*
X618089Y157964D01*
X618006Y157380D01*
X617756Y156797D01*
X617256Y156464D01*
X616589Y156297D01*
X616006Y156380D01*
X615422Y156630D01*
X615089Y156964D01*
G01X622189Y156297D02*
Y161297D01*
G01X626539Y158547D02*
X629206D01*
X628956Y159130D01*
X628539Y159464D01*
X627956Y159630D01*
X627372Y159547D01*
X626872Y159297D01*
X626539Y158714D01*
X626372Y158214D01*
Y157714D01*
X626539Y157214D01*
X626956Y156714D01*
X627456Y156380D01*
X628039Y156297D01*
X628622Y156464D01*
X629206Y156964D01*
G01X640656Y156297D02*
X637322Y157964D01*
X640656Y159630D01*
G01X650189Y156297D02*
Y161297D01*
X649189Y160297D01*
G01Y156297D02*
X651189D01*
G01X658889D02*
Y159630D01*
G01Y158714D02*
X659139Y159130D01*
X659556Y159464D01*
X660139Y159630D01*
X660722Y159464D01*
X661139Y159130D01*
X661389Y158714D01*
Y156297D01*
G01Y158714D02*
X661639Y159130D01*
X662056Y159464D01*
X662639Y159630D01*
X663222Y159464D01*
X663639Y159130D01*
X663889Y158630D01*
Y156297D01*
G01X666989Y159630D02*
Y156297D01*
G01Y160964D02*
X666822Y161047D01*
Y161214D01*
X666989Y161297D01*
X667156Y161214D01*
Y161047D01*
X666989Y160964D01*
G01X672589Y156297D02*
Y161297D01*
G01X683206Y154797D02*
X684372Y155964D01*
Y157130D01*
X683206D01*
Y155964D01*
X684372D01*
G01Y157964D02*
Y159130D01*
X683206D01*
Y157964D01*
X684372D01*
G01X588589Y190297D02*
Y195297D01*
X587589Y194297D01*
G01Y190297D02*
X589589D01*
G01X594189Y190130D02*
X594022Y190214D01*
Y190380D01*
X594189Y190464D01*
X594356Y190380D01*
Y190214D01*
X594189Y190130D01*
G01X597706Y195297D02*
X599789Y190297D01*
X601872Y195297D01*
G01X605389Y193630D02*
Y190297D01*
G01Y194964D02*
X605222Y195047D01*
Y195214D01*
X605389Y195297D01*
X605556Y195214D01*
Y195047D01*
X605389Y194964D01*
G01X612489Y190297D02*
Y193630D01*
G01Y193047D02*
X612156Y193380D01*
X611656Y193547D01*
X611072Y193630D01*
X610489Y193464D01*
X609989Y193130D01*
X609656Y192630D01*
X609489Y191964D01*
X609656Y191297D01*
X609989Y190797D01*
X610489Y190464D01*
X611072Y190297D01*
X611656Y190380D01*
X612156Y190630D01*
X612489Y190964D01*
G01X620939Y190880D02*
X621356Y190547D01*
X621939Y190297D01*
X622439D01*
X622939Y190464D01*
X623272Y190714D01*
X623439Y191047D01*
X623356Y191547D01*
X623022Y191797D01*
X621522Y192297D01*
X621189Y192880D01*
X621356Y193297D01*
X621689Y193547D01*
X622189Y193630D01*
X622689Y193547D01*
X623189Y193297D01*
G01X626372Y190297D02*
Y195297D01*
G01Y192880D02*
X626789Y193297D01*
X627206Y193547D01*
X627872Y193630D01*
X628372Y193547D01*
X628956Y193214D01*
X629206Y192714D01*
Y190297D01*
G01X633389D02*
X632889Y190380D01*
X632389Y190714D01*
X632056Y191297D01*
X631889Y191964D01*
X632056Y192630D01*
X632389Y193214D01*
X632889Y193547D01*
X633389Y193630D01*
X633889Y193547D01*
X634389Y193214D01*
X634722Y192630D01*
X634806Y191964D01*
X634722Y191297D01*
X634389Y190714D01*
X633889Y190380D01*
X633389Y190297D01*
G01X637572Y193630D02*
Y191297D01*
X637906Y190714D01*
X638406Y190380D01*
X638989Y190297D01*
X639572Y190380D01*
X640072Y190714D01*
X640406Y191297D01*
G01Y190297D02*
Y193630D01*
G01X644589Y190297D02*
Y195297D01*
G01X651689D02*
Y190297D01*
G01Y191047D02*
X651356Y190630D01*
X650856Y190380D01*
X650272Y190297D01*
X649606Y190464D01*
X649106Y190880D01*
X648772Y191380D01*
X648689Y191964D01*
X648772Y192547D01*
X649106Y193047D01*
X649606Y193464D01*
X650272Y193630D01*
X650856Y193547D01*
X651272Y193380D01*
X651689Y193047D01*
G01X659889Y190297D02*
Y195297D01*
G01Y192797D02*
X660306Y193297D01*
X660806Y193547D01*
X661306Y193630D01*
X662056Y193464D01*
X662556Y193130D01*
X662889Y192547D01*
Y191880D01*
X662722Y191214D01*
X662389Y190714D01*
X661806Y190380D01*
X661306Y190297D01*
X660806Y190380D01*
X660306Y190630D01*
X659889Y191047D01*
G01X665739Y192547D02*
X668406D01*
X668156Y193130D01*
X667739Y193464D01*
X667156Y193630D01*
X666572Y193547D01*
X666072Y193297D01*
X665739Y192714D01*
X665572Y192214D01*
Y191714D01*
X665739Y191214D01*
X666156Y190714D01*
X666656Y190380D01*
X667239Y190297D01*
X667822Y190464D01*
X668406Y190964D01*
G01X676689Y188630D02*
Y193630D01*
G01Y192880D02*
X677106Y193297D01*
X677522Y193547D01*
X678189Y193630D01*
X678772Y193547D01*
X679356Y193130D01*
X679606Y192547D01*
X679689Y191964D01*
X679606Y191380D01*
X679356Y190797D01*
X678856Y190464D01*
X678189Y190297D01*
X677606Y190380D01*
X677022Y190630D01*
X676689Y190964D01*
G01X683789Y190297D02*
Y195297D01*
G01X687972Y193630D02*
Y191297D01*
X688306Y190714D01*
X688806Y190380D01*
X689389Y190297D01*
X689972Y190380D01*
X690472Y190714D01*
X690806Y191297D01*
G01Y190297D02*
Y193630D01*
G01X693822Y189047D02*
X694406Y188714D01*
X695072Y188630D01*
X695656Y188714D01*
X696156Y189130D01*
X696489Y189714D01*
Y193630D01*
G01Y192964D02*
X696156Y193297D01*
X695656Y193547D01*
X695072Y193630D01*
X694406Y193464D01*
X693989Y193130D01*
X693656Y192547D01*
X693489Y191964D01*
X693572Y191464D01*
X693906Y190880D01*
X694406Y190464D01*
X695072Y190297D01*
X695572Y190380D01*
X696156Y190714D01*
X696489Y191047D01*
G01X699422Y189047D02*
X700006Y188714D01*
X700672Y188630D01*
X701256Y188714D01*
X701756Y189130D01*
X702089Y189714D01*
Y193630D01*
G01Y192964D02*
X701756Y193297D01*
X701256Y193547D01*
X700672Y193630D01*
X700006Y193464D01*
X699589Y193130D01*
X699256Y192547D01*
X699089Y191964D01*
X699172Y191464D01*
X699506Y190880D01*
X700006Y190464D01*
X700672Y190297D01*
X701172Y190380D01*
X701756Y190714D01*
X702089Y191047D01*
G01X704939Y192547D02*
X707606D01*
X707356Y193130D01*
X706939Y193464D01*
X706356Y193630D01*
X705772Y193547D01*
X705272Y193297D01*
X704939Y192714D01*
X704772Y192214D01*
Y191714D01*
X704939Y191214D01*
X705356Y190714D01*
X705856Y190380D01*
X706439Y190297D01*
X707022Y190464D01*
X707606Y190964D01*
G01X713289Y195297D02*
Y190297D01*
G01Y191047D02*
X712956Y190630D01*
X712456Y190380D01*
X711872Y190297D01*
X711206Y190464D01*
X710706Y190880D01*
X710372Y191380D01*
X710289Y191964D01*
X710372Y192547D01*
X710706Y193047D01*
X711206Y193464D01*
X711872Y193630D01*
X712456Y193547D01*
X712872Y193380D01*
X713289Y193047D01*
G01X720906Y193630D02*
X721906Y190297D01*
X722989Y193630D01*
X724072Y190297D01*
X725072Y193630D01*
G01X728589D02*
Y190297D01*
G01Y194964D02*
X728422Y195047D01*
Y195214D01*
X728589Y195297D01*
X728756Y195214D01*
Y195047D01*
X728589Y194964D01*
G01X734189Y195297D02*
Y190297D01*
G01X733022Y193630D02*
X735356D01*
G01X738372Y190297D02*
Y195297D01*
G01Y192880D02*
X738789Y193297D01*
X739206Y193547D01*
X739872Y193630D01*
X740372Y193547D01*
X740956Y193214D01*
X741206Y192714D01*
Y190297D01*
G01X749322D02*
X752656Y191964D01*
X749322Y193630D01*
G01X755172Y190880D02*
X755756Y190464D01*
X756422Y190297D01*
X757089Y190464D01*
X757672Y190964D01*
X758089Y191714D01*
X758256Y192464D01*
Y193380D01*
X758089Y194130D01*
X757672Y194797D01*
X757172Y195130D01*
X756589Y195297D01*
X755922Y195130D01*
X755422Y194797D01*
X755089Y194297D01*
X754922Y193630D01*
X755089Y193047D01*
X755506Y192464D01*
X756006Y192130D01*
X756589Y192047D01*
X757256Y192214D01*
X757756Y192630D01*
X758256Y193380D01*
G01X762189Y195297D02*
X761522Y195130D01*
X761022Y194714D01*
X760689Y194214D01*
X760439Y193547D01*
X760356Y192797D01*
X760439Y192047D01*
X760689Y191380D01*
X761022Y190880D01*
X761522Y190464D01*
X762189Y190297D01*
X762856Y190464D01*
X763356Y190880D01*
X763689Y191380D01*
X763939Y192047D01*
X764022Y192797D01*
X763939Y193547D01*
X763689Y194214D01*
X763356Y194714D01*
X762856Y195130D01*
X762189Y195297D01*
G01X766289Y190130D02*
X769289Y195297D01*
G01X766289D02*
X765789Y195130D01*
X765539Y194880D01*
X765372Y194380D01*
X765539Y193880D01*
X765789Y193630D01*
X766289Y193464D01*
X766789Y193630D01*
X767039Y193880D01*
X767206Y194380D01*
X767039Y194880D01*
X766789Y195130D01*
X766289Y195297D01*
G01X769289Y191964D02*
X768789Y191797D01*
X768539Y191547D01*
X768372Y191047D01*
X768539Y190547D01*
X768789Y190297D01*
X769289Y190130D01*
X769789Y190297D01*
X770039Y190547D01*
X770206Y191047D01*
X770039Y191547D01*
X769789Y191797D01*
X769289Y191964D01*
G01X777822Y190297D02*
Y193630D01*
G01Y192964D02*
X778239Y193297D01*
X778656Y193547D01*
X779239Y193630D01*
X779656Y193547D01*
X780156Y193297D01*
G01X783339Y192547D02*
X786006D01*
X785756Y193130D01*
X785339Y193464D01*
X784756Y193630D01*
X784172Y193547D01*
X783672Y193297D01*
X783339Y192714D01*
X783172Y192214D01*
Y191714D01*
X783339Y191214D01*
X783756Y190714D01*
X784256Y190380D01*
X784839Y190297D01*
X785422Y190464D01*
X786006Y190964D01*
G01X788939Y190880D02*
X789356Y190547D01*
X789939Y190297D01*
X790439D01*
X790939Y190464D01*
X791272Y190714D01*
X791439Y191047D01*
X791356Y191547D01*
X791022Y191797D01*
X789522Y192297D01*
X789189Y192880D01*
X789356Y193297D01*
X789689Y193547D01*
X790189Y193630D01*
X790689Y193547D01*
X791189Y193297D01*
G01X795789Y193630D02*
Y190297D01*
G01Y194964D02*
X795622Y195047D01*
Y195214D01*
X795789Y195297D01*
X795956Y195214D01*
Y195047D01*
X795789Y194964D01*
G01X799972Y190297D02*
Y193630D01*
G01Y192797D02*
X800306Y193214D01*
X800806Y193547D01*
X801472Y193630D01*
X802056Y193547D01*
X802556Y193214D01*
X802806Y192630D01*
Y190297D01*
G01X812006Y188797D02*
X813172Y189964D01*
Y191130D01*
X812006D01*
Y189964D01*
X813172D01*
G01Y191964D02*
Y193130D01*
X812006D01*
Y191964D01*
X813172D01*
G01X816356Y190297D02*
Y195297D01*
X818022D01*
X818689Y195047D01*
X819189Y194714D01*
X819606Y194214D01*
X819939Y193630D01*
X820022Y192797D01*
X819939Y191964D01*
X819606Y191380D01*
X819189Y190880D01*
X818689Y190547D01*
X818022Y190297D01*
X816356D01*
G01X823789D02*
X823289Y190380D01*
X822789Y190714D01*
X822456Y191297D01*
X822289Y191964D01*
X822456Y192630D01*
X822789Y193214D01*
X823289Y193547D01*
X823789Y193630D01*
X824289Y193547D01*
X824789Y193214D01*
X825122Y192630D01*
X825206Y191964D01*
X825122Y191297D01*
X824789Y190714D01*
X824289Y190380D01*
X823789Y190297D01*
G01X833572D02*
Y193630D01*
G01Y192797D02*
X833906Y193214D01*
X834406Y193547D01*
X835072Y193630D01*
X835656Y193547D01*
X836156Y193214D01*
X836406Y192630D01*
Y190297D01*
G01X840589D02*
X840089Y190380D01*
X839589Y190714D01*
X839256Y191297D01*
X839089Y191964D01*
X839256Y192630D01*
X839589Y193214D01*
X840089Y193547D01*
X840589Y193630D01*
X841089Y193547D01*
X841589Y193214D01*
X841922Y192630D01*
X842006Y191964D01*
X841922Y191297D01*
X841589Y190714D01*
X841089Y190380D01*
X840589Y190297D01*
G01X846189Y195297D02*
Y190297D01*
G01X845022Y193630D02*
X847356D01*
G01X858889Y190297D02*
Y193630D01*
G01Y193047D02*
X858556Y193380D01*
X858056Y193547D01*
X857472Y193630D01*
X856889Y193464D01*
X856389Y193130D01*
X856056Y192630D01*
X855889Y191964D01*
X856056Y191297D01*
X856389Y190797D01*
X856889Y190464D01*
X857472Y190297D01*
X858056Y190380D01*
X858556Y190630D01*
X858889Y190964D01*
G01X862989Y190297D02*
Y195297D01*
G01X868589Y190297D02*
Y195297D01*
G01X874189Y190297D02*
X873689Y190380D01*
X873189Y190714D01*
X872856Y191297D01*
X872689Y191964D01*
X872856Y192630D01*
X873189Y193214D01*
X873689Y193547D01*
X874189Y193630D01*
X874689Y193547D01*
X875189Y193214D01*
X875522Y192630D01*
X875606Y191964D01*
X875522Y191297D01*
X875189Y190714D01*
X874689Y190380D01*
X874189Y190297D01*
G01X877706Y193630D02*
X878706Y190297D01*
X879789Y193630D01*
X880872Y190297D01*
X881872Y193630D01*
G01X591006Y211797D02*
X593089Y206797D01*
X595172Y211797D01*
G01X598689Y210130D02*
Y206797D01*
G01Y211464D02*
X598522Y211547D01*
Y211714D01*
X598689Y211797D01*
X598856Y211714D01*
Y211547D01*
X598689Y211464D01*
G01X605789Y206797D02*
Y210130D01*
G01Y209547D02*
X605456Y209880D01*
X604956Y210047D01*
X604372Y210130D01*
X603789Y209964D01*
X603289Y209630D01*
X602956Y209130D01*
X602789Y208464D01*
X602956Y207797D01*
X603289Y207297D01*
X603789Y206964D01*
X604372Y206797D01*
X604956Y206880D01*
X605456Y207130D01*
X605789Y207464D01*
G01X614239Y207380D02*
X614656Y207047D01*
X615239Y206797D01*
X615739D01*
X616239Y206964D01*
X616572Y207214D01*
X616739Y207547D01*
X616656Y208047D01*
X616322Y208297D01*
X614822Y208797D01*
X614489Y209380D01*
X614656Y209797D01*
X614989Y210047D01*
X615489Y210130D01*
X615989Y210047D01*
X616489Y209797D01*
G01X619672Y206797D02*
Y211797D01*
G01Y209380D02*
X620089Y209797D01*
X620506Y210047D01*
X621172Y210130D01*
X621672Y210047D01*
X622256Y209714D01*
X622506Y209214D01*
Y206797D01*
G01X626689D02*
X626189Y206880D01*
X625689Y207214D01*
X625356Y207797D01*
X625189Y208464D01*
X625356Y209130D01*
X625689Y209714D01*
X626189Y210047D01*
X626689Y210130D01*
X627189Y210047D01*
X627689Y209714D01*
X628022Y209130D01*
X628106Y208464D01*
X628022Y207797D01*
X627689Y207214D01*
X627189Y206880D01*
X626689Y206797D01*
G01X630872Y210130D02*
Y207797D01*
X631206Y207214D01*
X631706Y206880D01*
X632289Y206797D01*
X632872Y206880D01*
X633372Y207214D01*
X633706Y207797D01*
G01Y206797D02*
Y210130D01*
G01X637889Y206797D02*
Y211797D01*
G01X644989D02*
Y206797D01*
G01Y207547D02*
X644656Y207130D01*
X644156Y206880D01*
X643572Y206797D01*
X642906Y206964D01*
X642406Y207380D01*
X642072Y207880D01*
X641989Y208464D01*
X642072Y209047D01*
X642406Y209547D01*
X642906Y209964D01*
X643572Y210130D01*
X644156Y210047D01*
X644572Y209880D01*
X644989Y209547D01*
G01X653189Y206797D02*
Y211797D01*
G01Y209297D02*
X653606Y209797D01*
X654106Y210047D01*
X654606Y210130D01*
X655356Y209964D01*
X655856Y209630D01*
X656189Y209047D01*
Y208380D01*
X656022Y207714D01*
X655689Y207214D01*
X655106Y206880D01*
X654606Y206797D01*
X654106Y206880D01*
X653606Y207130D01*
X653189Y207547D01*
G01X659039Y209047D02*
X661706D01*
X661456Y209630D01*
X661039Y209964D01*
X660456Y210130D01*
X659872Y210047D01*
X659372Y209797D01*
X659039Y209214D01*
X658872Y208714D01*
Y208214D01*
X659039Y207714D01*
X659456Y207214D01*
X659956Y206880D01*
X660539Y206797D01*
X661122Y206964D01*
X661706Y207464D01*
G01X669989Y205130D02*
Y210130D01*
G01Y209380D02*
X670406Y209797D01*
X670822Y210047D01*
X671489Y210130D01*
X672072Y210047D01*
X672656Y209630D01*
X672906Y209047D01*
X672989Y208464D01*
X672906Y207880D01*
X672656Y207297D01*
X672156Y206964D01*
X671489Y206797D01*
X670906Y206880D01*
X670322Y207130D01*
X669989Y207464D01*
G01X677089Y206797D02*
Y211797D01*
G01X681272Y210130D02*
Y207797D01*
X681606Y207214D01*
X682106Y206880D01*
X682689Y206797D01*
X683272Y206880D01*
X683772Y207214D01*
X684106Y207797D01*
G01Y206797D02*
Y210130D01*
G01X687122Y205547D02*
X687706Y205214D01*
X688372Y205130D01*
X688956Y205214D01*
X689456Y205630D01*
X689789Y206214D01*
Y210130D01*
G01Y209464D02*
X689456Y209797D01*
X688956Y210047D01*
X688372Y210130D01*
X687706Y209964D01*
X687289Y209630D01*
X686956Y209047D01*
X686789Y208464D01*
X686872Y207964D01*
X687206Y207380D01*
X687706Y206964D01*
X688372Y206797D01*
X688872Y206880D01*
X689456Y207214D01*
X689789Y207547D01*
G01X692722Y205547D02*
X693306Y205214D01*
X693972Y205130D01*
X694556Y205214D01*
X695056Y205630D01*
X695389Y206214D01*
Y210130D01*
G01Y209464D02*
X695056Y209797D01*
X694556Y210047D01*
X693972Y210130D01*
X693306Y209964D01*
X692889Y209630D01*
X692556Y209047D01*
X692389Y208464D01*
X692472Y207964D01*
X692806Y207380D01*
X693306Y206964D01*
X693972Y206797D01*
X694472Y206880D01*
X695056Y207214D01*
X695389Y207547D01*
G01X698239Y209047D02*
X700906D01*
X700656Y209630D01*
X700239Y209964D01*
X699656Y210130D01*
X699072Y210047D01*
X698572Y209797D01*
X698239Y209214D01*
X698072Y208714D01*
Y208214D01*
X698239Y207714D01*
X698656Y207214D01*
X699156Y206880D01*
X699739Y206797D01*
X700322Y206964D01*
X700906Y207464D01*
G01X706589Y211797D02*
Y206797D01*
G01Y207547D02*
X706256Y207130D01*
X705756Y206880D01*
X705172Y206797D01*
X704506Y206964D01*
X704006Y207380D01*
X703672Y207880D01*
X703589Y208464D01*
X703672Y209047D01*
X704006Y209547D01*
X704506Y209964D01*
X705172Y210130D01*
X705756Y210047D01*
X706172Y209880D01*
X706589Y209547D01*
G01X714206Y210130D02*
X715206Y206797D01*
X716289Y210130D01*
X717372Y206797D01*
X718372Y210130D01*
G01X721889D02*
Y206797D01*
G01Y211464D02*
X721722Y211547D01*
Y211714D01*
X721889Y211797D01*
X722056Y211714D01*
Y211547D01*
X721889Y211464D01*
G01X727489Y211797D02*
Y206797D01*
G01X726322Y210130D02*
X728656D01*
G01X731672Y206797D02*
Y211797D01*
G01Y209380D02*
X732089Y209797D01*
X732506Y210047D01*
X733172Y210130D01*
X733672Y210047D01*
X734256Y209714D01*
X734506Y209214D01*
Y206797D01*
G01X742622D02*
X745956Y208464D01*
X742622Y210130D01*
G01X748472Y207380D02*
X749056Y206964D01*
X749722Y206797D01*
X750389Y206964D01*
X750972Y207464D01*
X751389Y208214D01*
X751556Y208964D01*
Y209880D01*
X751389Y210630D01*
X750972Y211297D01*
X750472Y211630D01*
X749889Y211797D01*
X749222Y211630D01*
X748722Y211297D01*
X748389Y210797D01*
X748222Y210130D01*
X748389Y209547D01*
X748806Y208964D01*
X749306Y208630D01*
X749889Y208547D01*
X750556Y208714D01*
X751056Y209130D01*
X751556Y209880D01*
G01X755489Y211797D02*
X754822Y211630D01*
X754322Y211214D01*
X753989Y210714D01*
X753739Y210047D01*
X753656Y209297D01*
X753739Y208547D01*
X753989Y207880D01*
X754322Y207380D01*
X754822Y206964D01*
X755489Y206797D01*
X756156Y206964D01*
X756656Y207380D01*
X756989Y207880D01*
X757239Y208547D01*
X757322Y209297D01*
X757239Y210047D01*
X756989Y210714D01*
X756656Y211214D01*
X756156Y211630D01*
X755489Y211797D01*
G01X759589Y206630D02*
X762589Y211797D01*
G01X759589D02*
X759089Y211630D01*
X758839Y211380D01*
X758672Y210880D01*
X758839Y210380D01*
X759089Y210130D01*
X759589Y209964D01*
X760089Y210130D01*
X760339Y210380D01*
X760506Y210880D01*
X760339Y211380D01*
X760089Y211630D01*
X759589Y211797D01*
G01X762589Y208464D02*
X762089Y208297D01*
X761839Y208047D01*
X761672Y207547D01*
X761839Y207047D01*
X762089Y206797D01*
X762589Y206630D01*
X763089Y206797D01*
X763339Y207047D01*
X763506Y207547D01*
X763339Y208047D01*
X763089Y208297D01*
X762589Y208464D01*
G01X771122Y206797D02*
Y210130D01*
G01Y209464D02*
X771539Y209797D01*
X771956Y210047D01*
X772539Y210130D01*
X772956Y210047D01*
X773456Y209797D01*
G01X776639Y209047D02*
X779306D01*
X779056Y209630D01*
X778639Y209964D01*
X778056Y210130D01*
X777472Y210047D01*
X776972Y209797D01*
X776639Y209214D01*
X776472Y208714D01*
Y208214D01*
X776639Y207714D01*
X777056Y207214D01*
X777556Y206880D01*
X778139Y206797D01*
X778722Y206964D01*
X779306Y207464D01*
G01X782239Y207380D02*
X782656Y207047D01*
X783239Y206797D01*
X783739D01*
X784239Y206964D01*
X784572Y207214D01*
X784739Y207547D01*
X784656Y208047D01*
X784322Y208297D01*
X782822Y208797D01*
X782489Y209380D01*
X782656Y209797D01*
X782989Y210047D01*
X783489Y210130D01*
X783989Y210047D01*
X784489Y209797D01*
G01X789089Y210130D02*
Y206797D01*
G01Y211464D02*
X788922Y211547D01*
Y211714D01*
X789089Y211797D01*
X789256Y211714D01*
Y211547D01*
X789089Y211464D01*
G01X793272Y206797D02*
Y210130D01*
G01Y209297D02*
X793606Y209714D01*
X794106Y210047D01*
X794772Y210130D01*
X795356Y210047D01*
X795856Y209714D01*
X796106Y209130D01*
Y206797D01*
G01X589506Y232797D02*
X591589Y227797D01*
X593672Y232797D01*
G01X597189Y231130D02*
Y227797D01*
G01Y232464D02*
X597022Y232547D01*
Y232714D01*
X597189Y232797D01*
X597356Y232714D01*
Y232547D01*
X597189Y232464D01*
G01X604289Y227797D02*
Y231130D01*
G01Y230547D02*
X603956Y230880D01*
X603456Y231047D01*
X602872Y231130D01*
X602289Y230964D01*
X601789Y230630D01*
X601456Y230130D01*
X601289Y229464D01*
X601456Y228797D01*
X601789Y228297D01*
X602289Y227964D01*
X602872Y227797D01*
X603456Y227880D01*
X603956Y228130D01*
X604289Y228464D01*
G01X612739Y228380D02*
X613156Y228047D01*
X613739Y227797D01*
X614239D01*
X614739Y227964D01*
X615072Y228214D01*
X615239Y228547D01*
X615156Y229047D01*
X614822Y229297D01*
X613322Y229797D01*
X612989Y230380D01*
X613156Y230797D01*
X613489Y231047D01*
X613989Y231130D01*
X614489Y231047D01*
X614989Y230797D01*
G01X618172Y227797D02*
Y232797D01*
G01Y230380D02*
X618589Y230797D01*
X619006Y231047D01*
X619672Y231130D01*
X620172Y231047D01*
X620756Y230714D01*
X621006Y230214D01*
Y227797D01*
G01X625189D02*
X624689Y227880D01*
X624189Y228214D01*
X623856Y228797D01*
X623689Y229464D01*
X623856Y230130D01*
X624189Y230714D01*
X624689Y231047D01*
X625189Y231130D01*
X625689Y231047D01*
X626189Y230714D01*
X626522Y230130D01*
X626606Y229464D01*
X626522Y228797D01*
X626189Y228214D01*
X625689Y227880D01*
X625189Y227797D01*
G01X629372Y231130D02*
Y228797D01*
X629706Y228214D01*
X630206Y227880D01*
X630789Y227797D01*
X631372Y227880D01*
X631872Y228214D01*
X632206Y228797D01*
G01Y227797D02*
Y231130D01*
G01X636389Y227797D02*
Y232797D01*
G01X643489D02*
Y227797D01*
G01Y228547D02*
X643156Y228130D01*
X642656Y227880D01*
X642072Y227797D01*
X641406Y227964D01*
X640906Y228380D01*
X640572Y228880D01*
X640489Y229464D01*
X640572Y230047D01*
X640906Y230547D01*
X641406Y230964D01*
X642072Y231130D01*
X642656Y231047D01*
X643072Y230880D01*
X643489Y230547D01*
G01X651689Y227797D02*
Y232797D01*
G01Y230297D02*
X652106Y230797D01*
X652606Y231047D01*
X653106Y231130D01*
X653856Y230964D01*
X654356Y230630D01*
X654689Y230047D01*
Y229380D01*
X654522Y228714D01*
X654189Y228214D01*
X653606Y227880D01*
X653106Y227797D01*
X652606Y227880D01*
X652106Y228130D01*
X651689Y228547D01*
G01X657539Y230047D02*
X660206D01*
X659956Y230630D01*
X659539Y230964D01*
X658956Y231130D01*
X658372Y231047D01*
X657872Y230797D01*
X657539Y230214D01*
X657372Y229714D01*
Y229214D01*
X657539Y228714D01*
X657956Y228214D01*
X658456Y227880D01*
X659039Y227797D01*
X659622Y227964D01*
X660206Y228464D01*
G01X668489Y226130D02*
Y231130D01*
G01Y230380D02*
X668906Y230797D01*
X669322Y231047D01*
X669989Y231130D01*
X670572Y231047D01*
X671156Y230630D01*
X671406Y230047D01*
X671489Y229464D01*
X671406Y228880D01*
X671156Y228297D01*
X670656Y227964D01*
X669989Y227797D01*
X669406Y227880D01*
X668822Y228130D01*
X668489Y228464D01*
G01X675589Y227797D02*
Y232797D01*
G01X679772Y231130D02*
Y228797D01*
X680106Y228214D01*
X680606Y227880D01*
X681189Y227797D01*
X681772Y227880D01*
X682272Y228214D01*
X682606Y228797D01*
G01Y227797D02*
Y231130D01*
G01X685622Y226547D02*
X686206Y226214D01*
X686872Y226130D01*
X687456Y226214D01*
X687956Y226630D01*
X688289Y227214D01*
Y231130D01*
G01Y230464D02*
X687956Y230797D01*
X687456Y231047D01*
X686872Y231130D01*
X686206Y230964D01*
X685789Y230630D01*
X685456Y230047D01*
X685289Y229464D01*
X685372Y228964D01*
X685706Y228380D01*
X686206Y227964D01*
X686872Y227797D01*
X687372Y227880D01*
X687956Y228214D01*
X688289Y228547D01*
G01X691222Y226547D02*
X691806Y226214D01*
X692472Y226130D01*
X693056Y226214D01*
X693556Y226630D01*
X693889Y227214D01*
Y231130D01*
G01Y230464D02*
X693556Y230797D01*
X693056Y231047D01*
X692472Y231130D01*
X691806Y230964D01*
X691389Y230630D01*
X691056Y230047D01*
X690889Y229464D01*
X690972Y228964D01*
X691306Y228380D01*
X691806Y227964D01*
X692472Y227797D01*
X692972Y227880D01*
X693556Y228214D01*
X693889Y228547D01*
G01X696739Y230047D02*
X699406D01*
X699156Y230630D01*
X698739Y230964D01*
X698156Y231130D01*
X697572Y231047D01*
X697072Y230797D01*
X696739Y230214D01*
X696572Y229714D01*
Y229214D01*
X696739Y228714D01*
X697156Y228214D01*
X697656Y227880D01*
X698239Y227797D01*
X698822Y227964D01*
X699406Y228464D01*
G01X705089Y232797D02*
Y227797D01*
G01Y228547D02*
X704756Y228130D01*
X704256Y227880D01*
X703672Y227797D01*
X703006Y227964D01*
X702506Y228380D01*
X702172Y228880D01*
X702089Y229464D01*
X702172Y230047D01*
X702506Y230547D01*
X703006Y230964D01*
X703672Y231130D01*
X704256Y231047D01*
X704672Y230880D01*
X705089Y230547D01*
G01X715789Y227797D02*
Y232797D01*
X712706Y229214D01*
X716872D01*
G01X720389Y232797D02*
X719722Y232630D01*
X719222Y232214D01*
X718889Y231714D01*
X718639Y231047D01*
X718556Y230297D01*
X718639Y229547D01*
X718889Y228880D01*
X719222Y228380D01*
X719722Y227964D01*
X720389Y227797D01*
X721056Y227964D01*
X721556Y228380D01*
X721889Y228880D01*
X722139Y229547D01*
X722222Y230297D01*
X722139Y231047D01*
X721889Y231714D01*
X721556Y232214D01*
X721056Y232630D01*
X720389Y232797D01*
G01X724489Y227630D02*
X727489Y232797D01*
G01X724489D02*
X723989Y232630D01*
X723739Y232380D01*
X723572Y231880D01*
X723739Y231380D01*
X723989Y231130D01*
X724489Y230964D01*
X724989Y231130D01*
X725239Y231380D01*
X725406Y231880D01*
X725239Y232380D01*
X724989Y232630D01*
X724489Y232797D01*
G01X727489Y229464D02*
X726989Y229297D01*
X726739Y229047D01*
X726572Y228547D01*
X726739Y228047D01*
X726989Y227797D01*
X727489Y227630D01*
X727989Y227797D01*
X728239Y228047D01*
X728406Y228547D01*
X728239Y229047D01*
X727989Y229297D01*
X727489Y229464D01*
G01X734689D02*
X735522Y231130D01*
X736356D01*
X738022Y227797D01*
X738856D01*
X739689Y229464D01*
G01X748389Y227797D02*
Y232797D01*
X747389Y231797D01*
G01Y227797D02*
X749389D01*
G01X753989Y232797D02*
X753322Y232630D01*
X752822Y232214D01*
X752489Y231714D01*
X752239Y231047D01*
X752156Y230297D01*
X752239Y229547D01*
X752489Y228880D01*
X752822Y228380D01*
X753322Y227964D01*
X753989Y227797D01*
X754656Y227964D01*
X755156Y228380D01*
X755489Y228880D01*
X755739Y229547D01*
X755822Y230297D01*
X755739Y231047D01*
X755489Y231714D01*
X755156Y232214D01*
X754656Y232630D01*
X753989Y232797D01*
G01X759589D02*
X758922Y232630D01*
X758422Y232214D01*
X758089Y231714D01*
X757839Y231047D01*
X757756Y230297D01*
X757839Y229547D01*
X758089Y228880D01*
X758422Y228380D01*
X758922Y227964D01*
X759589Y227797D01*
X760256Y227964D01*
X760756Y228380D01*
X761089Y228880D01*
X761339Y229547D01*
X761422Y230297D01*
X761339Y231047D01*
X761089Y231714D01*
X760756Y232214D01*
X760256Y232630D01*
X759589Y232797D01*
G01X763689Y227630D02*
X766689Y232797D01*
G01X763689D02*
X763189Y232630D01*
X762939Y232380D01*
X762772Y231880D01*
X762939Y231380D01*
X763189Y231130D01*
X763689Y230964D01*
X764189Y231130D01*
X764439Y231380D01*
X764606Y231880D01*
X764439Y232380D01*
X764189Y232630D01*
X763689Y232797D01*
G01X766689Y229464D02*
X766189Y229297D01*
X765939Y229047D01*
X765772Y228547D01*
X765939Y228047D01*
X766189Y227797D01*
X766689Y227630D01*
X767189Y227797D01*
X767439Y228047D01*
X767606Y228547D01*
X767439Y229047D01*
X767189Y229297D01*
X766689Y229464D01*
G01X775139Y228380D02*
X775556Y228047D01*
X776139Y227797D01*
X776639D01*
X777139Y227964D01*
X777472Y228214D01*
X777639Y228547D01*
X777556Y229047D01*
X777222Y229297D01*
X775722Y229797D01*
X775389Y230380D01*
X775556Y230797D01*
X775889Y231047D01*
X776389Y231130D01*
X776889Y231047D01*
X777389Y230797D01*
G01X781989Y227797D02*
X781489Y227880D01*
X780989Y228214D01*
X780656Y228797D01*
X780489Y229464D01*
X780656Y230130D01*
X780989Y230714D01*
X781489Y231047D01*
X781989Y231130D01*
X782489Y231047D01*
X782989Y230714D01*
X783322Y230130D01*
X783406Y229464D01*
X783322Y228797D01*
X782989Y228214D01*
X782489Y227880D01*
X781989Y227797D01*
G01X787589D02*
Y232797D01*
G01X794689D02*
Y227797D01*
G01Y228547D02*
X794356Y228130D01*
X793856Y227880D01*
X793272Y227797D01*
X792606Y227964D01*
X792106Y228380D01*
X791772Y228880D01*
X791689Y229464D01*
X791772Y230047D01*
X792106Y230547D01*
X792606Y230964D01*
X793272Y231130D01*
X793856Y231047D01*
X794272Y230880D01*
X794689Y230547D01*
G01X797539Y230047D02*
X800206D01*
X799956Y230630D01*
X799539Y230964D01*
X798956Y231130D01*
X798372Y231047D01*
X797872Y230797D01*
X797539Y230214D01*
X797372Y229714D01*
Y229214D01*
X797539Y228714D01*
X797956Y228214D01*
X798456Y227880D01*
X799039Y227797D01*
X799622Y227964D01*
X800206Y228464D01*
G01X803222Y227797D02*
Y231130D01*
G01Y230464D02*
X803639Y230797D01*
X804056Y231047D01*
X804639Y231130D01*
X805056Y231047D01*
X805556Y230797D01*
G01X813089Y227797D02*
Y231130D01*
G01Y230214D02*
X813339Y230630D01*
X813756Y230964D01*
X814339Y231130D01*
X814922Y230964D01*
X815339Y230630D01*
X815589Y230214D01*
Y227797D01*
G01Y230214D02*
X815839Y230630D01*
X816256Y230964D01*
X816839Y231130D01*
X817422Y230964D01*
X817839Y230630D01*
X818089Y230130D01*
Y227797D01*
G01X822689D02*
Y231130D01*
G01Y230547D02*
X822356Y230880D01*
X821856Y231047D01*
X821272Y231130D01*
X820689Y230964D01*
X820189Y230630D01*
X819856Y230130D01*
X819689Y229464D01*
X819856Y228797D01*
X820189Y228297D01*
X820689Y227964D01*
X821272Y227797D01*
X821856Y227880D01*
X822356Y228130D01*
X822689Y228464D01*
G01X825539Y228380D02*
X825956Y228047D01*
X826539Y227797D01*
X827039D01*
X827539Y227964D01*
X827872Y228214D01*
X828039Y228547D01*
X827956Y229047D01*
X827622Y229297D01*
X826122Y229797D01*
X825789Y230380D01*
X825956Y230797D01*
X826289Y231047D01*
X826789Y231130D01*
X827289Y231047D01*
X827789Y230797D01*
G01X830972Y227797D02*
Y232797D01*
G01X833639Y231130D02*
X830972Y229214D01*
G01X832056Y229964D02*
X833806Y227797D01*
G01X586006Y308964D02*
X586506Y309464D01*
X587089Y309714D01*
X587756Y309797D01*
X588589Y309630D01*
X589172Y309214D01*
X589339Y308714D01*
X589256Y308214D01*
X588922Y307797D01*
X587256Y306964D01*
X586506Y306380D01*
X586006Y305547D01*
X585839Y304797D01*
X589339D01*
G01X593189Y304630D02*
X593022Y304714D01*
Y304880D01*
X593189Y304964D01*
X593356Y304880D01*
Y304714D01*
X593189Y304630D01*
G01X598789Y309797D02*
Y304797D01*
G01X596872Y309797D02*
X600706D01*
G01X602972Y304797D02*
Y309797D01*
G01Y307380D02*
X603389Y307797D01*
X603806Y308047D01*
X604472Y308130D01*
X604972Y308047D01*
X605556Y307714D01*
X605806Y307214D01*
Y304797D01*
G01X608739Y307047D02*
X611406D01*
X611156Y307630D01*
X610739Y307964D01*
X610156Y308130D01*
X609572Y308047D01*
X609072Y307797D01*
X608739Y307214D01*
X608572Y306714D01*
Y306214D01*
X608739Y305714D01*
X609156Y305214D01*
X609656Y304880D01*
X610239Y304797D01*
X610822Y304964D01*
X611406Y305464D01*
G01X619939Y305380D02*
X620356Y305047D01*
X620939Y304797D01*
X621439D01*
X621939Y304964D01*
X622272Y305214D01*
X622439Y305547D01*
X622356Y306047D01*
X622022Y306297D01*
X620522Y306797D01*
X620189Y307380D01*
X620356Y307797D01*
X620689Y308047D01*
X621189Y308130D01*
X621689Y308047D01*
X622189Y307797D01*
G01X626789Y308130D02*
Y304797D01*
G01Y309464D02*
X626622Y309547D01*
Y309714D01*
X626789Y309797D01*
X626956Y309714D01*
Y309547D01*
X626789Y309464D01*
G01X633889Y309797D02*
Y304797D01*
G01Y305547D02*
X633556Y305130D01*
X633056Y304880D01*
X632472Y304797D01*
X631806Y304964D01*
X631306Y305380D01*
X630972Y305880D01*
X630889Y306464D01*
X630972Y307047D01*
X631306Y307547D01*
X631806Y307964D01*
X632472Y308130D01*
X633056Y308047D01*
X633472Y307880D01*
X633889Y307547D01*
G01X636739Y307047D02*
X639406D01*
X639156Y307630D01*
X638739Y307964D01*
X638156Y308130D01*
X637572Y308047D01*
X637072Y307797D01*
X636739Y307214D01*
X636572Y306714D01*
Y306214D01*
X636739Y305714D01*
X637156Y305214D01*
X637656Y304880D01*
X638239Y304797D01*
X638822Y304964D01*
X639406Y305464D01*
G01X647106Y308130D02*
X648106Y304797D01*
X649189Y308130D01*
X650272Y304797D01*
X651272Y308130D01*
G01X654789D02*
Y304797D01*
G01Y309464D02*
X654622Y309547D01*
Y309714D01*
X654789Y309797D01*
X654956Y309714D01*
Y309547D01*
X654789Y309464D01*
G01X660389Y309797D02*
Y304797D01*
G01X659222Y308130D02*
X661556D01*
G01X664572Y304797D02*
Y309797D01*
G01Y307380D02*
X664989Y307797D01*
X665406Y308047D01*
X666072Y308130D01*
X666572Y308047D01*
X667156Y307714D01*
X667406Y307214D01*
Y304797D01*
G01X675939Y305380D02*
X676356Y305047D01*
X676939Y304797D01*
X677439D01*
X677939Y304964D01*
X678272Y305214D01*
X678439Y305547D01*
X678356Y306047D01*
X678022Y306297D01*
X676522Y306797D01*
X676189Y307380D01*
X676356Y307797D01*
X676689Y308047D01*
X677189Y308130D01*
X677689Y308047D01*
X678189Y307797D01*
G01X682789Y304797D02*
X682289Y304880D01*
X681789Y305214D01*
X681456Y305797D01*
X681289Y306464D01*
X681456Y307130D01*
X681789Y307714D01*
X682289Y308047D01*
X682789Y308130D01*
X683289Y308047D01*
X683789Y307714D01*
X684122Y307130D01*
X684206Y306464D01*
X684122Y305797D01*
X683789Y305214D01*
X683289Y304880D01*
X682789Y304797D01*
G01X688389D02*
Y309797D01*
G01X695489D02*
Y304797D01*
G01Y305547D02*
X695156Y305130D01*
X694656Y304880D01*
X694072Y304797D01*
X693406Y304964D01*
X692906Y305380D01*
X692572Y305880D01*
X692489Y306464D01*
X692572Y307047D01*
X692906Y307547D01*
X693406Y307964D01*
X694072Y308130D01*
X694656Y308047D01*
X695072Y307880D01*
X695489Y307547D01*
G01X698339Y307047D02*
X701006D01*
X700756Y307630D01*
X700339Y307964D01*
X699756Y308130D01*
X699172Y308047D01*
X698672Y307797D01*
X698339Y307214D01*
X698172Y306714D01*
Y306214D01*
X698339Y305714D01*
X698756Y305214D01*
X699256Y304880D01*
X699839Y304797D01*
X700422Y304964D01*
X701006Y305464D01*
G01X704022Y304797D02*
Y308130D01*
G01Y307464D02*
X704439Y307797D01*
X704856Y308047D01*
X705439Y308130D01*
X705856Y308047D01*
X706356Y307797D01*
G01X713889Y304797D02*
Y308130D01*
G01Y307214D02*
X714139Y307630D01*
X714556Y307964D01*
X715139Y308130D01*
X715722Y307964D01*
X716139Y307630D01*
X716389Y307214D01*
Y304797D01*
G01Y307214D02*
X716639Y307630D01*
X717056Y307964D01*
X717639Y308130D01*
X718222Y307964D01*
X718639Y307630D01*
X718889Y307130D01*
Y304797D01*
G01X723489D02*
Y308130D01*
G01Y307547D02*
X723156Y307880D01*
X722656Y308047D01*
X722072Y308130D01*
X721489Y307964D01*
X720989Y307630D01*
X720656Y307130D01*
X720489Y306464D01*
X720656Y305797D01*
X720989Y305297D01*
X721489Y304964D01*
X722072Y304797D01*
X722656Y304880D01*
X723156Y305130D01*
X723489Y305464D01*
G01X726339Y305380D02*
X726756Y305047D01*
X727339Y304797D01*
X727839D01*
X728339Y304964D01*
X728672Y305214D01*
X728839Y305547D01*
X728756Y306047D01*
X728422Y306297D01*
X726922Y306797D01*
X726589Y307380D01*
X726756Y307797D01*
X727089Y308047D01*
X727589Y308130D01*
X728089Y308047D01*
X728589Y307797D01*
G01X731772Y304797D02*
Y309797D01*
G01X734439Y308130D02*
X731772Y306214D01*
G01X732856Y306964D02*
X734606Y304797D01*
G01X742889Y303130D02*
Y308130D01*
G01Y307380D02*
X743306Y307797D01*
X743722Y308047D01*
X744389Y308130D01*
X744972Y308047D01*
X745556Y307630D01*
X745806Y307047D01*
X745889Y306464D01*
X745806Y305880D01*
X745556Y305297D01*
X745056Y304964D01*
X744389Y304797D01*
X743806Y304880D01*
X743222Y305130D01*
X742889Y305464D01*
G01X751489Y304797D02*
Y308130D01*
G01Y307547D02*
X751156Y307880D01*
X750656Y308047D01*
X750072Y308130D01*
X749489Y307964D01*
X748989Y307630D01*
X748656Y307130D01*
X748489Y306464D01*
X748656Y305797D01*
X748989Y305297D01*
X749489Y304964D01*
X750072Y304797D01*
X750656Y304880D01*
X751156Y305130D01*
X751489Y305464D01*
G01X757089Y309797D02*
Y304797D01*
G01Y305547D02*
X756756Y305130D01*
X756256Y304880D01*
X755672Y304797D01*
X755006Y304964D01*
X754506Y305380D01*
X754172Y305880D01*
X754089Y306464D01*
X754172Y307047D01*
X754506Y307547D01*
X755006Y307964D01*
X755672Y308130D01*
X756256Y308047D01*
X756672Y307880D01*
X757089Y307547D01*
G01X761022Y303880D02*
X761356Y304964D01*
G01X772389Y309797D02*
Y304797D01*
G01X771222Y308130D02*
X773556D01*
G01X776572Y304797D02*
Y309797D01*
G01Y307380D02*
X776989Y307797D01*
X777406Y308047D01*
X778072Y308130D01*
X778572Y308047D01*
X779156Y307714D01*
X779406Y307214D01*
Y304797D01*
G01X782339Y307047D02*
X785006D01*
X784756Y307630D01*
X784339Y307964D01*
X783756Y308130D01*
X783172Y308047D01*
X782672Y307797D01*
X782339Y307214D01*
X782172Y306714D01*
Y306214D01*
X782339Y305714D01*
X782756Y305214D01*
X783256Y304880D01*
X783839Y304797D01*
X784422Y304964D01*
X785006Y305464D01*
G01X796289Y304797D02*
Y308130D01*
G01Y307547D02*
X795956Y307880D01*
X795456Y308047D01*
X794872Y308130D01*
X794289Y307964D01*
X793789Y307630D01*
X793456Y307130D01*
X793289Y306464D01*
X793456Y305797D01*
X793789Y305297D01*
X794289Y304964D01*
X794872Y304797D01*
X795456Y304880D01*
X795956Y305130D01*
X796289Y305464D01*
G01X798972Y304797D02*
Y308130D01*
G01Y307297D02*
X799306Y307714D01*
X799806Y308047D01*
X800472Y308130D01*
X801056Y308047D01*
X801556Y307714D01*
X801806Y307130D01*
Y304797D01*
G01X804572D02*
Y308130D01*
G01Y307297D02*
X804906Y307714D01*
X805406Y308047D01*
X806072Y308130D01*
X806656Y308047D01*
X807156Y307714D01*
X807406Y307130D01*
Y304797D01*
G01X810172Y308130D02*
Y305797D01*
X810506Y305214D01*
X811006Y304880D01*
X811589Y304797D01*
X812172Y304880D01*
X812672Y305214D01*
X813006Y305797D01*
G01Y304797D02*
Y308130D01*
G01X818689Y304797D02*
Y308130D01*
G01Y307547D02*
X818356Y307880D01*
X817856Y308047D01*
X817272Y308130D01*
X816689Y307964D01*
X816189Y307630D01*
X815856Y307130D01*
X815689Y306464D01*
X815856Y305797D01*
X816189Y305297D01*
X816689Y304964D01*
X817272Y304797D01*
X817856Y304880D01*
X818356Y305130D01*
X818689Y305464D01*
G01X822789Y304797D02*
Y309797D01*
G01X832822Y304797D02*
Y308130D01*
G01Y307464D02*
X833239Y307797D01*
X833656Y308047D01*
X834239Y308130D01*
X834656Y308047D01*
X835156Y307797D01*
G01X839589Y308130D02*
Y304797D01*
G01Y309464D02*
X839422Y309547D01*
Y309714D01*
X839589Y309797D01*
X839756Y309714D01*
Y309547D01*
X839589Y309464D01*
G01X843772Y304797D02*
Y308130D01*
G01Y307297D02*
X844106Y307714D01*
X844606Y308047D01*
X845272Y308130D01*
X845856Y308047D01*
X846356Y307714D01*
X846606Y307130D01*
Y304797D01*
G01X849622Y303547D02*
X850206Y303214D01*
X850872Y303130D01*
X851456Y303214D01*
X851956Y303630D01*
X852289Y304214D01*
Y308130D01*
G01Y307464D02*
X851956Y307797D01*
X851456Y308047D01*
X850872Y308130D01*
X850206Y307964D01*
X849789Y307630D01*
X849456Y307047D01*
X849289Y306464D01*
X849372Y305964D01*
X849706Y305380D01*
X850206Y304964D01*
X850872Y304797D01*
X851372Y304880D01*
X851956Y305214D01*
X852289Y305547D01*
G01X860739Y305380D02*
X861156Y305047D01*
X861739Y304797D01*
X862239D01*
X862739Y304964D01*
X863072Y305214D01*
X863239Y305547D01*
X863156Y306047D01*
X862822Y306297D01*
X861322Y306797D01*
X860989Y307380D01*
X861156Y307797D01*
X861489Y308047D01*
X861989Y308130D01*
X862489Y308047D01*
X862989Y307797D01*
G01X866172Y304797D02*
Y309797D01*
G01Y307380D02*
X866589Y307797D01*
X867006Y308047D01*
X867672Y308130D01*
X868172Y308047D01*
X868756Y307714D01*
X869006Y307214D01*
Y304797D01*
G01X873189D02*
X872689Y304880D01*
X872189Y305214D01*
X871856Y305797D01*
X871689Y306464D01*
X871856Y307130D01*
X872189Y307714D01*
X872689Y308047D01*
X873189Y308130D01*
X873689Y308047D01*
X874189Y307714D01*
X874522Y307130D01*
X874606Y306464D01*
X874522Y305797D01*
X874189Y305214D01*
X873689Y304880D01*
X873189Y304797D01*
G01X877372Y308130D02*
Y305797D01*
X877706Y305214D01*
X878206Y304880D01*
X878789Y304797D01*
X879372Y304880D01*
X879872Y305214D01*
X880206Y305797D01*
G01Y304797D02*
Y308130D01*
G01X884389Y304797D02*
Y309797D01*
G01X891489D02*
Y304797D01*
G01Y305547D02*
X891156Y305130D01*
X890656Y304880D01*
X890072Y304797D01*
X889406Y304964D01*
X888906Y305380D01*
X888572Y305880D01*
X888489Y306464D01*
X888572Y307047D01*
X888906Y307547D01*
X889406Y307964D01*
X890072Y308130D01*
X890656Y308047D01*
X891072Y307880D01*
X891489Y307547D01*
G01X587589Y335797D02*
Y340797D01*
X586589Y339797D01*
G01Y335797D02*
X588589D01*
G01X593189Y335630D02*
X593022Y335714D01*
Y335880D01*
X593189Y335964D01*
X593356Y335880D01*
Y335714D01*
X593189Y335630D01*
G01X598789Y340797D02*
Y335797D01*
G01X596872Y340797D02*
X600706D01*
G01X602972Y335797D02*
Y340797D01*
G01Y338380D02*
X603389Y338797D01*
X603806Y339047D01*
X604472Y339130D01*
X604972Y339047D01*
X605556Y338714D01*
X605806Y338214D01*
Y335797D01*
G01X608739Y338047D02*
X611406D01*
X611156Y338630D01*
X610739Y338964D01*
X610156Y339130D01*
X609572Y339047D01*
X609072Y338797D01*
X608739Y338214D01*
X608572Y337714D01*
Y337214D01*
X608739Y336714D01*
X609156Y336214D01*
X609656Y335880D01*
X610239Y335797D01*
X610822Y335964D01*
X611406Y336464D01*
G01X619939Y336380D02*
X620356Y336047D01*
X620939Y335797D01*
X621439D01*
X621939Y335964D01*
X622272Y336214D01*
X622439Y336547D01*
X622356Y337047D01*
X622022Y337297D01*
X620522Y337797D01*
X620189Y338380D01*
X620356Y338797D01*
X620689Y339047D01*
X621189Y339130D01*
X621689Y339047D01*
X622189Y338797D01*
G01X626789Y339130D02*
Y335797D01*
G01Y340464D02*
X626622Y340547D01*
Y340714D01*
X626789Y340797D01*
X626956Y340714D01*
Y340547D01*
X626789Y340464D01*
G01X633889Y340797D02*
Y335797D01*
G01Y336547D02*
X633556Y336130D01*
X633056Y335880D01*
X632472Y335797D01*
X631806Y335964D01*
X631306Y336380D01*
X630972Y336880D01*
X630889Y337464D01*
X630972Y338047D01*
X631306Y338547D01*
X631806Y338964D01*
X632472Y339130D01*
X633056Y339047D01*
X633472Y338880D01*
X633889Y338547D01*
G01X636739Y338047D02*
X639406D01*
X639156Y338630D01*
X638739Y338964D01*
X638156Y339130D01*
X637572Y339047D01*
X637072Y338797D01*
X636739Y338214D01*
X636572Y337714D01*
Y337214D01*
X636739Y336714D01*
X637156Y336214D01*
X637656Y335880D01*
X638239Y335797D01*
X638822Y335964D01*
X639406Y336464D01*
G01X647106Y339130D02*
X648106Y335797D01*
X649189Y339130D01*
X650272Y335797D01*
X651272Y339130D01*
G01X654789D02*
Y335797D01*
G01Y340464D02*
X654622Y340547D01*
Y340714D01*
X654789Y340797D01*
X654956Y340714D01*
Y340547D01*
X654789Y340464D01*
G01X660389Y340797D02*
Y335797D01*
G01X659222Y339130D02*
X661556D01*
G01X664572Y335797D02*
Y340797D01*
G01Y338380D02*
X664989Y338797D01*
X665406Y339047D01*
X666072Y339130D01*
X666572Y339047D01*
X667156Y338714D01*
X667406Y338214D01*
Y335797D01*
G01X671589D02*
X671089Y335880D01*
X670589Y336214D01*
X670256Y336797D01*
X670089Y337464D01*
X670256Y338130D01*
X670589Y338714D01*
X671089Y339047D01*
X671589Y339130D01*
X672089Y339047D01*
X672589Y338714D01*
X672922Y338130D01*
X673006Y337464D01*
X672922Y336797D01*
X672589Y336214D01*
X672089Y335880D01*
X671589Y335797D01*
G01X675772Y339130D02*
Y336797D01*
X676106Y336214D01*
X676606Y335880D01*
X677189Y335797D01*
X677772Y335880D01*
X678272Y336214D01*
X678606Y336797D01*
G01Y335797D02*
Y339130D01*
G01X682789Y340797D02*
Y335797D01*
G01X681622Y339130D02*
X683956D01*
G01X692739Y336380D02*
X693156Y336047D01*
X693739Y335797D01*
X694239D01*
X694739Y335964D01*
X695072Y336214D01*
X695239Y336547D01*
X695156Y337047D01*
X694822Y337297D01*
X693322Y337797D01*
X692989Y338380D01*
X693156Y338797D01*
X693489Y339047D01*
X693989Y339130D01*
X694489Y339047D01*
X694989Y338797D01*
G01X699589Y335797D02*
X699089Y335880D01*
X698589Y336214D01*
X698256Y336797D01*
X698089Y337464D01*
X698256Y338130D01*
X698589Y338714D01*
X699089Y339047D01*
X699589Y339130D01*
X700089Y339047D01*
X700589Y338714D01*
X700922Y338130D01*
X701006Y337464D01*
X700922Y336797D01*
X700589Y336214D01*
X700089Y335880D01*
X699589Y335797D01*
G01X705189D02*
Y340797D01*
G01X712289D02*
Y335797D01*
G01Y336547D02*
X711956Y336130D01*
X711456Y335880D01*
X710872Y335797D01*
X710206Y335964D01*
X709706Y336380D01*
X709372Y336880D01*
X709289Y337464D01*
X709372Y338047D01*
X709706Y338547D01*
X710206Y338964D01*
X710872Y339130D01*
X711456Y339047D01*
X711872Y338880D01*
X712289Y338547D01*
G01X715139Y338047D02*
X717806D01*
X717556Y338630D01*
X717139Y338964D01*
X716556Y339130D01*
X715972Y339047D01*
X715472Y338797D01*
X715139Y338214D01*
X714972Y337714D01*
Y337214D01*
X715139Y336714D01*
X715556Y336214D01*
X716056Y335880D01*
X716639Y335797D01*
X717222Y335964D01*
X717806Y336464D01*
G01X720822Y335797D02*
Y339130D01*
G01Y338464D02*
X721239Y338797D01*
X721656Y339047D01*
X722239Y339130D01*
X722656Y339047D01*
X723156Y338797D01*
G01X730689Y335797D02*
Y339130D01*
G01Y338214D02*
X730939Y338630D01*
X731356Y338964D01*
X731939Y339130D01*
X732522Y338964D01*
X732939Y338630D01*
X733189Y338214D01*
Y335797D01*
G01Y338214D02*
X733439Y338630D01*
X733856Y338964D01*
X734439Y339130D01*
X735022Y338964D01*
X735439Y338630D01*
X735689Y338130D01*
Y335797D01*
G01X740289D02*
Y339130D01*
G01Y338547D02*
X739956Y338880D01*
X739456Y339047D01*
X738872Y339130D01*
X738289Y338964D01*
X737789Y338630D01*
X737456Y338130D01*
X737289Y337464D01*
X737456Y336797D01*
X737789Y336297D01*
X738289Y335964D01*
X738872Y335797D01*
X739456Y335880D01*
X739956Y336130D01*
X740289Y336464D01*
G01X743139Y336380D02*
X743556Y336047D01*
X744139Y335797D01*
X744639D01*
X745139Y335964D01*
X745472Y336214D01*
X745639Y336547D01*
X745556Y337047D01*
X745222Y337297D01*
X743722Y337797D01*
X743389Y338380D01*
X743556Y338797D01*
X743889Y339047D01*
X744389Y339130D01*
X744889Y339047D01*
X745389Y338797D01*
G01X748572Y335797D02*
Y340797D01*
G01X751239Y339130D02*
X748572Y337214D01*
G01X749656Y337964D02*
X751406Y335797D01*
G01X759689Y334130D02*
Y339130D01*
G01Y338380D02*
X760106Y338797D01*
X760522Y339047D01*
X761189Y339130D01*
X761772Y339047D01*
X762356Y338630D01*
X762606Y338047D01*
X762689Y337464D01*
X762606Y336880D01*
X762356Y336297D01*
X761856Y335964D01*
X761189Y335797D01*
X760606Y335880D01*
X760022Y336130D01*
X759689Y336464D01*
G01X768289Y335797D02*
Y339130D01*
G01Y338547D02*
X767956Y338880D01*
X767456Y339047D01*
X766872Y339130D01*
X766289Y338964D01*
X765789Y338630D01*
X765456Y338130D01*
X765289Y337464D01*
X765456Y336797D01*
X765789Y336297D01*
X766289Y335964D01*
X766872Y335797D01*
X767456Y335880D01*
X767956Y336130D01*
X768289Y336464D01*
G01X773889Y340797D02*
Y335797D01*
G01Y336547D02*
X773556Y336130D01*
X773056Y335880D01*
X772472Y335797D01*
X771806Y335964D01*
X771306Y336380D01*
X770972Y336880D01*
X770889Y337464D01*
X770972Y338047D01*
X771306Y338547D01*
X771806Y338964D01*
X772472Y339130D01*
X773056Y339047D01*
X773472Y338880D01*
X773889Y338547D01*
G01X783422Y334880D02*
X783756Y335964D01*
G01X796289Y335797D02*
Y339130D01*
G01Y338547D02*
X795956Y338880D01*
X795456Y339047D01*
X794872Y339130D01*
X794289Y338964D01*
X793789Y338630D01*
X793456Y338130D01*
X793289Y337464D01*
X793456Y336797D01*
X793789Y336297D01*
X794289Y335964D01*
X794872Y335797D01*
X795456Y335880D01*
X795956Y336130D01*
X796289Y336464D01*
G01X798972Y335797D02*
Y339130D01*
G01Y338297D02*
X799306Y338714D01*
X799806Y339047D01*
X800472Y339130D01*
X801056Y339047D01*
X801556Y338714D01*
X801806Y338130D01*
Y335797D01*
G01X804572D02*
Y339130D01*
G01Y338297D02*
X804906Y338714D01*
X805406Y339047D01*
X806072Y339130D01*
X806656Y339047D01*
X807156Y338714D01*
X807406Y338130D01*
Y335797D01*
G01X810172Y339130D02*
Y336797D01*
X810506Y336214D01*
X811006Y335880D01*
X811589Y335797D01*
X812172Y335880D01*
X812672Y336214D01*
X813006Y336797D01*
G01Y335797D02*
Y339130D01*
G01X818689Y335797D02*
Y339130D01*
G01Y338547D02*
X818356Y338880D01*
X817856Y339047D01*
X817272Y339130D01*
X816689Y338964D01*
X816189Y338630D01*
X815856Y338130D01*
X815689Y337464D01*
X815856Y336797D01*
X816189Y336297D01*
X816689Y335964D01*
X817272Y335797D01*
X817856Y335880D01*
X818356Y336130D01*
X818689Y336464D01*
G01X822789Y335797D02*
Y340797D01*
G01X832822Y335797D02*
Y339130D01*
G01Y338464D02*
X833239Y338797D01*
X833656Y339047D01*
X834239Y339130D01*
X834656Y339047D01*
X835156Y338797D01*
G01X839589Y339130D02*
Y335797D01*
G01Y340464D02*
X839422Y340547D01*
Y340714D01*
X839589Y340797D01*
X839756Y340714D01*
Y340547D01*
X839589Y340464D01*
G01X843772Y335797D02*
Y339130D01*
G01Y338297D02*
X844106Y338714D01*
X844606Y339047D01*
X845272Y339130D01*
X845856Y339047D01*
X846356Y338714D01*
X846606Y338130D01*
Y335797D01*
G01X849622Y334547D02*
X850206Y334214D01*
X850872Y334130D01*
X851456Y334214D01*
X851956Y334630D01*
X852289Y335214D01*
Y339130D01*
G01Y338464D02*
X851956Y338797D01*
X851456Y339047D01*
X850872Y339130D01*
X850206Y338964D01*
X849789Y338630D01*
X849456Y338047D01*
X849289Y337464D01*
X849372Y336964D01*
X849706Y336380D01*
X850206Y335964D01*
X850872Y335797D01*
X851372Y335880D01*
X851956Y336214D01*
X852289Y336547D01*
G01X860572Y335797D02*
Y339130D01*
G01Y338297D02*
X860906Y338714D01*
X861406Y339047D01*
X862072Y339130D01*
X862656Y339047D01*
X863156Y338714D01*
X863406Y338130D01*
Y335797D01*
G01X866339Y338047D02*
X869006D01*
X868756Y338630D01*
X868339Y338964D01*
X867756Y339130D01*
X867172Y339047D01*
X866672Y338797D01*
X866339Y338214D01*
X866172Y337714D01*
Y337214D01*
X866339Y336714D01*
X866756Y336214D01*
X867256Y335880D01*
X867839Y335797D01*
X868422Y335964D01*
X869006Y336464D01*
G01X871939Y338047D02*
X874606D01*
X874356Y338630D01*
X873939Y338964D01*
X873356Y339130D01*
X872772Y339047D01*
X872272Y338797D01*
X871939Y338214D01*
X871772Y337714D01*
Y337214D01*
X871939Y336714D01*
X872356Y336214D01*
X872856Y335880D01*
X873439Y335797D01*
X874022Y335964D01*
X874606Y336464D01*
G01X880289Y340797D02*
Y335797D01*
G01Y336547D02*
X879956Y336130D01*
X879456Y335880D01*
X878872Y335797D01*
X878206Y335964D01*
X877706Y336380D01*
X877372Y336880D01*
X877289Y337464D01*
X877372Y338047D01*
X877706Y338547D01*
X878206Y338964D01*
X878872Y339130D01*
X879456Y339047D01*
X879872Y338880D01*
X880289Y338547D01*
G01X577672Y496797D02*
Y500130D01*
G01Y499297D02*
X578006Y499714D01*
X578506Y500047D01*
X579172Y500130D01*
X579756Y500047D01*
X580256Y499714D01*
X580506Y499130D01*
Y496797D01*
G01X584689D02*
X584189Y496880D01*
X583689Y497214D01*
X583356Y497797D01*
X583189Y498464D01*
X583356Y499130D01*
X583689Y499714D01*
X584189Y500047D01*
X584689Y500130D01*
X585189Y500047D01*
X585689Y499714D01*
X586022Y499130D01*
X586106Y498464D01*
X586022Y497797D01*
X585689Y497214D01*
X585189Y496880D01*
X584689Y496797D01*
G01X594389Y495130D02*
Y500130D01*
G01Y499380D02*
X594806Y499797D01*
X595222Y500047D01*
X595889Y500130D01*
X596472Y500047D01*
X597056Y499630D01*
X597306Y499047D01*
X597389Y498464D01*
X597306Y497880D01*
X597056Y497297D01*
X596556Y496964D01*
X595889Y496797D01*
X595306Y496880D01*
X594722Y497130D01*
X594389Y497464D01*
G01X601489Y496797D02*
Y501797D01*
G01X605672Y500130D02*
Y497797D01*
X606006Y497214D01*
X606506Y496880D01*
X607089Y496797D01*
X607672Y496880D01*
X608172Y497214D01*
X608506Y497797D01*
G01Y496797D02*
Y500130D01*
G01X611522Y495547D02*
X612106Y495214D01*
X612772Y495130D01*
X613356Y495214D01*
X613856Y495630D01*
X614189Y496214D01*
Y500130D01*
G01Y499464D02*
X613856Y499797D01*
X613356Y500047D01*
X612772Y500130D01*
X612106Y499964D01*
X611689Y499630D01*
X611356Y499047D01*
X611189Y498464D01*
X611272Y497964D01*
X611606Y497380D01*
X612106Y496964D01*
X612772Y496797D01*
X613272Y496880D01*
X613856Y497214D01*
X614189Y497547D01*
G01X617122Y495547D02*
X617706Y495214D01*
X618372Y495130D01*
X618956Y495214D01*
X619456Y495630D01*
X619789Y496214D01*
Y500130D01*
G01Y499464D02*
X619456Y499797D01*
X618956Y500047D01*
X618372Y500130D01*
X617706Y499964D01*
X617289Y499630D01*
X616956Y499047D01*
X616789Y498464D01*
X616872Y497964D01*
X617206Y497380D01*
X617706Y496964D01*
X618372Y496797D01*
X618872Y496880D01*
X619456Y497214D01*
X619789Y497547D01*
G01X623889Y500130D02*
Y496797D01*
G01Y501464D02*
X623722Y501547D01*
Y501714D01*
X623889Y501797D01*
X624056Y501714D01*
Y501547D01*
X623889Y501464D01*
G01X628072Y496797D02*
Y500130D01*
G01Y499297D02*
X628406Y499714D01*
X628906Y500047D01*
X629572Y500130D01*
X630156Y500047D01*
X630656Y499714D01*
X630906Y499130D01*
Y496797D01*
G01X633922Y495547D02*
X634506Y495214D01*
X635172Y495130D01*
X635756Y495214D01*
X636256Y495630D01*
X636589Y496214D01*
Y500130D01*
G01Y499464D02*
X636256Y499797D01*
X635756Y500047D01*
X635172Y500130D01*
X634506Y499964D01*
X634089Y499630D01*
X633756Y499047D01*
X633589Y498464D01*
X633672Y497964D01*
X634006Y497380D01*
X634506Y496964D01*
X635172Y496797D01*
X635672Y496880D01*
X636256Y497214D01*
X636589Y497547D01*
G01X599089Y136797D02*
Y141797D01*
G01Y139297D02*
X599506Y139797D01*
X600006Y140047D01*
X600506Y140130D01*
X601256Y139964D01*
X601756Y139630D01*
X602089Y139047D01*
Y138380D01*
X601922Y137714D01*
X601589Y137214D01*
X601006Y136880D01*
X600506Y136797D01*
X600006Y136880D01*
X599506Y137130D01*
X599089Y137547D01*
G01X604772Y140130D02*
Y137797D01*
X605106Y137214D01*
X605606Y136880D01*
X606189Y136797D01*
X606772Y136880D01*
X607272Y137214D01*
X607606Y137797D01*
G01Y136797D02*
Y140130D01*
G01X610289Y136797D02*
Y141797D01*
G01Y139297D02*
X610706Y139797D01*
X611206Y140047D01*
X611706Y140130D01*
X612456Y139964D01*
X612956Y139630D01*
X613289Y139047D01*
Y138380D01*
X613122Y137714D01*
X612789Y137214D01*
X612206Y136880D01*
X611706Y136797D01*
X611206Y136880D01*
X610706Y137130D01*
X610289Y137547D01*
G01X615889Y136797D02*
Y141797D01*
G01Y139297D02*
X616306Y139797D01*
X616806Y140047D01*
X617306Y140130D01*
X618056Y139964D01*
X618556Y139630D01*
X618889Y139047D01*
Y138380D01*
X618722Y137714D01*
X618389Y137214D01*
X617806Y136880D01*
X617306Y136797D01*
X616806Y136880D01*
X616306Y137130D01*
X615889Y137547D01*
G01X622989Y136797D02*
Y141797D01*
G01X627339Y139047D02*
X630006D01*
X629756Y139630D01*
X629339Y139964D01*
X628756Y140130D01*
X628172Y140047D01*
X627672Y139797D01*
X627339Y139214D01*
X627172Y138714D01*
Y138214D01*
X627339Y137714D01*
X627756Y137214D01*
X628256Y136880D01*
X628839Y136797D01*
X629422Y136964D01*
X630006Y137464D01*
G01X639789Y140130D02*
Y136797D01*
G01Y141464D02*
X639622Y141547D01*
Y141714D01*
X639789Y141797D01*
X639956Y141714D01*
Y141547D01*
X639789Y141464D01*
G01X643972Y136797D02*
Y140130D01*
G01Y139297D02*
X644306Y139714D01*
X644806Y140047D01*
X645472Y140130D01*
X646056Y140047D01*
X646556Y139714D01*
X646806Y139130D01*
Y136797D01*
G01X649739Y137380D02*
X650156Y137047D01*
X650739Y136797D01*
X651239D01*
X651739Y136964D01*
X652072Y137214D01*
X652239Y137547D01*
X652156Y138047D01*
X651822Y138297D01*
X650322Y138797D01*
X649989Y139380D01*
X650156Y139797D01*
X650489Y140047D01*
X650989Y140130D01*
X651489Y140047D01*
X651989Y139797D01*
G01X656589Y140130D02*
Y136797D01*
G01Y141464D02*
X656422Y141547D01*
Y141714D01*
X656589Y141797D01*
X656756Y141714D01*
Y141547D01*
X656589Y141464D01*
G01X663689Y141797D02*
Y136797D01*
G01Y137547D02*
X663356Y137130D01*
X662856Y136880D01*
X662272Y136797D01*
X661606Y136964D01*
X661106Y137380D01*
X660772Y137880D01*
X660689Y138464D01*
X660772Y139047D01*
X661106Y139547D01*
X661606Y139964D01*
X662272Y140130D01*
X662856Y140047D01*
X663272Y139880D01*
X663689Y139547D01*
G01X666539Y139047D02*
X669206D01*
X668956Y139630D01*
X668539Y139964D01*
X667956Y140130D01*
X667372Y140047D01*
X666872Y139797D01*
X666539Y139214D01*
X666372Y138714D01*
Y138214D01*
X666539Y137714D01*
X666956Y137214D01*
X667456Y136880D01*
X668039Y136797D01*
X668622Y136964D01*
X669206Y137464D01*
G01X678989Y141797D02*
Y136797D01*
G01X677822Y140130D02*
X680156D01*
G01X683172Y136797D02*
Y141797D01*
G01Y139380D02*
X683589Y139797D01*
X684006Y140047D01*
X684672Y140130D01*
X685172Y140047D01*
X685756Y139714D01*
X686006Y139214D01*
Y136797D01*
G01X688939Y139047D02*
X691606D01*
X691356Y139630D01*
X690939Y139964D01*
X690356Y140130D01*
X689772Y140047D01*
X689272Y139797D01*
X688939Y139214D01*
X688772Y138714D01*
Y138214D01*
X688939Y137714D01*
X689356Y137214D01*
X689856Y136880D01*
X690439Y136797D01*
X691022Y136964D01*
X691606Y137464D01*
G01X700222Y136797D02*
Y140130D01*
G01Y139464D02*
X700639Y139797D01*
X701056Y140047D01*
X701639Y140130D01*
X702056Y140047D01*
X702556Y139797D01*
G01X705739Y139047D02*
X708406D01*
X708156Y139630D01*
X707739Y139964D01*
X707156Y140130D01*
X706572Y140047D01*
X706072Y139797D01*
X705739Y139214D01*
X705572Y138714D01*
Y138214D01*
X705739Y137714D01*
X706156Y137214D01*
X706656Y136880D01*
X707239Y136797D01*
X707822Y136964D01*
X708406Y137464D01*
G01X711339Y137380D02*
X711756Y137047D01*
X712339Y136797D01*
X712839D01*
X713339Y136964D01*
X713672Y137214D01*
X713839Y137547D01*
X713756Y138047D01*
X713422Y138297D01*
X711922Y138797D01*
X711589Y139380D01*
X711756Y139797D01*
X712089Y140047D01*
X712589Y140130D01*
X713089Y140047D01*
X713589Y139797D01*
G01X718189Y140130D02*
Y136797D01*
G01Y141464D02*
X718022Y141547D01*
Y141714D01*
X718189Y141797D01*
X718356Y141714D01*
Y141547D01*
X718189Y141464D01*
G01X722372Y136797D02*
Y140130D01*
G01Y139297D02*
X722706Y139714D01*
X723206Y140047D01*
X723872Y140130D01*
X724456Y140047D01*
X724956Y139714D01*
X725206Y139130D01*
Y136797D01*
G01X729389Y136630D02*
X729222Y136714D01*
Y136880D01*
X729389Y136964D01*
X729556Y136880D01*
Y136714D01*
X729389Y136630D01*
G01X599089Y179797D02*
Y184797D01*
G01Y182297D02*
X599506Y182797D01*
X600006Y183047D01*
X600506Y183130D01*
X601256Y182964D01*
X601756Y182630D01*
X602089Y182047D01*
Y181380D01*
X601922Y180714D01*
X601589Y180214D01*
X601006Y179880D01*
X600506Y179797D01*
X600006Y179880D01*
X599506Y180130D01*
X599089Y180547D01*
G01X604772Y183130D02*
Y180797D01*
X605106Y180214D01*
X605606Y179880D01*
X606189Y179797D01*
X606772Y179880D01*
X607272Y180214D01*
X607606Y180797D01*
G01Y179797D02*
Y183130D01*
G01X610289Y179797D02*
Y184797D01*
G01Y182297D02*
X610706Y182797D01*
X611206Y183047D01*
X611706Y183130D01*
X612456Y182964D01*
X612956Y182630D01*
X613289Y182047D01*
Y181380D01*
X613122Y180714D01*
X612789Y180214D01*
X612206Y179880D01*
X611706Y179797D01*
X611206Y179880D01*
X610706Y180130D01*
X610289Y180547D01*
G01X615889Y179797D02*
Y184797D01*
G01Y182297D02*
X616306Y182797D01*
X616806Y183047D01*
X617306Y183130D01*
X618056Y182964D01*
X618556Y182630D01*
X618889Y182047D01*
Y181380D01*
X618722Y180714D01*
X618389Y180214D01*
X617806Y179880D01*
X617306Y179797D01*
X616806Y179880D01*
X616306Y180130D01*
X615889Y180547D01*
G01X622989Y179797D02*
Y184797D01*
G01X627339Y182047D02*
X630006D01*
X629756Y182630D01*
X629339Y182964D01*
X628756Y183130D01*
X628172Y183047D01*
X627672Y182797D01*
X627339Y182214D01*
X627172Y181714D01*
Y181214D01*
X627339Y180714D01*
X627756Y180214D01*
X628256Y179880D01*
X628839Y179797D01*
X629422Y179964D01*
X630006Y180464D01*
G01X639789Y183130D02*
Y179797D01*
G01Y184464D02*
X639622Y184547D01*
Y184714D01*
X639789Y184797D01*
X639956Y184714D01*
Y184547D01*
X639789Y184464D01*
G01X643972Y179797D02*
Y183130D01*
G01Y182297D02*
X644306Y182714D01*
X644806Y183047D01*
X645472Y183130D01*
X646056Y183047D01*
X646556Y182714D01*
X646806Y182130D01*
Y179797D01*
G01X649739Y180380D02*
X650156Y180047D01*
X650739Y179797D01*
X651239D01*
X651739Y179964D01*
X652072Y180214D01*
X652239Y180547D01*
X652156Y181047D01*
X651822Y181297D01*
X650322Y181797D01*
X649989Y182380D01*
X650156Y182797D01*
X650489Y183047D01*
X650989Y183130D01*
X651489Y183047D01*
X651989Y182797D01*
G01X656589Y183130D02*
Y179797D01*
G01Y184464D02*
X656422Y184547D01*
Y184714D01*
X656589Y184797D01*
X656756Y184714D01*
Y184547D01*
X656589Y184464D01*
G01X663689Y184797D02*
Y179797D01*
G01Y180547D02*
X663356Y180130D01*
X662856Y179880D01*
X662272Y179797D01*
X661606Y179964D01*
X661106Y180380D01*
X660772Y180880D01*
X660689Y181464D01*
X660772Y182047D01*
X661106Y182547D01*
X661606Y182964D01*
X662272Y183130D01*
X662856Y183047D01*
X663272Y182880D01*
X663689Y182547D01*
G01X666539Y182047D02*
X669206D01*
X668956Y182630D01*
X668539Y182964D01*
X667956Y183130D01*
X667372Y183047D01*
X666872Y182797D01*
X666539Y182214D01*
X666372Y181714D01*
Y181214D01*
X666539Y180714D01*
X666956Y180214D01*
X667456Y179880D01*
X668039Y179797D01*
X668622Y179964D01*
X669206Y180464D01*
G01X678989Y184797D02*
Y179797D01*
G01X677822Y183130D02*
X680156D01*
G01X683172Y179797D02*
Y184797D01*
G01Y182380D02*
X683589Y182797D01*
X684006Y183047D01*
X684672Y183130D01*
X685172Y183047D01*
X685756Y182714D01*
X686006Y182214D01*
Y179797D01*
G01X688939Y182047D02*
X691606D01*
X691356Y182630D01*
X690939Y182964D01*
X690356Y183130D01*
X689772Y183047D01*
X689272Y182797D01*
X688939Y182214D01*
X688772Y181714D01*
Y181214D01*
X688939Y180714D01*
X689356Y180214D01*
X689856Y179880D01*
X690439Y179797D01*
X691022Y179964D01*
X691606Y180464D01*
G01X700222Y179797D02*
Y183130D01*
G01Y182464D02*
X700639Y182797D01*
X701056Y183047D01*
X701639Y183130D01*
X702056Y183047D01*
X702556Y182797D01*
G01X705739Y182047D02*
X708406D01*
X708156Y182630D01*
X707739Y182964D01*
X707156Y183130D01*
X706572Y183047D01*
X706072Y182797D01*
X705739Y182214D01*
X705572Y181714D01*
Y181214D01*
X705739Y180714D01*
X706156Y180214D01*
X706656Y179880D01*
X707239Y179797D01*
X707822Y179964D01*
X708406Y180464D01*
G01X711339Y180380D02*
X711756Y180047D01*
X712339Y179797D01*
X712839D01*
X713339Y179964D01*
X713672Y180214D01*
X713839Y180547D01*
X713756Y181047D01*
X713422Y181297D01*
X711922Y181797D01*
X711589Y182380D01*
X711756Y182797D01*
X712089Y183047D01*
X712589Y183130D01*
X713089Y183047D01*
X713589Y182797D01*
G01X718189Y183130D02*
Y179797D01*
G01Y184464D02*
X718022Y184547D01*
Y184714D01*
X718189Y184797D01*
X718356Y184714D01*
Y184547D01*
X718189Y184464D01*
G01X722372Y179797D02*
Y183130D01*
G01Y182297D02*
X722706Y182714D01*
X723206Y183047D01*
X723872Y183130D01*
X724456Y183047D01*
X724956Y182714D01*
X725206Y182130D01*
Y179797D01*
G01X729389Y179630D02*
X729222Y179714D01*
Y179880D01*
X729389Y179964D01*
X729556Y179880D01*
Y179714D01*
X729389Y179630D01*
G01X612089Y252130D02*
X613589Y248797D01*
X615089Y252130D01*
G01X619189D02*
Y248797D01*
G01Y253464D02*
X619022Y253547D01*
Y253714D01*
X619189Y253797D01*
X619356Y253714D01*
Y253547D01*
X619189Y253464D01*
G01X626289Y248797D02*
Y252130D01*
G01Y251547D02*
X625956Y251880D01*
X625456Y252047D01*
X624872Y252130D01*
X624289Y251964D01*
X623789Y251630D01*
X623456Y251130D01*
X623289Y250464D01*
X623456Y249797D01*
X623789Y249297D01*
X624289Y248964D01*
X624872Y248797D01*
X625456Y248880D01*
X625956Y249130D01*
X626289Y249464D01*
G01X634739Y249380D02*
X635156Y249047D01*
X635739Y248797D01*
X636239D01*
X636739Y248964D01*
X637072Y249214D01*
X637239Y249547D01*
X637156Y250047D01*
X636822Y250297D01*
X635322Y250797D01*
X634989Y251380D01*
X635156Y251797D01*
X635489Y252047D01*
X635989Y252130D01*
X636489Y252047D01*
X636989Y251797D01*
G01X640172Y248797D02*
Y253797D01*
G01Y251380D02*
X640589Y251797D01*
X641006Y252047D01*
X641672Y252130D01*
X642172Y252047D01*
X642756Y251714D01*
X643006Y251214D01*
Y248797D01*
G01X648689D02*
Y252130D01*
G01Y251547D02*
X648356Y251880D01*
X647856Y252047D01*
X647272Y252130D01*
X646689Y251964D01*
X646189Y251630D01*
X645856Y251130D01*
X645689Y250464D01*
X645856Y249797D01*
X646189Y249297D01*
X646689Y248964D01*
X647272Y248797D01*
X647856Y248880D01*
X648356Y249130D01*
X648689Y249464D01*
G01X652789Y248797D02*
Y253797D01*
G01X658389Y248797D02*
Y253797D01*
G01X668089Y248797D02*
Y253797D01*
G01Y251297D02*
X668506Y251797D01*
X669006Y252047D01*
X669506Y252130D01*
X670256Y251964D01*
X670756Y251630D01*
X671089Y251047D01*
Y250380D01*
X670922Y249714D01*
X670589Y249214D01*
X670006Y248880D01*
X669506Y248797D01*
X669006Y248880D01*
X668506Y249130D01*
X668089Y249547D01*
G01X673939Y251047D02*
X676606D01*
X676356Y251630D01*
X675939Y251964D01*
X675356Y252130D01*
X674772Y252047D01*
X674272Y251797D01*
X673939Y251214D01*
X673772Y250714D01*
Y250214D01*
X673939Y249714D01*
X674356Y249214D01*
X674856Y248880D01*
X675439Y248797D01*
X676022Y248964D01*
X676606Y249464D01*
G01X684306Y252130D02*
X685306Y248797D01*
X686389Y252130D01*
X687472Y248797D01*
X688472Y252130D01*
G01X691989D02*
Y248797D01*
G01Y253464D02*
X691822Y253547D01*
Y253714D01*
X691989Y253797D01*
X692156Y253714D01*
Y253547D01*
X691989Y253464D01*
G01X697589Y253797D02*
Y248797D01*
G01X696422Y252130D02*
X698756D01*
G01X701772Y248797D02*
Y253797D01*
G01Y251380D02*
X702189Y251797D01*
X702606Y252047D01*
X703272Y252130D01*
X703772Y252047D01*
X704356Y251714D01*
X704606Y251214D01*
Y248797D01*
G01X716056D02*
X712722Y250464D01*
X716056Y252130D01*
G01X725589Y248797D02*
X726172Y248880D01*
X726839Y249130D01*
X727256Y249547D01*
X727422Y250130D01*
X727256Y250714D01*
X726756Y251214D01*
X726006Y251464D01*
X725172D01*
X724672Y251630D01*
X724256Y252047D01*
X724089Y252630D01*
X724339Y253214D01*
X724922Y253630D01*
X725589Y253797D01*
X726256Y253630D01*
X726839Y253214D01*
X727089Y252630D01*
X726922Y252047D01*
X726506Y251630D01*
X726006Y251464D01*
X725172D01*
X724422Y251214D01*
X723922Y250714D01*
X723756Y250130D01*
X723922Y249547D01*
X724339Y249130D01*
X725006Y248880D01*
X725589Y248797D01*
G01X731189Y253797D02*
X730522Y253630D01*
X730022Y253214D01*
X729689Y252714D01*
X729439Y252047D01*
X729356Y251297D01*
X729439Y250547D01*
X729689Y249880D01*
X730022Y249380D01*
X730522Y248964D01*
X731189Y248797D01*
X731856Y248964D01*
X732356Y249380D01*
X732689Y249880D01*
X732939Y250547D01*
X733022Y251297D01*
X732939Y252047D01*
X732689Y252714D01*
X732356Y253214D01*
X731856Y253630D01*
X731189Y253797D01*
G01X740889Y248630D02*
X743889Y253797D01*
G01X740889D02*
X740389Y253630D01*
X740139Y253380D01*
X739972Y252880D01*
X740139Y252380D01*
X740389Y252130D01*
X740889Y251964D01*
X741389Y252130D01*
X741639Y252380D01*
X741806Y252880D01*
X741639Y253380D01*
X741389Y253630D01*
X740889Y253797D01*
G01X743889Y250464D02*
X743389Y250297D01*
X743139Y250047D01*
X742972Y249547D01*
X743139Y249047D01*
X743389Y248797D01*
X743889Y248630D01*
X744389Y248797D01*
X744639Y249047D01*
X744806Y249547D01*
X744639Y250047D01*
X744389Y250297D01*
X743889Y250464D01*
G01X752339Y249380D02*
X752756Y249047D01*
X753339Y248797D01*
X753839D01*
X754339Y248964D01*
X754672Y249214D01*
X754839Y249547D01*
X754756Y250047D01*
X754422Y250297D01*
X752922Y250797D01*
X752589Y251380D01*
X752756Y251797D01*
X753089Y252047D01*
X753589Y252130D01*
X754089Y252047D01*
X754589Y251797D01*
G01X759189Y248797D02*
X758689Y248880D01*
X758189Y249214D01*
X757856Y249797D01*
X757689Y250464D01*
X757856Y251130D01*
X758189Y251714D01*
X758689Y252047D01*
X759189Y252130D01*
X759689Y252047D01*
X760189Y251714D01*
X760522Y251130D01*
X760606Y250464D01*
X760522Y249797D01*
X760189Y249214D01*
X759689Y248880D01*
X759189Y248797D01*
G01X764789D02*
Y253797D01*
G01X771889D02*
Y248797D01*
G01Y249547D02*
X771556Y249130D01*
X771056Y248880D01*
X770472Y248797D01*
X769806Y248964D01*
X769306Y249380D01*
X768972Y249880D01*
X768889Y250464D01*
X768972Y251047D01*
X769306Y251547D01*
X769806Y251964D01*
X770472Y252130D01*
X771056Y252047D01*
X771472Y251880D01*
X771889Y251547D01*
G01X774739Y251047D02*
X777406D01*
X777156Y251630D01*
X776739Y251964D01*
X776156Y252130D01*
X775572Y252047D01*
X775072Y251797D01*
X774739Y251214D01*
X774572Y250714D01*
Y250214D01*
X774739Y249714D01*
X775156Y249214D01*
X775656Y248880D01*
X776239Y248797D01*
X776822Y248964D01*
X777406Y249464D01*
G01X780422Y248797D02*
Y252130D01*
G01Y251464D02*
X780839Y251797D01*
X781256Y252047D01*
X781839Y252130D01*
X782256Y252047D01*
X782756Y251797D01*
G01X790289Y248797D02*
Y252130D01*
G01Y251214D02*
X790539Y251630D01*
X790956Y251964D01*
X791539Y252130D01*
X792122Y251964D01*
X792539Y251630D01*
X792789Y251214D01*
Y248797D01*
G01Y251214D02*
X793039Y251630D01*
X793456Y251964D01*
X794039Y252130D01*
X794622Y251964D01*
X795039Y251630D01*
X795289Y251130D01*
Y248797D01*
G01X799889D02*
Y252130D01*
G01Y251547D02*
X799556Y251880D01*
X799056Y252047D01*
X798472Y252130D01*
X797889Y251964D01*
X797389Y251630D01*
X797056Y251130D01*
X796889Y250464D01*
X797056Y249797D01*
X797389Y249297D01*
X797889Y248964D01*
X798472Y248797D01*
X799056Y248880D01*
X799556Y249130D01*
X799889Y249464D01*
G01X802739Y249380D02*
X803156Y249047D01*
X803739Y248797D01*
X804239D01*
X804739Y248964D01*
X805072Y249214D01*
X805239Y249547D01*
X805156Y250047D01*
X804822Y250297D01*
X803322Y250797D01*
X802989Y251380D01*
X803156Y251797D01*
X803489Y252047D01*
X803989Y252130D01*
X804489Y252047D01*
X804989Y251797D01*
G01X808172Y248797D02*
Y253797D01*
G01X810839Y252130D02*
X808172Y250214D01*
G01X809256Y250964D02*
X811006Y248797D01*
G01X601089Y257797D02*
Y262797D01*
G01Y260297D02*
X601506Y260797D01*
X602006Y261047D01*
X602506Y261130D01*
X603256Y260964D01*
X603756Y260630D01*
X604089Y260047D01*
Y259380D01*
X603922Y258714D01*
X603589Y258214D01*
X603006Y257880D01*
X602506Y257797D01*
X602006Y257880D01*
X601506Y258130D01*
X601089Y258547D01*
G01X608189Y257630D02*
X608022Y257714D01*
Y257880D01*
X608189Y257964D01*
X608356Y257880D01*
Y257714D01*
X608189Y257630D01*
G01X614456Y260464D02*
X614789Y260714D01*
X615039Y261130D01*
X615206Y261714D01*
X615039Y262214D01*
X614706Y262547D01*
X614122Y262797D01*
X611872D01*
Y257797D01*
X614622D01*
X615206Y258130D01*
X615539Y258630D01*
X615706Y259214D01*
X615539Y259797D01*
X615039Y260297D01*
X614456Y260464D01*
X611872D01*
G01X619389Y257797D02*
X618889Y257880D01*
X618389Y258214D01*
X618056Y258797D01*
X617889Y259464D01*
X618056Y260130D01*
X618389Y260714D01*
X618889Y261047D01*
X619389Y261130D01*
X619889Y261047D01*
X620389Y260714D01*
X620722Y260130D01*
X620806Y259464D01*
X620722Y258797D01*
X620389Y258214D01*
X619889Y257880D01*
X619389Y257797D01*
G01X626489D02*
Y261130D01*
G01Y260547D02*
X626156Y260880D01*
X625656Y261047D01*
X625072Y261130D01*
X624489Y260964D01*
X623989Y260630D01*
X623656Y260130D01*
X623489Y259464D01*
X623656Y258797D01*
X623989Y258297D01*
X624489Y257964D01*
X625072Y257797D01*
X625656Y257880D01*
X626156Y258130D01*
X626489Y258464D01*
G01X629422Y257797D02*
Y261130D01*
G01Y260464D02*
X629839Y260797D01*
X630256Y261047D01*
X630839Y261130D01*
X631256Y261047D01*
X631756Y260797D01*
G01X637689Y262797D02*
Y257797D01*
G01Y258547D02*
X637356Y258130D01*
X636856Y257880D01*
X636272Y257797D01*
X635606Y257964D01*
X635106Y258380D01*
X634772Y258880D01*
X634689Y259464D01*
X634772Y260047D01*
X635106Y260547D01*
X635606Y260964D01*
X636272Y261130D01*
X636856Y261047D01*
X637272Y260880D01*
X637689Y260547D01*
G01X647389Y262797D02*
Y257797D01*
G01X646222Y261130D02*
X648556D01*
G01X651572Y257797D02*
Y262797D01*
G01Y260380D02*
X651989Y260797D01*
X652406Y261047D01*
X653072Y261130D01*
X653572Y261047D01*
X654156Y260714D01*
X654406Y260214D01*
Y257797D01*
G01X658589Y261130D02*
Y257797D01*
G01Y262464D02*
X658422Y262547D01*
Y262714D01*
X658589Y262797D01*
X658756Y262714D01*
Y262547D01*
X658589Y262464D01*
G01X665522Y260714D02*
X664939Y261047D01*
X664439Y261130D01*
X663772Y260964D01*
X663272Y260630D01*
X662939Y260047D01*
X662856Y259464D01*
X662939Y258880D01*
X663272Y258380D01*
X663772Y257964D01*
X664439Y257797D01*
X665022Y257964D01*
X665522Y258297D01*
G01X668372Y257797D02*
Y262797D01*
G01X671039Y261130D02*
X668372Y259214D01*
G01X669456Y259964D02*
X671206Y257797D01*
G01X673972D02*
Y261130D01*
G01Y260297D02*
X674306Y260714D01*
X674806Y261047D01*
X675472Y261130D01*
X676056Y261047D01*
X676556Y260714D01*
X676806Y260130D01*
Y257797D01*
G01X679739Y260047D02*
X682406D01*
X682156Y260630D01*
X681739Y260964D01*
X681156Y261130D01*
X680572Y261047D01*
X680072Y260797D01*
X679739Y260214D01*
X679572Y259714D01*
Y259214D01*
X679739Y258714D01*
X680156Y258214D01*
X680656Y257880D01*
X681239Y257797D01*
X681822Y257964D01*
X682406Y258464D01*
G01X685339Y258380D02*
X685756Y258047D01*
X686339Y257797D01*
X686839D01*
X687339Y257964D01*
X687672Y258214D01*
X687839Y258547D01*
X687756Y259047D01*
X687422Y259297D01*
X685922Y259797D01*
X685589Y260380D01*
X685756Y260797D01*
X686089Y261047D01*
X686589Y261130D01*
X687089Y261047D01*
X687589Y260797D01*
G01X690939Y258380D02*
X691356Y258047D01*
X691939Y257797D01*
X692439D01*
X692939Y257964D01*
X693272Y258214D01*
X693439Y258547D01*
X693356Y259047D01*
X693022Y259297D01*
X691522Y259797D01*
X691189Y260380D01*
X691356Y260797D01*
X691689Y261047D01*
X692189Y261130D01*
X692689Y261047D01*
X693189Y260797D01*
G01X705056Y257797D02*
X701722Y259464D01*
X705056Y261130D01*
G01X714589Y262797D02*
X713922Y262630D01*
X713422Y262214D01*
X713089Y261714D01*
X712839Y261047D01*
X712756Y260297D01*
X712839Y259547D01*
X713089Y258880D01*
X713422Y258380D01*
X713922Y257964D01*
X714589Y257797D01*
X715256Y257964D01*
X715756Y258380D01*
X716089Y258880D01*
X716339Y259547D01*
X716422Y260297D01*
X716339Y261047D01*
X716089Y261714D01*
X715756Y262214D01*
X715256Y262630D01*
X714589Y262797D01*
G01X720189Y257630D02*
X720022Y257714D01*
Y257880D01*
X720189Y257964D01*
X720356Y257880D01*
Y257714D01*
X720189Y257630D01*
G01X724372Y258380D02*
X724956Y257964D01*
X725622Y257797D01*
X726289Y257964D01*
X726872Y258464D01*
X727289Y259214D01*
X727456Y259964D01*
Y260880D01*
X727289Y261630D01*
X726872Y262297D01*
X726372Y262630D01*
X725789Y262797D01*
X725122Y262630D01*
X724622Y262297D01*
X724289Y261797D01*
X724122Y261130D01*
X724289Y260547D01*
X724706Y259964D01*
X725206Y259630D01*
X725789Y259547D01*
X726456Y259714D01*
X726956Y260130D01*
X727456Y260880D01*
G01X728889Y257797D02*
Y261130D01*
G01Y260214D02*
X729139Y260630D01*
X729556Y260964D01*
X730139Y261130D01*
X730722Y260964D01*
X731139Y260630D01*
X731389Y260214D01*
Y257797D01*
G01Y260214D02*
X731639Y260630D01*
X732056Y260964D01*
X732639Y261130D01*
X733222Y260964D01*
X733639Y260630D01*
X733889Y260130D01*
Y257797D01*
G01X734489D02*
Y261130D01*
G01Y260214D02*
X734739Y260630D01*
X735156Y260964D01*
X735739Y261130D01*
X736322Y260964D01*
X736739Y260630D01*
X736989Y260214D01*
Y257797D01*
G01Y260214D02*
X737239Y260630D01*
X737656Y260964D01*
X738239Y261130D01*
X738822Y260964D01*
X739239Y260630D01*
X739489Y260130D01*
Y257797D01*
G01X742589Y257630D02*
X742422Y257714D01*
Y257880D01*
X742589Y257964D01*
X742756Y257880D01*
Y257714D01*
X742589Y257630D01*
G01Y259880D02*
X742422Y259964D01*
Y260130D01*
X742589Y260214D01*
X742756Y260130D01*
Y259964D01*
X742589Y259880D01*
G01X611089Y271130D02*
X612589Y267797D01*
X614089Y271130D01*
G01X618189D02*
Y267797D01*
G01Y272464D02*
X618022Y272547D01*
Y272714D01*
X618189Y272797D01*
X618356Y272714D01*
Y272547D01*
X618189Y272464D01*
G01X625289Y267797D02*
Y271130D01*
G01Y270547D02*
X624956Y270880D01*
X624456Y271047D01*
X623872Y271130D01*
X623289Y270964D01*
X622789Y270630D01*
X622456Y270130D01*
X622289Y269464D01*
X622456Y268797D01*
X622789Y268297D01*
X623289Y267964D01*
X623872Y267797D01*
X624456Y267880D01*
X624956Y268130D01*
X625289Y268464D01*
G01X633739Y268380D02*
X634156Y268047D01*
X634739Y267797D01*
X635239D01*
X635739Y267964D01*
X636072Y268214D01*
X636239Y268547D01*
X636156Y269047D01*
X635822Y269297D01*
X634322Y269797D01*
X633989Y270380D01*
X634156Y270797D01*
X634489Y271047D01*
X634989Y271130D01*
X635489Y271047D01*
X635989Y270797D01*
G01X639172Y267797D02*
Y272797D01*
G01Y270380D02*
X639589Y270797D01*
X640006Y271047D01*
X640672Y271130D01*
X641172Y271047D01*
X641756Y270714D01*
X642006Y270214D01*
Y267797D01*
G01X647689D02*
Y271130D01*
G01Y270547D02*
X647356Y270880D01*
X646856Y271047D01*
X646272Y271130D01*
X645689Y270964D01*
X645189Y270630D01*
X644856Y270130D01*
X644689Y269464D01*
X644856Y268797D01*
X645189Y268297D01*
X645689Y267964D01*
X646272Y267797D01*
X646856Y267880D01*
X647356Y268130D01*
X647689Y268464D01*
G01X651789Y267797D02*
Y272797D01*
G01X657389Y267797D02*
Y272797D01*
G01X667089Y267797D02*
Y272797D01*
G01Y270297D02*
X667506Y270797D01*
X668006Y271047D01*
X668506Y271130D01*
X669256Y270964D01*
X669756Y270630D01*
X670089Y270047D01*
Y269380D01*
X669922Y268714D01*
X669589Y268214D01*
X669006Y267880D01*
X668506Y267797D01*
X668006Y267880D01*
X667506Y268130D01*
X667089Y268547D01*
G01X672939Y270047D02*
X675606D01*
X675356Y270630D01*
X674939Y270964D01*
X674356Y271130D01*
X673772Y271047D01*
X673272Y270797D01*
X672939Y270214D01*
X672772Y269714D01*
Y269214D01*
X672939Y268714D01*
X673356Y268214D01*
X673856Y267880D01*
X674439Y267797D01*
X675022Y267964D01*
X675606Y268464D01*
G01X683889Y266130D02*
Y271130D01*
G01Y270380D02*
X684306Y270797D01*
X684722Y271047D01*
X685389Y271130D01*
X685972Y271047D01*
X686556Y270630D01*
X686806Y270047D01*
X686889Y269464D01*
X686806Y268880D01*
X686556Y268297D01*
X686056Y267964D01*
X685389Y267797D01*
X684806Y267880D01*
X684222Y268130D01*
X683889Y268464D01*
G01X690989Y267797D02*
Y272797D01*
G01X695172Y271130D02*
Y268797D01*
X695506Y268214D01*
X696006Y267880D01*
X696589Y267797D01*
X697172Y267880D01*
X697672Y268214D01*
X698006Y268797D01*
G01Y267797D02*
Y271130D01*
G01X701022Y266547D02*
X701606Y266214D01*
X702272Y266130D01*
X702856Y266214D01*
X703356Y266630D01*
X703689Y267214D01*
Y271130D01*
G01Y270464D02*
X703356Y270797D01*
X702856Y271047D01*
X702272Y271130D01*
X701606Y270964D01*
X701189Y270630D01*
X700856Y270047D01*
X700689Y269464D01*
X700772Y268964D01*
X701106Y268380D01*
X701606Y267964D01*
X702272Y267797D01*
X702772Y267880D01*
X703356Y268214D01*
X703689Y268547D01*
G01X706622Y266547D02*
X707206Y266214D01*
X707872Y266130D01*
X708456Y266214D01*
X708956Y266630D01*
X709289Y267214D01*
Y271130D01*
G01Y270464D02*
X708956Y270797D01*
X708456Y271047D01*
X707872Y271130D01*
X707206Y270964D01*
X706789Y270630D01*
X706456Y270047D01*
X706289Y269464D01*
X706372Y268964D01*
X706706Y268380D01*
X707206Y267964D01*
X707872Y267797D01*
X708372Y267880D01*
X708956Y268214D01*
X709289Y268547D01*
G01X712139Y270047D02*
X714806D01*
X714556Y270630D01*
X714139Y270964D01*
X713556Y271130D01*
X712972Y271047D01*
X712472Y270797D01*
X712139Y270214D01*
X711972Y269714D01*
Y269214D01*
X712139Y268714D01*
X712556Y268214D01*
X713056Y267880D01*
X713639Y267797D01*
X714222Y267964D01*
X714806Y268464D01*
G01X720489Y272797D02*
Y267797D01*
G01Y268547D02*
X720156Y268130D01*
X719656Y267880D01*
X719072Y267797D01*
X718406Y267964D01*
X717906Y268380D01*
X717572Y268880D01*
X717489Y269464D01*
X717572Y270047D01*
X717906Y270547D01*
X718406Y270964D01*
X719072Y271130D01*
X719656Y271047D01*
X720072Y270880D01*
X720489Y270547D01*
G01X728106Y271130D02*
X729106Y267797D01*
X730189Y271130D01*
X731272Y267797D01*
X732272Y271130D01*
G01X735789D02*
Y267797D01*
G01Y272464D02*
X735622Y272547D01*
Y272714D01*
X735789Y272797D01*
X735956Y272714D01*
Y272547D01*
X735789Y272464D01*
G01X741389Y272797D02*
Y267797D01*
G01X740222Y271130D02*
X742556D01*
G01X745572Y267797D02*
Y272797D01*
G01Y270380D02*
X745989Y270797D01*
X746406Y271047D01*
X747072Y271130D01*
X747572Y271047D01*
X748156Y270714D01*
X748406Y270214D01*
Y267797D01*
G01X759856D02*
X756522Y269464D01*
X759856Y271130D01*
G01X767556Y268547D02*
X768056Y268130D01*
X768639Y267880D01*
X769389Y267797D01*
X770139Y267964D01*
X770722Y268297D01*
X771139Y268880D01*
X771222Y269547D01*
X771056Y270214D01*
X770639Y270630D01*
X770056Y270964D01*
X769472Y271047D01*
X768889Y270964D01*
X768139Y270630D01*
X768389Y272797D01*
X770639D01*
G01X774989D02*
X774322Y272630D01*
X773822Y272214D01*
X773489Y271714D01*
X773239Y271047D01*
X773156Y270297D01*
X773239Y269547D01*
X773489Y268880D01*
X773822Y268380D01*
X774322Y267964D01*
X774989Y267797D01*
X775656Y267964D01*
X776156Y268380D01*
X776489Y268880D01*
X776739Y269547D01*
X776822Y270297D01*
X776739Y271047D01*
X776489Y271714D01*
X776156Y272214D01*
X775656Y272630D01*
X774989Y272797D01*
G01X784689Y267630D02*
X787689Y272797D01*
G01X784689D02*
X784189Y272630D01*
X783939Y272380D01*
X783772Y271880D01*
X783939Y271380D01*
X784189Y271130D01*
X784689Y270964D01*
X785189Y271130D01*
X785439Y271380D01*
X785606Y271880D01*
X785439Y272380D01*
X785189Y272630D01*
X784689Y272797D01*
G01X787689Y269464D02*
X787189Y269297D01*
X786939Y269047D01*
X786772Y268547D01*
X786939Y268047D01*
X787189Y267797D01*
X787689Y267630D01*
X788189Y267797D01*
X788439Y268047D01*
X788606Y268547D01*
X788439Y269047D01*
X788189Y269297D01*
X787689Y269464D01*
G01X796139Y268380D02*
X796556Y268047D01*
X797139Y267797D01*
X797639D01*
X798139Y267964D01*
X798472Y268214D01*
X798639Y268547D01*
X798556Y269047D01*
X798222Y269297D01*
X796722Y269797D01*
X796389Y270380D01*
X796556Y270797D01*
X796889Y271047D01*
X797389Y271130D01*
X797889Y271047D01*
X798389Y270797D01*
G01X802989Y267797D02*
X802489Y267880D01*
X801989Y268214D01*
X801656Y268797D01*
X801489Y269464D01*
X801656Y270130D01*
X801989Y270714D01*
X802489Y271047D01*
X802989Y271130D01*
X803489Y271047D01*
X803989Y270714D01*
X804322Y270130D01*
X804406Y269464D01*
X804322Y268797D01*
X803989Y268214D01*
X803489Y267880D01*
X802989Y267797D01*
G01X808589D02*
Y272797D01*
G01X815689D02*
Y267797D01*
G01Y268547D02*
X815356Y268130D01*
X814856Y267880D01*
X814272Y267797D01*
X813606Y267964D01*
X813106Y268380D01*
X812772Y268880D01*
X812689Y269464D01*
X812772Y270047D01*
X813106Y270547D01*
X813606Y270964D01*
X814272Y271130D01*
X814856Y271047D01*
X815272Y270880D01*
X815689Y270547D01*
G01X818539Y270047D02*
X821206D01*
X820956Y270630D01*
X820539Y270964D01*
X819956Y271130D01*
X819372Y271047D01*
X818872Y270797D01*
X818539Y270214D01*
X818372Y269714D01*
Y269214D01*
X818539Y268714D01*
X818956Y268214D01*
X819456Y267880D01*
X820039Y267797D01*
X820622Y267964D01*
X821206Y268464D01*
G01X824222Y267797D02*
Y271130D01*
G01Y270464D02*
X824639Y270797D01*
X825056Y271047D01*
X825639Y271130D01*
X826056Y271047D01*
X826556Y270797D01*
G01X834089Y267797D02*
Y271130D01*
G01Y270214D02*
X834339Y270630D01*
X834756Y270964D01*
X835339Y271130D01*
X835922Y270964D01*
X836339Y270630D01*
X836589Y270214D01*
Y267797D01*
G01Y270214D02*
X836839Y270630D01*
X837256Y270964D01*
X837839Y271130D01*
X838422Y270964D01*
X838839Y270630D01*
X839089Y270130D01*
Y267797D01*
G01X843689D02*
Y271130D01*
G01Y270547D02*
X843356Y270880D01*
X842856Y271047D01*
X842272Y271130D01*
X841689Y270964D01*
X841189Y270630D01*
X840856Y270130D01*
X840689Y269464D01*
X840856Y268797D01*
X841189Y268297D01*
X841689Y267964D01*
X842272Y267797D01*
X842856Y267880D01*
X843356Y268130D01*
X843689Y268464D01*
G01X846539Y268380D02*
X846956Y268047D01*
X847539Y267797D01*
X848039D01*
X848539Y267964D01*
X848872Y268214D01*
X849039Y268547D01*
X848956Y269047D01*
X848622Y269297D01*
X847122Y269797D01*
X846789Y270380D01*
X846956Y270797D01*
X847289Y271047D01*
X847789Y271130D01*
X848289Y271047D01*
X848789Y270797D01*
G01X851972Y267797D02*
Y272797D01*
G01X854639Y271130D02*
X851972Y269214D01*
G01X853056Y269964D02*
X854806Y267797D01*
G01X858822Y266880D02*
X859156Y267964D01*
G01X604089Y276797D02*
Y280130D01*
G01Y279547D02*
X603756Y279880D01*
X603256Y280047D01*
X602672Y280130D01*
X602089Y279964D01*
X601589Y279630D01*
X601256Y279130D01*
X601089Y278464D01*
X601256Y277797D01*
X601589Y277297D01*
X602089Y276964D01*
X602672Y276797D01*
X603256Y276880D01*
X603756Y277130D01*
X604089Y277464D01*
G01X608189Y276630D02*
X608022Y276714D01*
Y276880D01*
X608189Y276964D01*
X608356Y276880D01*
Y276714D01*
X608189Y276630D01*
G01X614456Y279464D02*
X614789Y279714D01*
X615039Y280130D01*
X615206Y280714D01*
X615039Y281214D01*
X614706Y281547D01*
X614122Y281797D01*
X611872D01*
Y276797D01*
X614622D01*
X615206Y277130D01*
X615539Y277630D01*
X615706Y278214D01*
X615539Y278797D01*
X615039Y279297D01*
X614456Y279464D01*
X611872D01*
G01X619389Y276797D02*
X618889Y276880D01*
X618389Y277214D01*
X618056Y277797D01*
X617889Y278464D01*
X618056Y279130D01*
X618389Y279714D01*
X618889Y280047D01*
X619389Y280130D01*
X619889Y280047D01*
X620389Y279714D01*
X620722Y279130D01*
X620806Y278464D01*
X620722Y277797D01*
X620389Y277214D01*
X619889Y276880D01*
X619389Y276797D01*
G01X626489D02*
Y280130D01*
G01Y279547D02*
X626156Y279880D01*
X625656Y280047D01*
X625072Y280130D01*
X624489Y279964D01*
X623989Y279630D01*
X623656Y279130D01*
X623489Y278464D01*
X623656Y277797D01*
X623989Y277297D01*
X624489Y276964D01*
X625072Y276797D01*
X625656Y276880D01*
X626156Y277130D01*
X626489Y277464D01*
G01X629422Y276797D02*
Y280130D01*
G01Y279464D02*
X629839Y279797D01*
X630256Y280047D01*
X630839Y280130D01*
X631256Y280047D01*
X631756Y279797D01*
G01X637689Y281797D02*
Y276797D01*
G01Y277547D02*
X637356Y277130D01*
X636856Y276880D01*
X636272Y276797D01*
X635606Y276964D01*
X635106Y277380D01*
X634772Y277880D01*
X634689Y278464D01*
X634772Y279047D01*
X635106Y279547D01*
X635606Y279964D01*
X636272Y280130D01*
X636856Y280047D01*
X637272Y279880D01*
X637689Y279547D01*
G01X647389Y281797D02*
Y276797D01*
G01X646222Y280130D02*
X648556D01*
G01X651572Y276797D02*
Y281797D01*
G01Y279380D02*
X651989Y279797D01*
X652406Y280047D01*
X653072Y280130D01*
X653572Y280047D01*
X654156Y279714D01*
X654406Y279214D01*
Y276797D01*
G01X658589Y280130D02*
Y276797D01*
G01Y281464D02*
X658422Y281547D01*
Y281714D01*
X658589Y281797D01*
X658756Y281714D01*
Y281547D01*
X658589Y281464D01*
G01X665522Y279714D02*
X664939Y280047D01*
X664439Y280130D01*
X663772Y279964D01*
X663272Y279630D01*
X662939Y279047D01*
X662856Y278464D01*
X662939Y277880D01*
X663272Y277380D01*
X663772Y276964D01*
X664439Y276797D01*
X665022Y276964D01*
X665522Y277297D01*
G01X668372Y276797D02*
Y281797D01*
G01X671039Y280130D02*
X668372Y278214D01*
G01X669456Y278964D02*
X671206Y276797D01*
G01X673972D02*
Y280130D01*
G01Y279297D02*
X674306Y279714D01*
X674806Y280047D01*
X675472Y280130D01*
X676056Y280047D01*
X676556Y279714D01*
X676806Y279130D01*
Y276797D01*
G01X679739Y279047D02*
X682406D01*
X682156Y279630D01*
X681739Y279964D01*
X681156Y280130D01*
X680572Y280047D01*
X680072Y279797D01*
X679739Y279214D01*
X679572Y278714D01*
Y278214D01*
X679739Y277714D01*
X680156Y277214D01*
X680656Y276880D01*
X681239Y276797D01*
X681822Y276964D01*
X682406Y277464D01*
G01X685339Y277380D02*
X685756Y277047D01*
X686339Y276797D01*
X686839D01*
X687339Y276964D01*
X687672Y277214D01*
X687839Y277547D01*
X687756Y278047D01*
X687422Y278297D01*
X685922Y278797D01*
X685589Y279380D01*
X685756Y279797D01*
X686089Y280047D01*
X686589Y280130D01*
X687089Y280047D01*
X687589Y279797D01*
G01X690939Y277380D02*
X691356Y277047D01*
X691939Y276797D01*
X692439D01*
X692939Y276964D01*
X693272Y277214D01*
X693439Y277547D01*
X693356Y278047D01*
X693022Y278297D01*
X691522Y278797D01*
X691189Y279380D01*
X691356Y279797D01*
X691689Y280047D01*
X692189Y280130D01*
X692689Y280047D01*
X693189Y279797D01*
G01X696122Y276797D02*
X699456Y278464D01*
X696122Y280130D01*
G01X702306Y277714D02*
X704472D01*
G01Y279214D02*
X702306D01*
G01X714589Y281797D02*
X713922Y281630D01*
X713422Y281214D01*
X713089Y280714D01*
X712839Y280047D01*
X712756Y279297D01*
X712839Y278547D01*
X713089Y277880D01*
X713422Y277380D01*
X713922Y276964D01*
X714589Y276797D01*
X715256Y276964D01*
X715756Y277380D01*
X716089Y277880D01*
X716339Y278547D01*
X716422Y279297D01*
X716339Y280047D01*
X716089Y280714D01*
X715756Y281214D01*
X715256Y281630D01*
X714589Y281797D01*
G01X720189Y276630D02*
X720022Y276714D01*
Y276880D01*
X720189Y276964D01*
X720356Y276880D01*
Y276714D01*
X720189Y276630D01*
G01X724372Y277380D02*
X724956Y276964D01*
X725622Y276797D01*
X726289Y276964D01*
X726872Y277464D01*
X727289Y278214D01*
X727456Y278964D01*
Y279880D01*
X727289Y280630D01*
X726872Y281297D01*
X726372Y281630D01*
X725789Y281797D01*
X725122Y281630D01*
X724622Y281297D01*
X724289Y280797D01*
X724122Y280130D01*
X724289Y279547D01*
X724706Y278964D01*
X725206Y278630D01*
X725789Y278547D01*
X726456Y278714D01*
X726956Y279130D01*
X727456Y279880D01*
G01X728889Y276797D02*
Y280130D01*
G01Y279214D02*
X729139Y279630D01*
X729556Y279964D01*
X730139Y280130D01*
X730722Y279964D01*
X731139Y279630D01*
X731389Y279214D01*
Y276797D01*
G01Y279214D02*
X731639Y279630D01*
X732056Y279964D01*
X732639Y280130D01*
X733222Y279964D01*
X733639Y279630D01*
X733889Y279130D01*
Y276797D01*
G01X736989Y276630D02*
X736822Y276714D01*
Y276880D01*
X736989Y276964D01*
X737156Y276880D01*
Y276714D01*
X736989Y276630D01*
G01Y278880D02*
X736822Y278964D01*
Y279130D01*
X736989Y279214D01*
X737156Y279130D01*
Y278964D01*
X736989Y278880D01*
G01X599839Y286797D02*
Y291797D01*
G01X603339D02*
Y286797D01*
G01Y289297D02*
X599839D01*
G01X608689Y286797D02*
Y290130D01*
G01Y289547D02*
X608356Y289880D01*
X607856Y290047D01*
X607272Y290130D01*
X606689Y289964D01*
X606189Y289630D01*
X605856Y289130D01*
X605689Y288464D01*
X605856Y287797D01*
X606189Y287297D01*
X606689Y286964D01*
X607272Y286797D01*
X607856Y286880D01*
X608356Y287130D01*
X608689Y287464D01*
G01X612789Y286797D02*
Y291797D01*
G01X617889Y286797D02*
Y291047D01*
X618056Y291464D01*
X618389Y291714D01*
X618889Y291797D01*
X619389Y291630D01*
X619639Y291214D01*
G01X618639Y289797D02*
X616972D01*
G01X622906Y288464D02*
X625072D01*
G01X628089Y285130D02*
Y290130D01*
G01Y289380D02*
X628506Y289797D01*
X628922Y290047D01*
X629589Y290130D01*
X630172Y290047D01*
X630756Y289630D01*
X631006Y289047D01*
X631089Y288464D01*
X631006Y287880D01*
X630756Y287297D01*
X630256Y286964D01*
X629589Y286797D01*
X629006Y286880D01*
X628422Y287130D01*
X628089Y287464D01*
G01X635189Y286797D02*
Y291797D01*
G01X639372Y290130D02*
Y287797D01*
X639706Y287214D01*
X640206Y286880D01*
X640789Y286797D01*
X641372Y286880D01*
X641872Y287214D01*
X642206Y287797D01*
G01Y286797D02*
Y290130D01*
G01X645222Y285547D02*
X645806Y285214D01*
X646472Y285130D01*
X647056Y285214D01*
X647556Y285630D01*
X647889Y286214D01*
Y290130D01*
G01Y289464D02*
X647556Y289797D01*
X647056Y290047D01*
X646472Y290130D01*
X645806Y289964D01*
X645389Y289630D01*
X645056Y289047D01*
X644889Y288464D01*
X644972Y287964D01*
X645306Y287380D01*
X645806Y286964D01*
X646472Y286797D01*
X646972Y286880D01*
X647556Y287214D01*
X647889Y287547D01*
G01X650822Y285547D02*
X651406Y285214D01*
X652072Y285130D01*
X652656Y285214D01*
X653156Y285630D01*
X653489Y286214D01*
Y290130D01*
G01Y289464D02*
X653156Y289797D01*
X652656Y290047D01*
X652072Y290130D01*
X651406Y289964D01*
X650989Y289630D01*
X650656Y289047D01*
X650489Y288464D01*
X650572Y287964D01*
X650906Y287380D01*
X651406Y286964D01*
X652072Y286797D01*
X652572Y286880D01*
X653156Y287214D01*
X653489Y287547D01*
G01X657589Y290130D02*
Y286797D01*
G01Y291464D02*
X657422Y291547D01*
Y291714D01*
X657589Y291797D01*
X657756Y291714D01*
Y291547D01*
X657589Y291464D01*
G01X661772Y286797D02*
Y290130D01*
G01Y289297D02*
X662106Y289714D01*
X662606Y290047D01*
X663272Y290130D01*
X663856Y290047D01*
X664356Y289714D01*
X664606Y289130D01*
Y286797D01*
G01X667622Y285547D02*
X668206Y285214D01*
X668872Y285130D01*
X669456Y285214D01*
X669956Y285630D01*
X670289Y286214D01*
Y290130D01*
G01Y289464D02*
X669956Y289797D01*
X669456Y290047D01*
X668872Y290130D01*
X668206Y289964D01*
X667789Y289630D01*
X667456Y289047D01*
X667289Y288464D01*
X667372Y287964D01*
X667706Y287380D01*
X668206Y286964D01*
X668872Y286797D01*
X669372Y286880D01*
X669956Y287214D01*
X670289Y287547D01*
G01X679989Y286630D02*
X679822Y286714D01*
Y286880D01*
X679989Y286964D01*
X680156Y286880D01*
Y286714D01*
X679989Y286630D01*
G01Y288880D02*
X679822Y288964D01*
Y289130D01*
X679989Y289214D01*
X680156Y289130D01*
Y288964D01*
X679989Y288880D01*
G01X691189Y291797D02*
Y286797D01*
G01X690022Y290130D02*
X692356D01*
G01X695372Y286797D02*
Y291797D01*
G01Y289380D02*
X695789Y289797D01*
X696206Y290047D01*
X696872Y290130D01*
X697372Y290047D01*
X697956Y289714D01*
X698206Y289214D01*
Y286797D01*
G01X701139Y289047D02*
X703806D01*
X703556Y289630D01*
X703139Y289964D01*
X702556Y290130D01*
X701972Y290047D01*
X701472Y289797D01*
X701139Y289214D01*
X700972Y288714D01*
Y288214D01*
X701139Y287714D01*
X701556Y287214D01*
X702056Y286880D01*
X702639Y286797D01*
X703222Y286964D01*
X703806Y287464D01*
G01X712089Y285130D02*
Y290130D01*
G01Y289380D02*
X712506Y289797D01*
X712922Y290047D01*
X713589Y290130D01*
X714172Y290047D01*
X714756Y289630D01*
X715006Y289047D01*
X715089Y288464D01*
X715006Y287880D01*
X714756Y287297D01*
X714256Y286964D01*
X713589Y286797D01*
X713006Y286880D01*
X712422Y287130D01*
X712089Y287464D01*
G01X719189Y286797D02*
Y291797D01*
G01X723372Y290130D02*
Y287797D01*
X723706Y287214D01*
X724206Y286880D01*
X724789Y286797D01*
X725372Y286880D01*
X725872Y287214D01*
X726206Y287797D01*
G01Y286797D02*
Y290130D01*
G01X729222Y285547D02*
X729806Y285214D01*
X730472Y285130D01*
X731056Y285214D01*
X731556Y285630D01*
X731889Y286214D01*
Y290130D01*
G01Y289464D02*
X731556Y289797D01*
X731056Y290047D01*
X730472Y290130D01*
X729806Y289964D01*
X729389Y289630D01*
X729056Y289047D01*
X728889Y288464D01*
X728972Y287964D01*
X729306Y287380D01*
X729806Y286964D01*
X730472Y286797D01*
X730972Y286880D01*
X731556Y287214D01*
X731889Y287547D01*
G01X734822Y285547D02*
X735406Y285214D01*
X736072Y285130D01*
X736656Y285214D01*
X737156Y285630D01*
X737489Y286214D01*
Y290130D01*
G01Y289464D02*
X737156Y289797D01*
X736656Y290047D01*
X736072Y290130D01*
X735406Y289964D01*
X734989Y289630D01*
X734656Y289047D01*
X734489Y288464D01*
X734572Y287964D01*
X734906Y287380D01*
X735406Y286964D01*
X736072Y286797D01*
X736572Y286880D01*
X737156Y287214D01*
X737489Y287547D01*
G01X741589Y290130D02*
Y286797D01*
G01Y291464D02*
X741422Y291547D01*
Y291714D01*
X741589Y291797D01*
X741756Y291714D01*
Y291547D01*
X741589Y291464D01*
G01X745772Y286797D02*
Y290130D01*
G01Y289297D02*
X746106Y289714D01*
X746606Y290047D01*
X747272Y290130D01*
X747856Y290047D01*
X748356Y289714D01*
X748606Y289130D01*
Y286797D01*
G01X751622Y285547D02*
X752206Y285214D01*
X752872Y285130D01*
X753456Y285214D01*
X753956Y285630D01*
X754289Y286214D01*
Y290130D01*
G01Y289464D02*
X753956Y289797D01*
X753456Y290047D01*
X752872Y290130D01*
X752206Y289964D01*
X751789Y289630D01*
X751456Y289047D01*
X751289Y288464D01*
X751372Y287964D01*
X751706Y287380D01*
X752206Y286964D01*
X752872Y286797D01*
X753372Y286880D01*
X753956Y287214D01*
X754289Y287547D01*
G01X762822Y286797D02*
Y290130D01*
G01Y289464D02*
X763239Y289797D01*
X763656Y290047D01*
X764239Y290130D01*
X764656Y290047D01*
X765156Y289797D01*
G01X771089Y286797D02*
Y290130D01*
G01Y289547D02*
X770756Y289880D01*
X770256Y290047D01*
X769672Y290130D01*
X769089Y289964D01*
X768589Y289630D01*
X768256Y289130D01*
X768089Y288464D01*
X768256Y287797D01*
X768589Y287297D01*
X769089Y286964D01*
X769672Y286797D01*
X770256Y286880D01*
X770756Y287130D01*
X771089Y287464D01*
G01X775189Y291797D02*
Y286797D01*
G01X774022Y290130D02*
X776356D01*
G01X780789D02*
Y286797D01*
G01Y291464D02*
X780622Y291547D01*
Y291714D01*
X780789Y291797D01*
X780956Y291714D01*
Y291547D01*
X780789Y291464D01*
G01X786389Y286797D02*
X785889Y286880D01*
X785389Y287214D01*
X785056Y287797D01*
X784889Y288464D01*
X785056Y289130D01*
X785389Y289714D01*
X785889Y290047D01*
X786389Y290130D01*
X786889Y290047D01*
X787389Y289714D01*
X787722Y289130D01*
X787806Y288464D01*
X787722Y287797D01*
X787389Y287214D01*
X786889Y286880D01*
X786389Y286797D01*
G01X796089Y285130D02*
Y290130D01*
G01Y289380D02*
X796506Y289797D01*
X796922Y290047D01*
X797589Y290130D01*
X798172Y290047D01*
X798756Y289630D01*
X799006Y289047D01*
X799089Y288464D01*
X799006Y287880D01*
X798756Y287297D01*
X798256Y286964D01*
X797589Y286797D01*
X797006Y286880D01*
X796422Y287130D01*
X796089Y287464D01*
G01X801939Y289047D02*
X804606D01*
X804356Y289630D01*
X803939Y289964D01*
X803356Y290130D01*
X802772Y290047D01*
X802272Y289797D01*
X801939Y289214D01*
X801772Y288714D01*
Y288214D01*
X801939Y287714D01*
X802356Y287214D01*
X802856Y286880D01*
X803439Y286797D01*
X804022Y286964D01*
X804606Y287464D01*
G01X807622Y286797D02*
Y290130D01*
G01Y289464D02*
X808039Y289797D01*
X808456Y290047D01*
X809039Y290130D01*
X809456Y290047D01*
X809956Y289797D01*
G01X819489Y286797D02*
Y291047D01*
X819656Y291464D01*
X819989Y291714D01*
X820489Y291797D01*
X820989Y291630D01*
X821239Y291214D01*
G01X820239Y289797D02*
X818572D01*
G01X825589Y286797D02*
X825089Y286880D01*
X824589Y287214D01*
X824256Y287797D01*
X824089Y288464D01*
X824256Y289130D01*
X824589Y289714D01*
X825089Y290047D01*
X825589Y290130D01*
X826089Y290047D01*
X826589Y289714D01*
X826922Y289130D01*
X827006Y288464D01*
X826922Y287797D01*
X826589Y287214D01*
X826089Y286880D01*
X825589Y286797D01*
G01X831189D02*
Y291797D01*
G01X836789Y286797D02*
Y291797D01*
G01X842389Y286797D02*
X841889Y286880D01*
X841389Y287214D01*
X841056Y287797D01*
X840889Y288464D01*
X841056Y289130D01*
X841389Y289714D01*
X841889Y290047D01*
X842389Y290130D01*
X842889Y290047D01*
X843389Y289714D01*
X843722Y289130D01*
X843806Y288464D01*
X843722Y287797D01*
X843389Y287214D01*
X842889Y286880D01*
X842389Y286797D01*
G01X845906Y290130D02*
X846906Y286797D01*
X847989Y290130D01*
X849072Y286797D01*
X850072Y290130D01*
G01X853589D02*
Y286797D01*
G01Y291464D02*
X853422Y291547D01*
Y291714D01*
X853589Y291797D01*
X853756Y291714D01*
Y291547D01*
X853589Y291464D01*
G01X857772Y286797D02*
Y290130D01*
G01Y289297D02*
X858106Y289714D01*
X858606Y290047D01*
X859272Y290130D01*
X859856Y290047D01*
X860356Y289714D01*
X860606Y289130D01*
Y286797D01*
G01X863622Y285547D02*
X864206Y285214D01*
X864872Y285130D01*
X865456Y285214D01*
X865956Y285630D01*
X866289Y286214D01*
Y290130D01*
G01Y289464D02*
X865956Y289797D01*
X865456Y290047D01*
X864872Y290130D01*
X864206Y289964D01*
X863789Y289630D01*
X863456Y289047D01*
X863289Y288464D01*
X863372Y287964D01*
X863706Y287380D01*
X864206Y286964D01*
X864872Y286797D01*
X865372Y286880D01*
X865956Y287214D01*
X866289Y287547D01*
G01X870389Y286630D02*
X870222Y286714D01*
Y286880D01*
X870389Y286964D01*
X870556Y286880D01*
Y286714D01*
X870389Y286630D01*
G01Y288880D02*
X870222Y288964D01*
Y289130D01*
X870389Y289214D01*
X870556Y289130D01*
Y288964D01*
X870389Y288880D01*
G01X599089Y295797D02*
Y300797D01*
G01Y298297D02*
X599506Y298797D01*
X600006Y299047D01*
X600506Y299130D01*
X601256Y298964D01*
X601756Y298630D01*
X602089Y298047D01*
Y297380D01*
X601922Y296714D01*
X601589Y296214D01*
X601006Y295880D01*
X600506Y295797D01*
X600006Y295880D01*
X599506Y296130D01*
X599089Y296547D01*
G01X604939Y298047D02*
X607606D01*
X607356Y298630D01*
X606939Y298964D01*
X606356Y299130D01*
X605772Y299047D01*
X605272Y298797D01*
X604939Y298214D01*
X604772Y297714D01*
Y297214D01*
X604939Y296714D01*
X605356Y296214D01*
X605856Y295880D01*
X606439Y295797D01*
X607022Y295964D01*
X607606Y296464D01*
G01X616889Y295797D02*
Y300047D01*
X617056Y300464D01*
X617389Y300714D01*
X617889Y300797D01*
X618389Y300630D01*
X618639Y300214D01*
G01X617639Y298797D02*
X615972D01*
G01X621822Y295797D02*
Y299130D01*
G01Y298464D02*
X622239Y298797D01*
X622656Y299047D01*
X623239Y299130D01*
X623656Y299047D01*
X624156Y298797D01*
G01X627339Y298047D02*
X630006D01*
X629756Y298630D01*
X629339Y298964D01*
X628756Y299130D01*
X628172Y299047D01*
X627672Y298797D01*
X627339Y298214D01*
X627172Y297714D01*
Y297214D01*
X627339Y296714D01*
X627756Y296214D01*
X628256Y295880D01*
X628839Y295797D01*
X629422Y295964D01*
X630006Y296464D01*
G01X632939Y298047D02*
X635606D01*
X635356Y298630D01*
X634939Y298964D01*
X634356Y299130D01*
X633772Y299047D01*
X633272Y298797D01*
X632939Y298214D01*
X632772Y297714D01*
Y297214D01*
X632939Y296714D01*
X633356Y296214D01*
X633856Y295880D01*
X634439Y295797D01*
X635022Y295964D01*
X635606Y296464D01*
G01X644889Y295797D02*
Y300047D01*
X645056Y300464D01*
X645389Y300714D01*
X645889Y300797D01*
X646389Y300630D01*
X646639Y300214D01*
G01X645639Y298797D02*
X643972D01*
G01X649822Y295797D02*
Y299130D01*
G01Y298464D02*
X650239Y298797D01*
X650656Y299047D01*
X651239Y299130D01*
X651656Y299047D01*
X652156Y298797D01*
G01X656589Y295797D02*
X656089Y295880D01*
X655589Y296214D01*
X655256Y296797D01*
X655089Y297464D01*
X655256Y298130D01*
X655589Y298714D01*
X656089Y299047D01*
X656589Y299130D01*
X657089Y299047D01*
X657589Y298714D01*
X657922Y298130D01*
X658006Y297464D01*
X657922Y296797D01*
X657589Y296214D01*
X657089Y295880D01*
X656589Y295797D01*
G01X659689D02*
Y299130D01*
G01Y298214D02*
X659939Y298630D01*
X660356Y298964D01*
X660939Y299130D01*
X661522Y298964D01*
X661939Y298630D01*
X662189Y298214D01*
Y295797D01*
G01Y298214D02*
X662439Y298630D01*
X662856Y298964D01*
X663439Y299130D01*
X664022Y298964D01*
X664439Y298630D01*
X664689Y298130D01*
Y295797D01*
G01X672139Y296380D02*
X672556Y296047D01*
X673139Y295797D01*
X673639D01*
X674139Y295964D01*
X674472Y296214D01*
X674639Y296547D01*
X674556Y297047D01*
X674222Y297297D01*
X672722Y297797D01*
X672389Y298380D01*
X672556Y298797D01*
X672889Y299047D01*
X673389Y299130D01*
X673889Y299047D01*
X674389Y298797D01*
G01X678989Y295797D02*
X678489Y295880D01*
X677989Y296214D01*
X677656Y296797D01*
X677489Y297464D01*
X677656Y298130D01*
X677989Y298714D01*
X678489Y299047D01*
X678989Y299130D01*
X679489Y299047D01*
X679989Y298714D01*
X680322Y298130D01*
X680406Y297464D01*
X680322Y296797D01*
X679989Y296214D01*
X679489Y295880D01*
X678989Y295797D01*
G01X684589D02*
Y300797D01*
G01X691689D02*
Y295797D01*
G01Y296547D02*
X691356Y296130D01*
X690856Y295880D01*
X690272Y295797D01*
X689606Y295964D01*
X689106Y296380D01*
X688772Y296880D01*
X688689Y297464D01*
X688772Y298047D01*
X689106Y298547D01*
X689606Y298964D01*
X690272Y299130D01*
X690856Y299047D01*
X691272Y298880D01*
X691689Y298547D01*
G01X694539Y298047D02*
X697206D01*
X696956Y298630D01*
X696539Y298964D01*
X695956Y299130D01*
X695372Y299047D01*
X694872Y298797D01*
X694539Y298214D01*
X694372Y297714D01*
Y297214D01*
X694539Y296714D01*
X694956Y296214D01*
X695456Y295880D01*
X696039Y295797D01*
X696622Y295964D01*
X697206Y296464D01*
G01X700222Y295797D02*
Y299130D01*
G01Y298464D02*
X700639Y298797D01*
X701056Y299047D01*
X701639Y299130D01*
X702056Y299047D01*
X702556Y298797D01*
G01X710089Y295797D02*
Y299130D01*
G01Y298214D02*
X710339Y298630D01*
X710756Y298964D01*
X711339Y299130D01*
X711922Y298964D01*
X712339Y298630D01*
X712589Y298214D01*
Y295797D01*
G01Y298214D02*
X712839Y298630D01*
X713256Y298964D01*
X713839Y299130D01*
X714422Y298964D01*
X714839Y298630D01*
X715089Y298130D01*
Y295797D01*
G01X719689D02*
Y299130D01*
G01Y298547D02*
X719356Y298880D01*
X718856Y299047D01*
X718272Y299130D01*
X717689Y298964D01*
X717189Y298630D01*
X716856Y298130D01*
X716689Y297464D01*
X716856Y296797D01*
X717189Y296297D01*
X717689Y295964D01*
X718272Y295797D01*
X718856Y295880D01*
X719356Y296130D01*
X719689Y296464D01*
G01X722539Y296380D02*
X722956Y296047D01*
X723539Y295797D01*
X724039D01*
X724539Y295964D01*
X724872Y296214D01*
X725039Y296547D01*
X724956Y297047D01*
X724622Y297297D01*
X723122Y297797D01*
X722789Y298380D01*
X722956Y298797D01*
X723289Y299047D01*
X723789Y299130D01*
X724289Y299047D01*
X724789Y298797D01*
G01X727972Y295797D02*
Y300797D01*
G01X730639Y299130D02*
X727972Y297214D01*
G01X729056Y297964D02*
X730806Y295797D01*
G01X734989Y295630D02*
X734822Y295714D01*
Y295880D01*
X734989Y295964D01*
X735156Y295880D01*
Y295714D01*
X734989Y295630D01*
G01X598089Y318797D02*
Y323797D01*
G01Y321297D02*
X598506Y321797D01*
X599006Y322047D01*
X599506Y322130D01*
X600256Y321964D01*
X600756Y321630D01*
X601089Y321047D01*
Y320380D01*
X600922Y319714D01*
X600589Y319214D01*
X600006Y318880D01*
X599506Y318797D01*
X599006Y318880D01*
X598506Y319130D01*
X598089Y319547D01*
G01X603939Y321047D02*
X606606D01*
X606356Y321630D01*
X605939Y321964D01*
X605356Y322130D01*
X604772Y322047D01*
X604272Y321797D01*
X603939Y321214D01*
X603772Y320714D01*
Y320214D01*
X603939Y319714D01*
X604356Y319214D01*
X604856Y318880D01*
X605439Y318797D01*
X606022Y318964D01*
X606606Y319464D01*
G01X616389Y323797D02*
Y318797D01*
G01X615222Y322130D02*
X617556D01*
G01X620739Y321047D02*
X623406D01*
X623156Y321630D01*
X622739Y321964D01*
X622156Y322130D01*
X621572Y322047D01*
X621072Y321797D01*
X620739Y321214D01*
X620572Y320714D01*
Y320214D01*
X620739Y319714D01*
X621156Y319214D01*
X621656Y318880D01*
X622239Y318797D01*
X622822Y318964D01*
X623406Y319464D01*
G01X626172Y318797D02*
Y322130D01*
G01Y321297D02*
X626506Y321714D01*
X627006Y322047D01*
X627672Y322130D01*
X628256Y322047D01*
X628756Y321714D01*
X629006Y321130D01*
Y318797D01*
G01X633189Y323797D02*
Y318797D01*
G01X632022Y322130D02*
X634356D01*
G01X637539Y321047D02*
X640206D01*
X639956Y321630D01*
X639539Y321964D01*
X638956Y322130D01*
X638372Y322047D01*
X637872Y321797D01*
X637539Y321214D01*
X637372Y320714D01*
Y320214D01*
X637539Y319714D01*
X637956Y319214D01*
X638456Y318880D01*
X639039Y318797D01*
X639622Y318964D01*
X640206Y319464D01*
G01X645889Y323797D02*
Y318797D01*
G01Y319547D02*
X645556Y319130D01*
X645056Y318880D01*
X644472Y318797D01*
X643806Y318964D01*
X643306Y319380D01*
X642972Y319880D01*
X642889Y320464D01*
X642972Y321047D01*
X643306Y321547D01*
X643806Y321964D01*
X644472Y322130D01*
X645056Y322047D01*
X645472Y321880D01*
X645889Y321547D01*
G01X653506Y322130D02*
X654506Y318797D01*
X655589Y322130D01*
X656672Y318797D01*
X657672Y322130D01*
G01X661189D02*
Y318797D01*
G01Y323464D02*
X661022Y323547D01*
Y323714D01*
X661189Y323797D01*
X661356Y323714D01*
Y323547D01*
X661189Y323464D01*
G01X666789Y323797D02*
Y318797D01*
G01X665622Y322130D02*
X667956D01*
G01X670972Y318797D02*
Y323797D01*
G01Y321380D02*
X671389Y321797D01*
X671806Y322047D01*
X672472Y322130D01*
X672972Y322047D01*
X673556Y321714D01*
X673806Y321214D01*
Y318797D01*
G01X682339Y319380D02*
X682756Y319047D01*
X683339Y318797D01*
X683839D01*
X684339Y318964D01*
X684672Y319214D01*
X684839Y319547D01*
X684756Y320047D01*
X684422Y320297D01*
X682922Y320797D01*
X682589Y321380D01*
X682756Y321797D01*
X683089Y322047D01*
X683589Y322130D01*
X684089Y322047D01*
X684589Y321797D01*
G01X689189Y318797D02*
X688689Y318880D01*
X688189Y319214D01*
X687856Y319797D01*
X687689Y320464D01*
X687856Y321130D01*
X688189Y321714D01*
X688689Y322047D01*
X689189Y322130D01*
X689689Y322047D01*
X690189Y321714D01*
X690522Y321130D01*
X690606Y320464D01*
X690522Y319797D01*
X690189Y319214D01*
X689689Y318880D01*
X689189Y318797D01*
G01X694789D02*
Y323797D01*
G01X701889D02*
Y318797D01*
G01Y319547D02*
X701556Y319130D01*
X701056Y318880D01*
X700472Y318797D01*
X699806Y318964D01*
X699306Y319380D01*
X698972Y319880D01*
X698889Y320464D01*
X698972Y321047D01*
X699306Y321547D01*
X699806Y321964D01*
X700472Y322130D01*
X701056Y322047D01*
X701472Y321880D01*
X701889Y321547D01*
G01X704739Y321047D02*
X707406D01*
X707156Y321630D01*
X706739Y321964D01*
X706156Y322130D01*
X705572Y322047D01*
X705072Y321797D01*
X704739Y321214D01*
X704572Y320714D01*
Y320214D01*
X704739Y319714D01*
X705156Y319214D01*
X705656Y318880D01*
X706239Y318797D01*
X706822Y318964D01*
X707406Y319464D01*
G01X710422Y318797D02*
Y322130D01*
G01Y321464D02*
X710839Y321797D01*
X711256Y322047D01*
X711839Y322130D01*
X712256Y322047D01*
X712756Y321797D01*
G01X720289Y318797D02*
Y322130D01*
G01Y321214D02*
X720539Y321630D01*
X720956Y321964D01*
X721539Y322130D01*
X722122Y321964D01*
X722539Y321630D01*
X722789Y321214D01*
Y318797D01*
G01Y321214D02*
X723039Y321630D01*
X723456Y321964D01*
X724039Y322130D01*
X724622Y321964D01*
X725039Y321630D01*
X725289Y321130D01*
Y318797D01*
G01X729889D02*
Y322130D01*
G01Y321547D02*
X729556Y321880D01*
X729056Y322047D01*
X728472Y322130D01*
X727889Y321964D01*
X727389Y321630D01*
X727056Y321130D01*
X726889Y320464D01*
X727056Y319797D01*
X727389Y319297D01*
X727889Y318964D01*
X728472Y318797D01*
X729056Y318880D01*
X729556Y319130D01*
X729889Y319464D01*
G01X732739Y319380D02*
X733156Y319047D01*
X733739Y318797D01*
X734239D01*
X734739Y318964D01*
X735072Y319214D01*
X735239Y319547D01*
X735156Y320047D01*
X734822Y320297D01*
X733322Y320797D01*
X732989Y321380D01*
X733156Y321797D01*
X733489Y322047D01*
X733989Y322130D01*
X734489Y322047D01*
X734989Y321797D01*
G01X738172Y318797D02*
Y323797D01*
G01X740839Y322130D02*
X738172Y320214D01*
G01X739256Y320964D02*
X741006Y318797D01*
G01X745189Y318630D02*
X745022Y318714D01*
Y318880D01*
X745189Y318964D01*
X745356Y318880D01*
Y318714D01*
X745189Y318630D01*
G01X599589Y332797D02*
Y327797D01*
G01X598422Y331130D02*
X600756D01*
G01X605189Y327797D02*
X604689Y327880D01*
X604189Y328214D01*
X603856Y328797D01*
X603689Y329464D01*
X603856Y330130D01*
X604189Y330714D01*
X604689Y331047D01*
X605189Y331130D01*
X605689Y331047D01*
X606189Y330714D01*
X606522Y330130D01*
X606606Y329464D01*
X606522Y328797D01*
X606189Y328214D01*
X605689Y327880D01*
X605189Y327797D01*
G01X614889D02*
Y332797D01*
G01Y330297D02*
X615306Y330797D01*
X615806Y331047D01*
X616306Y331130D01*
X617056Y330964D01*
X617556Y330630D01*
X617889Y330047D01*
Y329380D01*
X617722Y328714D01*
X617389Y328214D01*
X616806Y327880D01*
X616306Y327797D01*
X615806Y327880D01*
X615306Y328130D01*
X614889Y328547D01*
G01X620739Y330047D02*
X623406D01*
X623156Y330630D01*
X622739Y330964D01*
X622156Y331130D01*
X621572Y331047D01*
X621072Y330797D01*
X620739Y330214D01*
X620572Y329714D01*
Y329214D01*
X620739Y328714D01*
X621156Y328214D01*
X621656Y327880D01*
X622239Y327797D01*
X622822Y327964D01*
X623406Y328464D01*
G01X634522Y330714D02*
X633939Y331047D01*
X633439Y331130D01*
X632772Y330964D01*
X632272Y330630D01*
X631939Y330047D01*
X631856Y329464D01*
X631939Y328880D01*
X632272Y328380D01*
X632772Y327964D01*
X633439Y327797D01*
X634022Y327964D01*
X634522Y328297D01*
G01X638789Y327797D02*
X638289Y327880D01*
X637789Y328214D01*
X637456Y328797D01*
X637289Y329464D01*
X637456Y330130D01*
X637789Y330714D01*
X638289Y331047D01*
X638789Y331130D01*
X639289Y331047D01*
X639789Y330714D01*
X640122Y330130D01*
X640206Y329464D01*
X640122Y328797D01*
X639789Y328214D01*
X639289Y327880D01*
X638789Y327797D01*
G01X642889Y331130D02*
X644389Y327797D01*
X645889Y331130D01*
G01X648739Y330047D02*
X651406D01*
X651156Y330630D01*
X650739Y330964D01*
X650156Y331130D01*
X649572Y331047D01*
X649072Y330797D01*
X648739Y330214D01*
X648572Y329714D01*
Y329214D01*
X648739Y328714D01*
X649156Y328214D01*
X649656Y327880D01*
X650239Y327797D01*
X650822Y327964D01*
X651406Y328464D01*
G01X654422Y327797D02*
Y331130D01*
G01Y330464D02*
X654839Y330797D01*
X655256Y331047D01*
X655839Y331130D01*
X656256Y331047D01*
X656756Y330797D01*
G01X659939Y330047D02*
X662606D01*
X662356Y330630D01*
X661939Y330964D01*
X661356Y331130D01*
X660772Y331047D01*
X660272Y330797D01*
X659939Y330214D01*
X659772Y329714D01*
Y329214D01*
X659939Y328714D01*
X660356Y328214D01*
X660856Y327880D01*
X661439Y327797D01*
X662022Y327964D01*
X662606Y328464D01*
G01X668289Y332797D02*
Y327797D01*
G01Y328547D02*
X667956Y328130D01*
X667456Y327880D01*
X666872Y327797D01*
X666206Y327964D01*
X665706Y328380D01*
X665372Y328880D01*
X665289Y329464D01*
X665372Y330047D01*
X665706Y330547D01*
X666206Y330964D01*
X666872Y331130D01*
X667456Y331047D01*
X667872Y330880D01*
X668289Y330547D01*
G01X676489Y327797D02*
Y332797D01*
G01Y330297D02*
X676906Y330797D01*
X677406Y331047D01*
X677906Y331130D01*
X678656Y330964D01*
X679156Y330630D01*
X679489Y330047D01*
Y329380D01*
X679322Y328714D01*
X678989Y328214D01*
X678406Y327880D01*
X677906Y327797D01*
X677406Y327880D01*
X676906Y328130D01*
X676489Y328547D01*
G01X681839Y326297D02*
X682339Y326130D01*
X683006Y326297D01*
X683422Y326630D01*
X683756Y327047D01*
X684256Y328380D01*
X685339Y331130D01*
G01X682672D02*
X684256Y328380D01*
G01X693539D02*
X693956Y328047D01*
X694539Y327797D01*
X695039D01*
X695539Y327964D01*
X695872Y328214D01*
X696039Y328547D01*
X695956Y329047D01*
X695622Y329297D01*
X694122Y329797D01*
X693789Y330380D01*
X693956Y330797D01*
X694289Y331047D01*
X694789Y331130D01*
X695289Y331047D01*
X695789Y330797D01*
G01X700389Y327797D02*
X699889Y327880D01*
X699389Y328214D01*
X699056Y328797D01*
X698889Y329464D01*
X699056Y330130D01*
X699389Y330714D01*
X699889Y331047D01*
X700389Y331130D01*
X700889Y331047D01*
X701389Y330714D01*
X701722Y330130D01*
X701806Y329464D01*
X701722Y328797D01*
X701389Y328214D01*
X700889Y327880D01*
X700389Y327797D01*
G01X705989D02*
Y332797D01*
G01X713089D02*
Y327797D01*
G01Y328547D02*
X712756Y328130D01*
X712256Y327880D01*
X711672Y327797D01*
X711006Y327964D01*
X710506Y328380D01*
X710172Y328880D01*
X710089Y329464D01*
X710172Y330047D01*
X710506Y330547D01*
X711006Y330964D01*
X711672Y331130D01*
X712256Y331047D01*
X712672Y330880D01*
X713089Y330547D01*
G01X715939Y330047D02*
X718606D01*
X718356Y330630D01*
X717939Y330964D01*
X717356Y331130D01*
X716772Y331047D01*
X716272Y330797D01*
X715939Y330214D01*
X715772Y329714D01*
Y329214D01*
X715939Y328714D01*
X716356Y328214D01*
X716856Y327880D01*
X717439Y327797D01*
X718022Y327964D01*
X718606Y328464D01*
G01X721622Y327797D02*
Y331130D01*
G01Y330464D02*
X722039Y330797D01*
X722456Y331047D01*
X723039Y331130D01*
X723456Y331047D01*
X723956Y330797D01*
G01X731489Y327797D02*
Y331130D01*
G01Y330214D02*
X731739Y330630D01*
X732156Y330964D01*
X732739Y331130D01*
X733322Y330964D01*
X733739Y330630D01*
X733989Y330214D01*
Y327797D01*
G01Y330214D02*
X734239Y330630D01*
X734656Y330964D01*
X735239Y331130D01*
X735822Y330964D01*
X736239Y330630D01*
X736489Y330130D01*
Y327797D01*
G01X741089D02*
Y331130D01*
G01Y330547D02*
X740756Y330880D01*
X740256Y331047D01*
X739672Y331130D01*
X739089Y330964D01*
X738589Y330630D01*
X738256Y330130D01*
X738089Y329464D01*
X738256Y328797D01*
X738589Y328297D01*
X739089Y327964D01*
X739672Y327797D01*
X740256Y327880D01*
X740756Y328130D01*
X741089Y328464D01*
G01X743939Y328380D02*
X744356Y328047D01*
X744939Y327797D01*
X745439D01*
X745939Y327964D01*
X746272Y328214D01*
X746439Y328547D01*
X746356Y329047D01*
X746022Y329297D01*
X744522Y329797D01*
X744189Y330380D01*
X744356Y330797D01*
X744689Y331047D01*
X745189Y331130D01*
X745689Y331047D01*
X746189Y330797D01*
G01X749372Y327797D02*
Y332797D01*
G01X752039Y331130D02*
X749372Y329214D01*
G01X750456Y329964D02*
X752206Y327797D01*
G01X763489D02*
Y331130D01*
G01Y330547D02*
X763156Y330880D01*
X762656Y331047D01*
X762072Y331130D01*
X761489Y330964D01*
X760989Y330630D01*
X760656Y330130D01*
X760489Y329464D01*
X760656Y328797D01*
X760989Y328297D01*
X761489Y327964D01*
X762072Y327797D01*
X762656Y327880D01*
X763156Y328130D01*
X763489Y328464D01*
G01X766172Y327797D02*
Y331130D01*
G01Y330297D02*
X766506Y330714D01*
X767006Y331047D01*
X767672Y331130D01*
X768256Y331047D01*
X768756Y330714D01*
X769006Y330130D01*
Y327797D01*
G01X774689Y332797D02*
Y327797D01*
G01Y328547D02*
X774356Y328130D01*
X773856Y327880D01*
X773272Y327797D01*
X772606Y327964D01*
X772106Y328380D01*
X771772Y328880D01*
X771689Y329464D01*
X771772Y330047D01*
X772106Y330547D01*
X772606Y330964D01*
X773272Y331130D01*
X773856Y331047D01*
X774272Y330880D01*
X774689Y330547D01*
G01X782972Y327797D02*
Y332797D01*
G01Y330380D02*
X783389Y330797D01*
X783806Y331047D01*
X784472Y331130D01*
X784972Y331047D01*
X785556Y330714D01*
X785806Y330214D01*
Y327797D01*
G01X789989D02*
X789489Y327880D01*
X788989Y328214D01*
X788656Y328797D01*
X788489Y329464D01*
X788656Y330130D01*
X788989Y330714D01*
X789489Y331047D01*
X789989Y331130D01*
X790489Y331047D01*
X790989Y330714D01*
X791322Y330130D01*
X791406Y329464D01*
X791322Y328797D01*
X790989Y328214D01*
X790489Y327880D01*
X789989Y327797D01*
G01X795589D02*
Y332797D01*
G01X799939Y330047D02*
X802606D01*
X802356Y330630D01*
X801939Y330964D01*
X801356Y331130D01*
X800772Y331047D01*
X800272Y330797D01*
X799939Y330214D01*
X799772Y329714D01*
Y329214D01*
X799939Y328714D01*
X800356Y328214D01*
X800856Y327880D01*
X801439Y327797D01*
X802022Y327964D01*
X802606Y328464D01*
G01X813889Y327797D02*
Y331130D01*
G01Y330547D02*
X813556Y330880D01*
X813056Y331047D01*
X812472Y331130D01*
X811889Y330964D01*
X811389Y330630D01*
X811056Y330130D01*
X810889Y329464D01*
X811056Y328797D01*
X811389Y328297D01*
X811889Y327964D01*
X812472Y327797D01*
X813056Y327880D01*
X813556Y328130D01*
X813889Y328464D01*
G01X817989Y327797D02*
Y332797D01*
G01X822339Y328380D02*
X822756Y328047D01*
X823339Y327797D01*
X823839D01*
X824339Y327964D01*
X824672Y328214D01*
X824839Y328547D01*
X824756Y329047D01*
X824422Y329297D01*
X822922Y329797D01*
X822589Y330380D01*
X822756Y330797D01*
X823089Y331047D01*
X823589Y331130D01*
X824089Y331047D01*
X824589Y330797D01*
G01X829189Y327797D02*
X828689Y327880D01*
X828189Y328214D01*
X827856Y328797D01*
X827689Y329464D01*
X827856Y330130D01*
X828189Y330714D01*
X828689Y331047D01*
X829189Y331130D01*
X829689Y331047D01*
X830189Y330714D01*
X830522Y330130D01*
X830606Y329464D01*
X830522Y328797D01*
X830189Y328214D01*
X829689Y327880D01*
X829189Y327797D01*
G01X838972D02*
Y331130D01*
G01Y330297D02*
X839306Y330714D01*
X839806Y331047D01*
X840472Y331130D01*
X841056Y331047D01*
X841556Y330714D01*
X841806Y330130D01*
Y327797D01*
G01X844739Y330047D02*
X847406D01*
X847156Y330630D01*
X846739Y330964D01*
X846156Y331130D01*
X845572Y331047D01*
X845072Y330797D01*
X844739Y330214D01*
X844572Y329714D01*
Y329214D01*
X844739Y328714D01*
X845156Y328214D01*
X845656Y327880D01*
X846239Y327797D01*
X846822Y327964D01*
X847406Y328464D01*
G01X850339Y330047D02*
X853006D01*
X852756Y330630D01*
X852339Y330964D01*
X851756Y331130D01*
X851172Y331047D01*
X850672Y330797D01*
X850339Y330214D01*
X850172Y329714D01*
Y329214D01*
X850339Y328714D01*
X850756Y328214D01*
X851256Y327880D01*
X851839Y327797D01*
X852422Y327964D01*
X853006Y328464D01*
G01X858689Y332797D02*
Y327797D01*
G01Y328547D02*
X858356Y328130D01*
X857856Y327880D01*
X857272Y327797D01*
X856606Y327964D01*
X856106Y328380D01*
X855772Y328880D01*
X855689Y329464D01*
X855772Y330047D01*
X856106Y330547D01*
X856606Y330964D01*
X857272Y331130D01*
X857856Y331047D01*
X858272Y330880D01*
X858689Y330547D01*
G01X868389Y332797D02*
Y327797D01*
G01X867222Y331130D02*
X869556D01*
G01X873989Y327797D02*
X873489Y327880D01*
X872989Y328214D01*
X872656Y328797D01*
X872489Y329464D01*
X872656Y330130D01*
X872989Y330714D01*
X873489Y331047D01*
X873989Y331130D01*
X874489Y331047D01*
X874989Y330714D01*
X875322Y330130D01*
X875406Y329464D01*
X875322Y328797D01*
X874989Y328214D01*
X874489Y327880D01*
X873989Y327797D01*
G01X655082Y-129003D02*
Y-134003D01*
X658416D01*
G01X661099Y-130670D02*
X663599Y-134003D01*
G01Y-130670D02*
X661099Y-134003D01*
G01X667949Y-134170D02*
X667782Y-134086D01*
Y-133920D01*
X667949Y-133836D01*
X668116Y-133920D01*
Y-134086D01*
X667949Y-134170D01*
G01Y-131920D02*
X667782Y-131836D01*
Y-131670D01*
X667949Y-131586D01*
X668116Y-131670D01*
Y-131836D01*
X667949Y-131920D01*
G01X676649Y-134003D02*
Y-130670D01*
G01Y-131586D02*
X676899Y-131170D01*
X677316Y-130836D01*
X677899Y-130670D01*
X678482Y-130836D01*
X678899Y-131170D01*
X679149Y-131586D01*
Y-134003D01*
G01Y-131586D02*
X679399Y-131170D01*
X679816Y-130836D01*
X680399Y-130670D01*
X680982Y-130836D01*
X681399Y-131170D01*
X681649Y-131670D01*
Y-134003D01*
G01X683332Y-130670D02*
Y-133003D01*
X683666Y-133586D01*
X684166Y-133920D01*
X684749Y-134003D01*
X685332Y-133920D01*
X685832Y-133586D01*
X686166Y-133003D01*
G01Y-134003D02*
Y-130670D01*
G01X689099Y-133420D02*
X689516Y-133753D01*
X690099Y-134003D01*
X690599D01*
X691099Y-133836D01*
X691432Y-133586D01*
X691599Y-133253D01*
X691516Y-132753D01*
X691182Y-132503D01*
X689682Y-132003D01*
X689349Y-131420D01*
X689516Y-131003D01*
X689849Y-130753D01*
X690349Y-130670D01*
X690849Y-130753D01*
X691349Y-131003D01*
G01X695949Y-129003D02*
Y-134003D01*
G01X694782Y-130670D02*
X697116D01*
G01X705649Y-134003D02*
Y-129003D01*
G01Y-131503D02*
X706066Y-131003D01*
X706566Y-130753D01*
X707066Y-130670D01*
X707816Y-130836D01*
X708316Y-131170D01*
X708649Y-131753D01*
Y-132420D01*
X708482Y-133086D01*
X708149Y-133586D01*
X707566Y-133920D01*
X707066Y-134003D01*
X706566Y-133920D01*
X706066Y-133670D01*
X705649Y-133253D01*
G01X711499Y-131753D02*
X714166D01*
X713916Y-131170D01*
X713499Y-130836D01*
X712916Y-130670D01*
X712332Y-130753D01*
X711832Y-131003D01*
X711499Y-131586D01*
X711332Y-132086D01*
Y-132586D01*
X711499Y-133086D01*
X711916Y-133586D01*
X712416Y-133920D01*
X712999Y-134003D01*
X713582Y-133836D01*
X714166Y-133336D01*
G01X722449Y-134003D02*
Y-129003D01*
G01Y-131503D02*
X722866Y-131003D01*
X723366Y-130753D01*
X723866Y-130670D01*
X724616Y-130836D01*
X725116Y-131170D01*
X725449Y-131753D01*
Y-132420D01*
X725282Y-133086D01*
X724949Y-133586D01*
X724366Y-133920D01*
X723866Y-134003D01*
X723366Y-133920D01*
X722866Y-133670D01*
X722449Y-133253D01*
G01X728382Y-134003D02*
Y-130670D01*
G01Y-131336D02*
X728799Y-131003D01*
X729216Y-130753D01*
X729799Y-130670D01*
X730216Y-130753D01*
X730716Y-131003D01*
G01X735149Y-134003D02*
X734649Y-133920D01*
X734149Y-133586D01*
X733816Y-133003D01*
X733649Y-132336D01*
X733816Y-131670D01*
X734149Y-131086D01*
X734649Y-130753D01*
X735149Y-130670D01*
X735649Y-130753D01*
X736149Y-131086D01*
X736482Y-131670D01*
X736566Y-132336D01*
X736482Y-133003D01*
X736149Y-133586D01*
X735649Y-133920D01*
X735149Y-134003D01*
G01X739332D02*
Y-129003D01*
G01X741999Y-130670D02*
X739332Y-132586D01*
G01X740416Y-131836D02*
X742166Y-134003D01*
G01X745099Y-131753D02*
X747766D01*
X747516Y-131170D01*
X747099Y-130836D01*
X746516Y-130670D01*
X745932Y-130753D01*
X745432Y-131003D01*
X745099Y-131586D01*
X744932Y-132086D01*
Y-132586D01*
X745099Y-133086D01*
X745516Y-133586D01*
X746016Y-133920D01*
X746599Y-134003D01*
X747182Y-133836D01*
X747766Y-133336D01*
G01X750532Y-134003D02*
Y-130670D01*
G01Y-131503D02*
X750866Y-131086D01*
X751366Y-130753D01*
X752032Y-130670D01*
X752616Y-130753D01*
X753116Y-131086D01*
X753366Y-131670D01*
Y-134003D01*
G01X763149D02*
Y-129003D01*
G01X770249Y-134003D02*
Y-130670D01*
G01Y-131253D02*
X769916Y-130920D01*
X769416Y-130753D01*
X768832Y-130670D01*
X768249Y-130836D01*
X767749Y-131170D01*
X767416Y-131670D01*
X767249Y-132336D01*
X767416Y-133003D01*
X767749Y-133503D01*
X768249Y-133836D01*
X768832Y-134003D01*
X769416Y-133920D01*
X769916Y-133670D01*
X770249Y-133336D01*
G01X772599Y-135503D02*
X773099Y-135670D01*
X773766Y-135503D01*
X774182Y-135170D01*
X774516Y-134753D01*
X775016Y-133420D01*
X776099Y-130670D01*
G01X773432D02*
X775016Y-133420D01*
G01X778699Y-131753D02*
X781366D01*
X781116Y-131170D01*
X780699Y-130836D01*
X780116Y-130670D01*
X779532Y-130753D01*
X779032Y-131003D01*
X778699Y-131586D01*
X778532Y-132086D01*
Y-132586D01*
X778699Y-133086D01*
X779116Y-133586D01*
X779616Y-133920D01*
X780199Y-134003D01*
X780782Y-133836D01*
X781366Y-133336D01*
G01X784382Y-134003D02*
Y-130670D01*
G01Y-131336D02*
X784799Y-131003D01*
X785216Y-130753D01*
X785799Y-130670D01*
X786216Y-130753D01*
X786716Y-131003D01*
G01X654482Y-116503D02*
Y-121503D01*
X657816D01*
G01X660332D02*
Y-118170D01*
G01Y-119003D02*
X660666Y-118586D01*
X661166Y-118253D01*
X661832Y-118170D01*
X662416Y-118253D01*
X662916Y-118586D01*
X663166Y-119170D01*
Y-121503D01*
G01X667349Y-121670D02*
X667182Y-121586D01*
Y-121420D01*
X667349Y-121336D01*
X667516Y-121420D01*
Y-121586D01*
X667349Y-121670D01*
G01Y-119420D02*
X667182Y-119336D01*
Y-119170D01*
X667349Y-119086D01*
X667516Y-119170D01*
Y-119336D01*
X667349Y-119420D01*
G01X679882Y-118586D02*
X679299Y-118253D01*
X678799Y-118170D01*
X678132Y-118336D01*
X677632Y-118670D01*
X677299Y-119253D01*
X677216Y-119836D01*
X677299Y-120420D01*
X677632Y-120920D01*
X678132Y-121336D01*
X678799Y-121503D01*
X679382Y-121336D01*
X679882Y-121003D01*
G01X685649Y-121503D02*
Y-118170D01*
G01Y-118753D02*
X685316Y-118420D01*
X684816Y-118253D01*
X684232Y-118170D01*
X683649Y-118336D01*
X683149Y-118670D01*
X682816Y-119170D01*
X682649Y-119836D01*
X682816Y-120503D01*
X683149Y-121003D01*
X683649Y-121336D01*
X684232Y-121503D01*
X684816Y-121420D01*
X685316Y-121170D01*
X685649Y-120836D01*
G01X688332Y-121503D02*
Y-118170D01*
G01Y-119003D02*
X688666Y-118586D01*
X689166Y-118253D01*
X689832Y-118170D01*
X690416Y-118253D01*
X690916Y-118586D01*
X691166Y-119170D01*
Y-121503D01*
G01X695349Y-118170D02*
X696182Y-117128D01*
Y-116503D01*
X695557D01*
Y-117128D01*
X696182D01*
G01X700949Y-116503D02*
Y-121503D01*
G01X699782Y-118170D02*
X702116D01*
G01X710649Y-121503D02*
Y-116503D01*
G01Y-119003D02*
X711066Y-118503D01*
X711566Y-118253D01*
X712066Y-118170D01*
X712816Y-118336D01*
X713316Y-118670D01*
X713649Y-119253D01*
Y-119920D01*
X713482Y-120586D01*
X713149Y-121086D01*
X712566Y-121420D01*
X712066Y-121503D01*
X711566Y-121420D01*
X711066Y-121170D01*
X710649Y-120753D01*
G01X716499Y-119253D02*
X719166D01*
X718916Y-118670D01*
X718499Y-118336D01*
X717916Y-118170D01*
X717332Y-118253D01*
X716832Y-118503D01*
X716499Y-119086D01*
X716332Y-119586D01*
Y-120086D01*
X716499Y-120586D01*
X716916Y-121086D01*
X717416Y-121420D01*
X717999Y-121503D01*
X718582Y-121336D01*
X719166Y-120836D01*
G01X727449Y-121503D02*
Y-116503D01*
G01Y-119003D02*
X727866Y-118503D01*
X728366Y-118253D01*
X728866Y-118170D01*
X729616Y-118336D01*
X730116Y-118670D01*
X730449Y-119253D01*
Y-119920D01*
X730282Y-120586D01*
X729949Y-121086D01*
X729366Y-121420D01*
X728866Y-121503D01*
X728366Y-121420D01*
X727866Y-121170D01*
X727449Y-120753D01*
G01X733382Y-121503D02*
Y-118170D01*
G01Y-118836D02*
X733799Y-118503D01*
X734216Y-118253D01*
X734799Y-118170D01*
X735216Y-118253D01*
X735716Y-118503D01*
G01X740149Y-121503D02*
X739649Y-121420D01*
X739149Y-121086D01*
X738816Y-120503D01*
X738649Y-119836D01*
X738816Y-119170D01*
X739149Y-118586D01*
X739649Y-118253D01*
X740149Y-118170D01*
X740649Y-118253D01*
X741149Y-118586D01*
X741482Y-119170D01*
X741566Y-119836D01*
X741482Y-120503D01*
X741149Y-121086D01*
X740649Y-121420D01*
X740149Y-121503D01*
G01X744332D02*
Y-116503D01*
G01X746999Y-118170D02*
X744332Y-120086D01*
G01X745416Y-119336D02*
X747166Y-121503D01*
G01X750099Y-119253D02*
X752766D01*
X752516Y-118670D01*
X752099Y-118336D01*
X751516Y-118170D01*
X750932Y-118253D01*
X750432Y-118503D01*
X750099Y-119086D01*
X749932Y-119586D01*
Y-120086D01*
X750099Y-120586D01*
X750516Y-121086D01*
X751016Y-121420D01*
X751599Y-121503D01*
X752182Y-121336D01*
X752766Y-120836D01*
G01X755532Y-121503D02*
Y-118170D01*
G01Y-119003D02*
X755866Y-118586D01*
X756366Y-118253D01*
X757032Y-118170D01*
X757616Y-118253D01*
X758116Y-118586D01*
X758366Y-119170D01*
Y-121503D01*
G01X768149D02*
Y-116503D01*
G01X775249Y-121503D02*
Y-118170D01*
G01Y-118753D02*
X774916Y-118420D01*
X774416Y-118253D01*
X773832Y-118170D01*
X773249Y-118336D01*
X772749Y-118670D01*
X772416Y-119170D01*
X772249Y-119836D01*
X772416Y-120503D01*
X772749Y-121003D01*
X773249Y-121336D01*
X773832Y-121503D01*
X774416Y-121420D01*
X774916Y-121170D01*
X775249Y-120836D01*
G01X777599Y-123003D02*
X778099Y-123170D01*
X778766Y-123003D01*
X779182Y-122670D01*
X779516Y-122253D01*
X780016Y-120920D01*
X781099Y-118170D01*
G01X778432D02*
X780016Y-120920D01*
G01X783699Y-119253D02*
X786366D01*
X786116Y-118670D01*
X785699Y-118336D01*
X785116Y-118170D01*
X784532Y-118253D01*
X784032Y-118503D01*
X783699Y-119086D01*
X783532Y-119586D01*
Y-120086D01*
X783699Y-120586D01*
X784116Y-121086D01*
X784616Y-121420D01*
X785199Y-121503D01*
X785782Y-121336D01*
X786366Y-120836D01*
G01X789382Y-121503D02*
Y-118170D01*
G01Y-118836D02*
X789799Y-118503D01*
X790216Y-118253D01*
X790799Y-118170D01*
X791216Y-118253D01*
X791716Y-118503D01*
G01X653256Y-109703D02*
Y-104703D01*
X654922D01*
X655589Y-104953D01*
X656089Y-105286D01*
X656506Y-105786D01*
X656839Y-106370D01*
X656922Y-107203D01*
X656839Y-108036D01*
X656506Y-108620D01*
X656089Y-109120D01*
X655589Y-109453D01*
X654922Y-109703D01*
X653256D01*
G01X659522D02*
Y-106370D01*
G01Y-107036D02*
X659939Y-106703D01*
X660356Y-106453D01*
X660939Y-106370D01*
X661356Y-106453D01*
X661856Y-106703D01*
G01X666289Y-106370D02*
Y-109703D01*
G01Y-105036D02*
X666122Y-104953D01*
Y-104786D01*
X666289Y-104703D01*
X666456Y-104786D01*
Y-104953D01*
X666289Y-105036D01*
G01X671889Y-109703D02*
Y-104703D01*
G01X677489Y-109703D02*
Y-104703D01*
G01X687106Y-109703D02*
Y-104703D01*
X690272D01*
G01X689106Y-107120D02*
X687106D01*
G01X693122Y-109703D02*
Y-106370D01*
G01Y-107036D02*
X693539Y-106703D01*
X693956Y-106453D01*
X694539Y-106370D01*
X694956Y-106453D01*
X695456Y-106703D01*
G01X699889Y-109703D02*
X699389Y-109620D01*
X698889Y-109286D01*
X698556Y-108703D01*
X698389Y-108036D01*
X698556Y-107370D01*
X698889Y-106786D01*
X699389Y-106453D01*
X699889Y-106370D01*
X700389Y-106453D01*
X700889Y-106786D01*
X701222Y-107370D01*
X701306Y-108036D01*
X701222Y-108703D01*
X700889Y-109286D01*
X700389Y-109620D01*
X699889Y-109703D01*
G01X702989D02*
Y-106370D01*
G01Y-107286D02*
X703239Y-106870D01*
X703656Y-106536D01*
X704239Y-106370D01*
X704822Y-106536D01*
X705239Y-106870D01*
X705489Y-107286D01*
Y-109703D01*
G01Y-107286D02*
X705739Y-106870D01*
X706156Y-106536D01*
X706739Y-106370D01*
X707322Y-106536D01*
X707739Y-106870D01*
X707989Y-107370D01*
Y-109703D01*
G01X733072Y-111370D02*
X732239Y-110536D01*
X731822Y-109703D01*
Y-106370D01*
X732239Y-105536D01*
X733072Y-104703D01*
G01X739756Y-107036D02*
X740089Y-106786D01*
X740339Y-106370D01*
X740506Y-105786D01*
X740339Y-105286D01*
X740006Y-104953D01*
X739422Y-104703D01*
X737172D01*
Y-109703D01*
X739922D01*
X740506Y-109370D01*
X740839Y-108870D01*
X741006Y-108286D01*
X740839Y-107703D01*
X740339Y-107203D01*
X739756Y-107036D01*
X737172D01*
G01X744689Y-109703D02*
X744022Y-109620D01*
X743439Y-109286D01*
X742939Y-108786D01*
X742606Y-108203D01*
X742439Y-107536D01*
Y-106870D01*
X742606Y-106203D01*
X742939Y-105620D01*
X743439Y-105120D01*
X744022Y-104786D01*
X744689Y-104703D01*
X745356Y-104786D01*
X745939Y-105120D01*
X746439Y-105620D01*
X746772Y-106203D01*
X746939Y-106870D01*
Y-107536D01*
X746772Y-108203D01*
X746439Y-108786D01*
X745939Y-109286D01*
X745356Y-109620D01*
X744689Y-109703D01*
G01X750289Y-104703D02*
Y-109703D01*
G01X748372Y-104703D02*
X752206D01*
G01X755889D02*
Y-109703D01*
G01X753972Y-104703D02*
X757806D01*
G01X761489Y-109703D02*
X760822Y-109620D01*
X760239Y-109286D01*
X759739Y-108786D01*
X759406Y-108203D01*
X759239Y-107536D01*
Y-106870D01*
X759406Y-106203D01*
X759739Y-105620D01*
X760239Y-105120D01*
X760822Y-104786D01*
X761489Y-104703D01*
X762156Y-104786D01*
X762739Y-105120D01*
X763239Y-105620D01*
X763572Y-106203D01*
X763739Y-106870D01*
Y-107536D01*
X763572Y-108203D01*
X763239Y-108786D01*
X762739Y-109286D01*
X762156Y-109620D01*
X761489Y-109703D01*
G01X764922D02*
Y-104703D01*
X767089Y-108870D01*
X769256Y-104703D01*
Y-109703D01*
G01X773106Y-111370D02*
X773939Y-110536D01*
X774356Y-109703D01*
Y-106370D01*
X773939Y-105536D01*
X773106Y-104703D01*
G01X783889D02*
Y-109703D01*
G01X782722Y-106370D02*
X785056D01*
G01X789489Y-109703D02*
X788989Y-109620D01*
X788489Y-109286D01*
X788156Y-108703D01*
X787989Y-108036D01*
X788156Y-107370D01*
X788489Y-106786D01*
X788989Y-106453D01*
X789489Y-106370D01*
X789989Y-106453D01*
X790489Y-106786D01*
X790822Y-107370D01*
X790906Y-108036D01*
X790822Y-108703D01*
X790489Y-109286D01*
X789989Y-109620D01*
X789489Y-109703D01*
G01X799022Y-104703D02*
Y-109703D01*
X802356D01*
G01X805039Y-106370D02*
X807539Y-109703D01*
G01Y-106370D02*
X805039Y-109703D01*
G01X675422Y356797D02*
Y361797D01*
X677422D01*
X678089Y361547D01*
X678589Y360964D01*
X678756Y360297D01*
X678589Y359630D01*
X678172Y359130D01*
X677422Y358880D01*
X675422D01*
G01X682689Y356797D02*
Y361797D01*
G01X686872Y360130D02*
Y357797D01*
X687206Y357214D01*
X687706Y356880D01*
X688289Y356797D01*
X688872Y356880D01*
X689372Y357214D01*
X689706Y357797D01*
G01Y356797D02*
Y360130D01*
G01X692722Y355547D02*
X693306Y355214D01*
X693972Y355130D01*
X694556Y355214D01*
X695056Y355630D01*
X695389Y356214D01*
Y360130D01*
G01Y359464D02*
X695056Y359797D01*
X694556Y360047D01*
X693972Y360130D01*
X693306Y359964D01*
X692889Y359630D01*
X692556Y359047D01*
X692389Y358464D01*
X692472Y357964D01*
X692806Y357380D01*
X693306Y356964D01*
X693972Y356797D01*
X694472Y356880D01*
X695056Y357214D01*
X695389Y357547D01*
G01X698322Y355547D02*
X698906Y355214D01*
X699572Y355130D01*
X700156Y355214D01*
X700656Y355630D01*
X700989Y356214D01*
Y360130D01*
G01Y359464D02*
X700656Y359797D01*
X700156Y360047D01*
X699572Y360130D01*
X698906Y359964D01*
X698489Y359630D01*
X698156Y359047D01*
X697989Y358464D01*
X698072Y357964D01*
X698406Y357380D01*
X698906Y356964D01*
X699572Y356797D01*
X700072Y356880D01*
X700656Y357214D01*
X700989Y357547D01*
G01X705089Y360130D02*
Y356797D01*
G01Y361464D02*
X704922Y361547D01*
Y361714D01*
X705089Y361797D01*
X705256Y361714D01*
Y361547D01*
X705089Y361464D01*
G01X709272Y356797D02*
Y360130D01*
G01Y359297D02*
X709606Y359714D01*
X710106Y360047D01*
X710772Y360130D01*
X711356Y360047D01*
X711856Y359714D01*
X712106Y359130D01*
Y356797D01*
G01X715122Y355547D02*
X715706Y355214D01*
X716372Y355130D01*
X716956Y355214D01*
X717456Y355630D01*
X717789Y356214D01*
Y360130D01*
G01Y359464D02*
X717456Y359797D01*
X716956Y360047D01*
X716372Y360130D01*
X715706Y359964D01*
X715289Y359630D01*
X714956Y359047D01*
X714789Y358464D01*
X714872Y357964D01*
X715206Y357380D01*
X715706Y356964D01*
X716372Y356797D01*
X716872Y356880D01*
X717456Y357214D01*
X717789Y357547D01*
G01X728822Y359714D02*
X728239Y360047D01*
X727739Y360130D01*
X727072Y359964D01*
X726572Y359630D01*
X726239Y359047D01*
X726156Y358464D01*
X726239Y357880D01*
X726572Y357380D01*
X727072Y356964D01*
X727739Y356797D01*
X728322Y356964D01*
X728822Y357297D01*
G01X731922Y356797D02*
Y360130D01*
G01Y359464D02*
X732339Y359797D01*
X732756Y360047D01*
X733339Y360130D01*
X733756Y360047D01*
X734256Y359797D01*
G01X738689Y360130D02*
Y356797D01*
G01Y361464D02*
X738522Y361547D01*
Y361714D01*
X738689Y361797D01*
X738856Y361714D01*
Y361547D01*
X738689Y361464D01*
G01X744289Y361797D02*
Y356797D01*
G01X743122Y360130D02*
X745456D01*
G01X748639Y359047D02*
X751306D01*
X751056Y359630D01*
X750639Y359964D01*
X750056Y360130D01*
X749472Y360047D01*
X748972Y359797D01*
X748639Y359214D01*
X748472Y358714D01*
Y358214D01*
X748639Y357714D01*
X749056Y357214D01*
X749556Y356880D01*
X750139Y356797D01*
X750722Y356964D01*
X751306Y357464D01*
G01X754322Y356797D02*
Y360130D01*
G01Y359464D02*
X754739Y359797D01*
X755156Y360047D01*
X755739Y360130D01*
X756156Y360047D01*
X756656Y359797D01*
G01X761089Y360130D02*
Y356797D01*
G01Y361464D02*
X760922Y361547D01*
Y361714D01*
X761089Y361797D01*
X761256Y361714D01*
Y361547D01*
X761089Y361464D01*
G01X768189Y356797D02*
Y360130D01*
G01Y359547D02*
X767856Y359880D01*
X767356Y360047D01*
X766772Y360130D01*
X766189Y359964D01*
X765689Y359630D01*
X765356Y359130D01*
X765189Y358464D01*
X765356Y357797D01*
X765689Y357297D01*
X766189Y356964D01*
X766772Y356797D01*
X767356Y356880D01*
X767856Y357130D01*
X768189Y357464D01*
G01X672006Y501797D02*
X674089Y496797D01*
X676172Y501797D01*
G01X678689D02*
X680689D01*
G01X679689D02*
Y496797D01*
G01X678689D02*
X680689D01*
G01X683622D02*
Y501797D01*
X685622D01*
X686289Y501547D01*
X686789Y500964D01*
X686956Y500297D01*
X686789Y499630D01*
X686372Y499130D01*
X685622Y498880D01*
X683622D01*
G01X701756Y-76003D02*
Y-71003D01*
X703422D01*
X704089Y-71253D01*
X704589Y-71586D01*
X705006Y-72086D01*
X705339Y-72670D01*
X705422Y-73503D01*
X705339Y-74336D01*
X705006Y-74920D01*
X704589Y-75420D01*
X704089Y-75753D01*
X703422Y-76003D01*
X701756D01*
G01X707606Y-71836D02*
X708106Y-71336D01*
X708689Y-71086D01*
X709356Y-71003D01*
X710189Y-71170D01*
X710772Y-71586D01*
X710939Y-72086D01*
X710856Y-72586D01*
X710522Y-73003D01*
X708856Y-73836D01*
X708106Y-74420D01*
X707606Y-75253D01*
X707439Y-76003D01*
X710939D01*
G01X700756Y81997D02*
Y86997D01*
X702422D01*
X703089Y86747D01*
X703589Y86414D01*
X704006Y85914D01*
X704339Y85330D01*
X704422Y84497D01*
X704339Y83664D01*
X704006Y83080D01*
X703589Y82580D01*
X703089Y82247D01*
X702422Y81997D01*
X700756D01*
G01X708189D02*
Y86997D01*
X707189Y85997D01*
G01Y81997D02*
X709189D01*
G01X702422Y386214D02*
X701839Y386547D01*
X701339Y386630D01*
X700672Y386464D01*
X700172Y386130D01*
X699839Y385547D01*
X699756Y384964D01*
X699839Y384380D01*
X700172Y383880D01*
X700672Y383464D01*
X701339Y383297D01*
X701922Y383464D01*
X702422Y383797D01*
G01X706689Y383297D02*
X706189Y383380D01*
X705689Y383714D01*
X705356Y384297D01*
X705189Y384964D01*
X705356Y385630D01*
X705689Y386214D01*
X706189Y386547D01*
X706689Y386630D01*
X707189Y386547D01*
X707689Y386214D01*
X708022Y385630D01*
X708106Y384964D01*
X708022Y384297D01*
X707689Y383714D01*
X707189Y383380D01*
X706689Y383297D01*
G01X710789Y381630D02*
Y386630D01*
G01Y385880D02*
X711206Y386297D01*
X711622Y386547D01*
X712289Y386630D01*
X712872Y386547D01*
X713456Y386130D01*
X713706Y385547D01*
X713789Y384964D01*
X713706Y384380D01*
X713456Y383797D01*
X712956Y383464D01*
X712289Y383297D01*
X711706Y383380D01*
X711122Y383630D01*
X710789Y383964D01*
G01X716389Y381630D02*
Y386630D01*
G01Y385880D02*
X716806Y386297D01*
X717222Y386547D01*
X717889Y386630D01*
X718472Y386547D01*
X719056Y386130D01*
X719306Y385547D01*
X719389Y384964D01*
X719306Y384380D01*
X719056Y383797D01*
X718556Y383464D01*
X717889Y383297D01*
X717306Y383380D01*
X716722Y383630D01*
X716389Y383964D01*
G01X722239Y385547D02*
X724906D01*
X724656Y386130D01*
X724239Y386464D01*
X723656Y386630D01*
X723072Y386547D01*
X722572Y386297D01*
X722239Y385714D01*
X722072Y385214D01*
Y384714D01*
X722239Y384214D01*
X722656Y383714D01*
X723156Y383380D01*
X723739Y383297D01*
X724322Y383464D01*
X724906Y383964D01*
G01X727922Y383297D02*
Y386630D01*
G01Y385964D02*
X728339Y386297D01*
X728756Y386547D01*
X729339Y386630D01*
X729756Y386547D01*
X730256Y386297D01*
G01X750256Y-83336D02*
X750589Y-83086D01*
X750839Y-82670D01*
X751006Y-82086D01*
X750839Y-81586D01*
X750506Y-81253D01*
X749922Y-81003D01*
X747672D01*
Y-86003D01*
X750422D01*
X751006Y-85670D01*
X751339Y-85170D01*
X751506Y-84586D01*
X751339Y-84003D01*
X750839Y-83503D01*
X750256Y-83336D01*
X747672D01*
G01X753106Y-86003D02*
X755189Y-81003D01*
X757272Y-86003D01*
G01X756522Y-84253D02*
X753856D01*
G01X762622Y-81420D02*
X762122Y-81170D01*
X761539Y-81003D01*
X760872D01*
X760122Y-81253D01*
X759539Y-81670D01*
X759122Y-82170D01*
X758789Y-83003D01*
X758706Y-83753D01*
X758872Y-84503D01*
X759122Y-85003D01*
X759622Y-85503D01*
X760206Y-85836D01*
X760789Y-86003D01*
X761372D01*
X761956Y-85836D01*
X762456Y-85586D01*
X762872Y-85253D01*
G01X764556Y-86003D02*
Y-81003D01*
G01X767722D02*
X764556Y-84086D01*
G01X768222Y-86003D02*
X765972Y-82670D01*
G01X775756Y-86003D02*
Y-81003D01*
X777422D01*
X778089Y-81253D01*
X778589Y-81586D01*
X779006Y-82086D01*
X779339Y-82670D01*
X779422Y-83503D01*
X779339Y-84336D01*
X779006Y-84920D01*
X778589Y-85420D01*
X778089Y-85753D01*
X777422Y-86003D01*
X775756D01*
G01X781522D02*
Y-81003D01*
X783606D01*
X784272Y-81253D01*
X784689Y-81586D01*
X784856Y-82253D01*
X784689Y-82920D01*
X784189Y-83336D01*
X783606Y-83586D01*
X781522D01*
G01X783606D02*
X784856Y-86003D01*
G01X787789Y-81003D02*
X789789D01*
G01X788789D02*
Y-86003D01*
G01X787789D02*
X789789D01*
G01X792722Y-81003D02*
Y-86003D01*
X796056D01*
G01X798322Y-81003D02*
Y-86003D01*
X801656D01*
G01X825489D02*
Y-82670D01*
G01Y-83586D02*
X825739Y-83170D01*
X826156Y-82836D01*
X826739Y-82670D01*
X827322Y-82836D01*
X827739Y-83170D01*
X827989Y-83586D01*
Y-86003D01*
G01Y-83586D02*
X828239Y-83170D01*
X828656Y-82836D01*
X829239Y-82670D01*
X829822Y-82836D01*
X830239Y-83170D01*
X830489Y-83670D01*
Y-86003D01*
G01X833589Y-82670D02*
Y-86003D01*
G01Y-81336D02*
X833422Y-81253D01*
Y-81086D01*
X833589Y-81003D01*
X833756Y-81086D01*
Y-81253D01*
X833589Y-81336D01*
G01X839189Y-86003D02*
Y-81003D01*
G01X843539Y-85420D02*
X843956Y-85753D01*
X844539Y-86003D01*
X845039D01*
X845539Y-85836D01*
X845872Y-85586D01*
X846039Y-85253D01*
X845956Y-84753D01*
X845622Y-84503D01*
X844122Y-84003D01*
X843789Y-83420D01*
X843956Y-83003D01*
X844289Y-82753D01*
X844789Y-82670D01*
X845289Y-82753D01*
X845789Y-83003D01*
G01X849972Y-87670D02*
X849139Y-86836D01*
X848722Y-86003D01*
Y-82670D01*
X849139Y-81836D01*
X849972Y-81003D01*
G01X854072Y-86003D02*
Y-81003D01*
X857906Y-86003D01*
Y-81003D01*
G01X859922Y-86003D02*
Y-81003D01*
X861922D01*
X862589Y-81253D01*
X863089Y-81836D01*
X863256Y-82503D01*
X863089Y-83170D01*
X862672Y-83670D01*
X861922Y-83920D01*
X859922D01*
G01X867189Y-81003D02*
Y-86003D01*
G01X865272Y-81003D02*
X869106D01*
G01X871039Y-86003D02*
Y-81003D01*
G01X874539D02*
Y-86003D01*
G01Y-83503D02*
X871039D01*
G01X878806Y-87670D02*
X879639Y-86836D01*
X880056Y-86003D01*
Y-82670D01*
X879639Y-81836D01*
X878806Y-81003D01*
G01X744339Y81797D02*
Y86797D01*
G01X747839D02*
Y81797D01*
G01Y84297D02*
X744339D01*
G01X751689Y81797D02*
X751022Y81880D01*
X750439Y82214D01*
X749939Y82714D01*
X749606Y83297D01*
X749439Y83964D01*
Y84630D01*
X749606Y85297D01*
X749939Y85880D01*
X750439Y86380D01*
X751022Y86714D01*
X751689Y86797D01*
X752356Y86714D01*
X752939Y86380D01*
X753439Y85880D01*
X753772Y85297D01*
X753939Y84630D01*
Y83964D01*
X753772Y83297D01*
X753439Y82714D01*
X752939Y82214D01*
X752356Y81880D01*
X751689Y81797D01*
G01X755622Y86797D02*
Y81797D01*
X758956D01*
G01X764556D02*
X761222D01*
Y86797D01*
X764556D01*
G01X763222Y84380D02*
X761222D01*
G01X788389Y81797D02*
Y85130D01*
G01Y84214D02*
X788639Y84630D01*
X789056Y84964D01*
X789639Y85130D01*
X790222Y84964D01*
X790639Y84630D01*
X790889Y84214D01*
Y81797D01*
G01Y84214D02*
X791139Y84630D01*
X791556Y84964D01*
X792139Y85130D01*
X792722Y84964D01*
X793139Y84630D01*
X793389Y84130D01*
Y81797D01*
G01X796489Y85130D02*
Y81797D01*
G01Y86464D02*
X796322Y86547D01*
Y86714D01*
X796489Y86797D01*
X796656Y86714D01*
Y86547D01*
X796489Y86464D01*
G01X802089Y81797D02*
Y86797D01*
G01X806439Y82380D02*
X806856Y82047D01*
X807439Y81797D01*
X807939D01*
X808439Y81964D01*
X808772Y82214D01*
X808939Y82547D01*
X808856Y83047D01*
X808522Y83297D01*
X807022Y83797D01*
X806689Y84380D01*
X806856Y84797D01*
X807189Y85047D01*
X807689Y85130D01*
X808189Y85047D01*
X808689Y84797D01*
G01X812872Y80130D02*
X812039Y80964D01*
X811622Y81797D01*
Y85130D01*
X812039Y85964D01*
X812872Y86797D01*
G01X817222Y81797D02*
Y86797D01*
X819222D01*
X819889Y86547D01*
X820389Y85964D01*
X820556Y85297D01*
X820389Y84630D01*
X819972Y84130D01*
X819222Y83880D01*
X817222D01*
G01X824489Y86797D02*
Y81797D01*
G01X822572Y86797D02*
X826406D01*
G01X828339Y81797D02*
Y86797D01*
G01X831839D02*
Y81797D01*
G01Y84297D02*
X828339D01*
G01X836106Y80130D02*
X836939Y80964D01*
X837356Y81797D01*
Y85130D01*
X836939Y85964D01*
X836106Y86797D01*
G01X746006Y500797D02*
X748089Y495797D01*
X750172Y500797D01*
G01X753689Y495797D02*
X753022Y495880D01*
X752439Y496214D01*
X751939Y496714D01*
X751606Y497297D01*
X751439Y497964D01*
Y498630D01*
X751606Y499297D01*
X751939Y499880D01*
X752439Y500380D01*
X753022Y500714D01*
X753689Y500797D01*
X754356Y500714D01*
X754939Y500380D01*
X755439Y499880D01*
X755772Y499297D01*
X755939Y498630D01*
Y497964D01*
X755772Y497297D01*
X755439Y496714D01*
X754939Y496214D01*
X754356Y495880D01*
X753689Y495797D01*
G01X757622D02*
Y500797D01*
X759622D01*
X760289Y500547D01*
X760789Y499964D01*
X760956Y499297D01*
X760789Y498630D01*
X760372Y498130D01*
X759622Y497880D01*
X757622D01*
G01X772922Y26797D02*
Y21797D01*
X776256D01*
G01X778772D02*
Y25130D01*
G01Y24297D02*
X779106Y24714D01*
X779606Y25047D01*
X780272Y25130D01*
X780856Y25047D01*
X781356Y24714D01*
X781606Y24130D01*
Y21797D01*
G01X775922Y-15003D02*
Y-20003D01*
X779256D01*
G01X781939Y-16670D02*
X784439Y-20003D01*
G01Y-16670D02*
X781939Y-20003D01*
G01X783839Y47880D02*
X784256Y47547D01*
X784839Y47297D01*
X785339D01*
X785839Y47464D01*
X786172Y47714D01*
X786339Y48047D01*
X786256Y48547D01*
X785922Y48797D01*
X784422Y49297D01*
X784089Y49880D01*
X784256Y50297D01*
X784589Y50547D01*
X785089Y50630D01*
X785589Y50547D01*
X786089Y50297D01*
G01X790689Y52297D02*
Y47297D01*
G01X789522Y50630D02*
X791856D01*
G01X794872D02*
Y48297D01*
X795206Y47714D01*
X795706Y47380D01*
X796289Y47297D01*
X796872Y47380D01*
X797372Y47714D01*
X797706Y48297D01*
G01Y47297D02*
Y50630D01*
G01X800389Y47297D02*
Y52297D01*
G01Y49797D02*
X800806Y50297D01*
X801306Y50547D01*
X801806Y50630D01*
X802556Y50464D01*
X803056Y50130D01*
X803389Y49547D01*
Y48880D01*
X803222Y48214D01*
X802889Y47714D01*
X802306Y47380D01*
X801806Y47297D01*
X801306Y47380D01*
X800806Y47630D01*
X800389Y48047D01*
G01X813089Y47297D02*
Y52297D01*
G01X817439Y49547D02*
X820106D01*
X819856Y50130D01*
X819439Y50464D01*
X818856Y50630D01*
X818272Y50547D01*
X817772Y50297D01*
X817439Y49714D01*
X817272Y49214D01*
Y48714D01*
X817439Y48214D01*
X817856Y47714D01*
X818356Y47380D01*
X818939Y47297D01*
X819522Y47464D01*
X820106Y47964D01*
G01X822872Y47297D02*
Y50630D01*
G01Y49797D02*
X823206Y50214D01*
X823706Y50547D01*
X824372Y50630D01*
X824956Y50547D01*
X825456Y50214D01*
X825706Y49630D01*
Y47297D01*
G01X828722Y46047D02*
X829306Y45714D01*
X829972Y45630D01*
X830556Y45714D01*
X831056Y46130D01*
X831389Y46714D01*
Y50630D01*
G01Y49964D02*
X831056Y50297D01*
X830556Y50547D01*
X829972Y50630D01*
X829306Y50464D01*
X828889Y50130D01*
X828556Y49547D01*
X828389Y48964D01*
X828472Y48464D01*
X828806Y47880D01*
X829306Y47464D01*
X829972Y47297D01*
X830472Y47380D01*
X831056Y47714D01*
X831389Y48047D01*
G01X835489Y52297D02*
Y47297D01*
G01X834322Y50630D02*
X836656D01*
G01X839672Y47297D02*
Y52297D01*
G01Y49880D02*
X840089Y50297D01*
X840506Y50547D01*
X841172Y50630D01*
X841672Y50547D01*
X842256Y50214D01*
X842506Y49714D01*
Y47297D01*
G01X845606Y48214D02*
X847772D01*
G01Y49714D02*
X845606D01*
G01X850706Y49380D02*
X851289Y49964D01*
X851789Y50297D01*
X852456Y50464D01*
X853039Y50297D01*
X853456Y49964D01*
X853789Y49464D01*
X853872Y48880D01*
X853789Y48380D01*
X853456Y47880D01*
X852956Y47464D01*
X852372Y47297D01*
X851706Y47464D01*
X851122Y47964D01*
X850789Y48714D01*
X850706Y49547D01*
X850872Y50630D01*
X851122Y51214D01*
X851539Y51797D01*
X852122Y52214D01*
X852706Y52297D01*
X853289Y52130D01*
X853706Y51714D01*
G01X856972Y48964D02*
X858972D01*
G01X857889Y50047D02*
Y47880D01*
G01X861989Y47130D02*
X864989Y52297D01*
G01X868006Y48964D02*
X870172D01*
G01X872856Y48047D02*
X873356Y47630D01*
X873939Y47380D01*
X874689Y47297D01*
X875439Y47464D01*
X876022Y47797D01*
X876439Y48380D01*
X876522Y49047D01*
X876356Y49714D01*
X875939Y50130D01*
X875356Y50464D01*
X874772Y50547D01*
X874189Y50464D01*
X873439Y50130D01*
X873689Y52297D01*
X875939D01*
G01X877789Y47297D02*
Y50630D01*
G01Y49714D02*
X878039Y50130D01*
X878456Y50464D01*
X879039Y50630D01*
X879622Y50464D01*
X880039Y50130D01*
X880289Y49714D01*
Y47297D01*
G01Y49714D02*
X880539Y50130D01*
X880956Y50464D01*
X881539Y50630D01*
X882122Y50464D01*
X882539Y50130D01*
X882789Y49630D01*
Y47297D01*
G01X885889Y50630D02*
Y47297D01*
G01Y51964D02*
X885722Y52047D01*
Y52214D01*
X885889Y52297D01*
X886056Y52214D01*
Y52047D01*
X885889Y51964D01*
G01X891489Y47297D02*
Y52297D01*
G01X808382Y551740D02*
X807549Y552574D01*
X807132Y553407D01*
Y556740D01*
X807549Y557574D01*
X808382Y558407D01*
G01X814399Y553407D02*
Y558407D01*
X813399Y557407D01*
G01Y553407D02*
X815399D01*
G01X819999Y553240D02*
X819832Y553324D01*
Y553490D01*
X819999Y553574D01*
X820166Y553490D01*
Y553324D01*
X819999Y553240D01*
G01X824016Y557574D02*
X824516Y558074D01*
X825099Y558324D01*
X825766Y558407D01*
X826599Y558240D01*
X827182Y557824D01*
X827349Y557324D01*
X827266Y556824D01*
X826932Y556407D01*
X825266Y555574D01*
X824516Y554990D01*
X824016Y554157D01*
X823849Y553407D01*
X827349D01*
G01X828699D02*
Y556740D01*
G01Y555824D02*
X828949Y556240D01*
X829366Y556574D01*
X829949Y556740D01*
X830532Y556574D01*
X830949Y556240D01*
X831199Y555824D01*
Y553407D01*
G01Y555824D02*
X831449Y556240D01*
X831866Y556574D01*
X832449Y556740D01*
X833032Y556574D01*
X833449Y556240D01*
X833699Y555740D01*
Y553407D01*
G01X834299D02*
Y556740D01*
G01Y555824D02*
X834549Y556240D01*
X834966Y556574D01*
X835549Y556740D01*
X836132Y556574D01*
X836549Y556240D01*
X836799Y555824D01*
Y553407D01*
G01Y555824D02*
X837049Y556240D01*
X837466Y556574D01*
X838049Y556740D01*
X838632Y556574D01*
X839049Y556240D01*
X839299Y555740D01*
Y553407D01*
G01X845832D02*
Y558407D01*
X847999Y554240D01*
X850166Y558407D01*
Y553407D01*
G01X855099D02*
Y556740D01*
G01Y556157D02*
X854766Y556490D01*
X854266Y556657D01*
X853682Y556740D01*
X853099Y556574D01*
X852599Y556240D01*
X852266Y555740D01*
X852099Y555074D01*
X852266Y554407D01*
X852599Y553907D01*
X853099Y553574D01*
X853682Y553407D01*
X854266Y553490D01*
X854766Y553740D01*
X855099Y554074D01*
G01X857949Y556740D02*
X860449Y553407D01*
G01Y556740D02*
X857949Y553407D01*
G01X865216Y551740D02*
X866049Y552574D01*
X866466Y553407D01*
Y556740D01*
X866049Y557574D01*
X865216Y558407D01*
G01X800129Y616797D02*
Y548297D01*
G01X806672Y577964D02*
X808672D01*
G01X807589Y579047D02*
Y576880D01*
G01X811689Y576130D02*
X814689Y581297D01*
G01X817706Y577964D02*
X819872D01*
G01X822806Y580464D02*
X823306Y580964D01*
X823889Y581214D01*
X824556Y581297D01*
X825389Y581130D01*
X825972Y580714D01*
X826139Y580214D01*
X826056Y579714D01*
X825722Y579297D01*
X824056Y578464D01*
X823306Y577880D01*
X822806Y577047D01*
X822639Y576297D01*
X826139D01*
G01X827489D02*
Y579630D01*
G01Y578714D02*
X827739Y579130D01*
X828156Y579464D01*
X828739Y579630D01*
X829322Y579464D01*
X829739Y579130D01*
X829989Y578714D01*
Y576297D01*
G01Y578714D02*
X830239Y579130D01*
X830656Y579464D01*
X831239Y579630D01*
X831822Y579464D01*
X832239Y579130D01*
X832489Y578630D01*
Y576297D01*
G01X835589Y579630D02*
Y576297D01*
G01Y580964D02*
X835422Y581047D01*
Y581214D01*
X835589Y581297D01*
X835756Y581214D01*
Y581047D01*
X835589Y580964D01*
G01X841189Y576297D02*
Y581297D01*
G01X810466Y563527D02*
X807132Y565194D01*
X810466Y566860D01*
G01X813316Y564444D02*
X815482D01*
G01Y565944D02*
X813316D01*
G01X819999Y568527D02*
X819332Y568360D01*
X818832Y567944D01*
X818499Y567444D01*
X818249Y566777D01*
X818166Y566027D01*
X818249Y565277D01*
X818499Y564610D01*
X818832Y564110D01*
X819332Y563694D01*
X819999Y563527D01*
X820666Y563694D01*
X821166Y564110D01*
X821499Y564610D01*
X821749Y565277D01*
X821832Y566027D01*
X821749Y566777D01*
X821499Y567444D01*
X821166Y567944D01*
X820666Y568360D01*
X819999Y568527D01*
G01X825599Y563360D02*
X825432Y563444D01*
Y563610D01*
X825599Y563694D01*
X825766Y563610D01*
Y563444D01*
X825599Y563360D01*
G01X831032Y563527D02*
X831199Y564610D01*
X831449Y565527D01*
X831782Y566360D01*
X832199Y567277D01*
X832866Y568527D01*
X829532D01*
G01X834966Y564277D02*
X835466Y563860D01*
X836049Y563610D01*
X836799Y563527D01*
X837549Y563694D01*
X838132Y564027D01*
X838549Y564610D01*
X838632Y565277D01*
X838466Y565944D01*
X838049Y566360D01*
X837466Y566694D01*
X836882Y566777D01*
X836299Y566694D01*
X835549Y566360D01*
X835799Y568527D01*
X838049D01*
G01X840899Y563360D02*
X843899Y568527D01*
G01X840899D02*
X840399Y568360D01*
X840149Y568110D01*
X839982Y567610D01*
X840149Y567110D01*
X840399Y566860D01*
X840899Y566694D01*
X841399Y566860D01*
X841649Y567110D01*
X841816Y567610D01*
X841649Y568110D01*
X841399Y568360D01*
X840899Y568527D01*
G01X843899Y565194D02*
X843399Y565027D01*
X843149Y564777D01*
X842982Y564277D01*
X843149Y563777D01*
X843399Y563527D01*
X843899Y563360D01*
X844399Y563527D01*
X844649Y563777D01*
X844816Y564277D01*
X844649Y564777D01*
X844399Y565027D01*
X843899Y565194D01*
G01X806672Y592964D02*
X808672D01*
G01X807589Y594047D02*
Y591880D01*
G01X811689Y591130D02*
X814689Y596297D01*
G01X817706Y592964D02*
X819872D01*
G01X822556Y592047D02*
X823056Y591630D01*
X823639Y591380D01*
X824389Y591297D01*
X825139Y591464D01*
X825722Y591797D01*
X826139Y592380D01*
X826222Y593047D01*
X826056Y593714D01*
X825639Y594130D01*
X825056Y594464D01*
X824472Y594547D01*
X823889Y594464D01*
X823139Y594130D01*
X823389Y596297D01*
X825639D01*
G01X827489Y591297D02*
Y594630D01*
G01Y593714D02*
X827739Y594130D01*
X828156Y594464D01*
X828739Y594630D01*
X829322Y594464D01*
X829739Y594130D01*
X829989Y593714D01*
Y591297D01*
G01Y593714D02*
X830239Y594130D01*
X830656Y594464D01*
X831239Y594630D01*
X831822Y594464D01*
X832239Y594130D01*
X832489Y593630D01*
Y591297D01*
G01X835589Y594630D02*
Y591297D01*
G01Y595964D02*
X835422Y596047D01*
Y596214D01*
X835589Y596297D01*
X835756Y596214D01*
Y596047D01*
X835589Y595964D01*
G01X841189Y591297D02*
Y596297D01*
G01X806672Y607964D02*
X808672D01*
G01X807589Y609047D02*
Y606880D01*
G01X811689Y606130D02*
X814689Y611297D01*
G01X817706Y607964D02*
X819872D01*
G01X822556Y607047D02*
X823056Y606630D01*
X823639Y606380D01*
X824389Y606297D01*
X825139Y606464D01*
X825722Y606797D01*
X826139Y607380D01*
X826222Y608047D01*
X826056Y608714D01*
X825639Y609130D01*
X825056Y609464D01*
X824472Y609547D01*
X823889Y609464D01*
X823139Y609130D01*
X823389Y611297D01*
X825639D01*
G01X827489Y606297D02*
Y609630D01*
G01Y608714D02*
X827739Y609130D01*
X828156Y609464D01*
X828739Y609630D01*
X829322Y609464D01*
X829739Y609130D01*
X829989Y608714D01*
Y606297D01*
G01Y608714D02*
X830239Y609130D01*
X830656Y609464D01*
X831239Y609630D01*
X831822Y609464D01*
X832239Y609130D01*
X832489Y608630D01*
Y606297D01*
G01X835589Y609630D02*
Y606297D01*
G01Y610964D02*
X835422Y611047D01*
Y611214D01*
X835589Y611297D01*
X835756Y611214D01*
Y611047D01*
X835589Y610964D01*
G01X841189Y606297D02*
Y611297D01*
G01X908589Y616907D02*
Y548407D01*
G54D12*
G01X431441Y401651D02*
X409441D01*
G01D02*
Y478651D01*
G01D02*
X431441D01*
G01X423191Y394776D02*
X438316D01*
G01X423191Y401651D02*
Y394776D01*
G01X431441Y478651D02*
Y401651D01*
G01X423191Y488276D02*
Y481401D01*
G01X438316Y488276D02*
X423191D01*
G01X438316Y394776D02*
Y488276D01*
G01X472691Y394776D02*
Y401651D01*
G01X457566Y394776D02*
X472691D01*
G01X457566Y488276D02*
Y394776D01*
G01X464441Y478651D02*
Y401651D01*
G01D02*
X508441D01*
G01Y478651D02*
X464441D01*
G01X472691Y481401D02*
Y488276D01*
G01D02*
X457566D01*
G01X500191Y394776D02*
X515316D01*
G01X500191Y401651D02*
Y394776D01*
G01Y488276D02*
Y481401D01*
G01X515316Y488276D02*
X500191D01*
G01X515316Y394776D02*
Y488276D01*
G01X508441Y401651D02*
Y478651D01*
G01X534566Y394776D02*
X549691D01*
G01X534566Y488276D02*
Y394776D01*
G01X541441Y478651D02*
Y401651D01*
G01D02*
X585441D01*
G01Y478651D02*
X541441D01*
G01X549691Y488276D02*
X534566D01*
G01X549691Y394776D02*
Y401651D01*
G01Y481401D02*
Y488276D01*
G01X592316Y394776D02*
Y485526D01*
G01X577191Y394776D02*
X592316D01*
G01X577191Y401651D02*
Y394776D01*
G01X585441Y401651D02*
Y478651D01*
G01X577191Y485526D02*
Y478651D01*
G01X592316Y485526D02*
X577191D01*
G01X611566Y394776D02*
X626691D01*
G01X611566Y485526D02*
Y394776D01*
G01X626691Y485526D02*
X611566D01*
G01X626691Y394776D02*
Y401651D01*
G01X618441Y478651D02*
Y401651D01*
G01D02*
X662441D01*
G01X626691Y478651D02*
Y485526D01*
G01X662441Y478651D02*
X618441D01*
G01X654191Y394776D02*
X688566D01*
G01X654191Y401651D02*
Y394776D01*
G01Y485526D02*
Y478651D01*
G01X669316Y485526D02*
X654191D01*
G01X662441Y401651D02*
Y478651D01*
G01X703691Y485526D02*
X669316D01*
G01X703691Y394776D02*
Y401651D01*
G01X688566Y394776D02*
X703691D01*
G01X695441Y478651D02*
Y401651D01*
G01D02*
X739441D01*
G01Y478651D02*
X695441D01*
G01X703691D02*
Y485526D01*
G01X746316Y394776D02*
Y485526D01*
G01X731191Y394776D02*
X746316D01*
G01X731191Y401651D02*
Y394776D01*
G01X739441Y401651D02*
Y478651D01*
G01X731191Y485526D02*
Y478651D01*
G01X746316Y485526D02*
X731191D01*
G01X765566Y394776D02*
X780691D01*
G01X765566Y485526D02*
Y394776D01*
G01X772441Y478651D02*
Y401651D01*
G01D02*
X816441D01*
G01Y478651D02*
X772441D01*
G01X780691Y485526D02*
X765566D01*
G01X780691Y394776D02*
Y401651D01*
G01Y478651D02*
Y485526D01*
G01X816441Y401651D02*
Y478651D01*
G54D13*
G01X-142321Y107127D02*
Y124127D01*
G01X-131321Y86127D02*
Y70127D01*
G01X-92821Y86127D02*
Y70127D01*
G01X-88731Y93977D02*
G02X-84049Y86157I-4190J-7820D01*
G01X-86221Y88077D01*
X-82991Y88247D01*
X-83951Y86147D01*
G01X-77929Y96450D02*
X-81959Y90960D01*
X-77759Y90940D01*
G01X-81821Y107127D02*
Y124127D01*
G01X5151Y67840D02*
X1121Y62350D01*
X5321Y62330D01*
G54D14*
G01X436741Y485526D02*
X430141Y492126D01*
G01X434408Y485526D02*
X427808Y492126D01*
G01X432074Y485526D02*
X425474Y492126D01*
G01X429740Y485526D02*
X423140Y492126D01*
G01X427407Y485526D02*
X421368Y491564D01*
G01X425074Y485526D02*
X420202Y490398D01*
G01X422916Y485350D02*
X419341Y488925D01*
G01X422916Y483017D02*
X419341Y486592D01*
G01X422916Y480684D02*
X419341Y484258D01*
G01X422339Y478926D02*
X419341Y481925D01*
G01X420006Y478926D02*
X419341Y479592D01*
G01X434247Y485526D02*
X439207Y490486D01*
G01X431913Y485526D02*
X438513Y492126D01*
G01X429580Y485526D02*
X436180Y492126D01*
G01X420647Y478926D02*
X422916Y481196D01*
G01X427247Y485526D02*
X433847Y492126D01*
G01X419341Y479954D02*
X422916Y483529D01*
G01X424912Y485526D02*
X431512Y492126D01*
G01X419341Y482288D02*
X429179Y492126D01*
G01X419341Y484621D02*
X426846Y492126D01*
G01X419341Y486954D02*
X424512Y492126D01*
G01X419341Y489288D02*
X422179Y492126D01*
G01X419341Y478926D02*
Y489537D01*
G01X422916Y478926D02*
X419341D01*
G01X422916Y485801D02*
Y478926D01*
G01X423191Y485526D02*
X422916Y485801D01*
G01X438591Y485526D02*
X423191D01*
G01X421929Y492126D02*
X438514D01*
G01X457291Y469643D02*
X434808Y492126D01*
G01X457291Y467310D02*
X432475Y492126D01*
G01X419341Y489537D02*
X421929Y492126D01*
G01X457291Y441642D02*
X456685Y442248D01*
G01X456546Y442490D02*
X457291Y443233D01*
G01X455577Y443854D02*
X457291Y445567D01*
G01Y440941D02*
X457290Y440942D01*
G01X457291Y485526D02*
Y440941D01*
G01X439634Y442965D02*
X438591Y444008D01*
G01X438804Y441460D02*
X438591Y441674D01*
G01Y443202D02*
X457291Y461900D01*
G01X438591Y440941D02*
Y485526D01*
G01Y440942D02*
Y440941D01*
G01X457290Y440942D02*
G03X438592I-9349J-3541D01*
G01X454412Y445022D02*
X457291Y447901D01*
G01X453051Y445994D02*
X457291Y450234D01*
G01X451476Y446752D02*
X457291Y452567D01*
G01X449643Y447253D02*
X457291Y454901D01*
G01X447443Y447386D02*
X457291Y457234D01*
G01Y464976D02*
X438591Y483676D01*
G01X457291Y462643D02*
X438591Y481343D01*
G01X457291Y460310D02*
X438591Y479009D01*
G01X457291Y457976D02*
X438591Y476676D01*
G01X457291Y455643D02*
X438591Y474343D01*
G01X457291Y453309D02*
X438591Y472008D01*
G01X457291Y450975D02*
X438591Y469675D01*
G01X457291Y448642D02*
X438591Y467342D01*
G01X457291Y446309D02*
X438591Y465008D01*
G01Y457202D02*
X457291Y475901D01*
G01X438591Y459535D02*
X457291Y478235D01*
G01X438591Y461869D02*
X457291Y480569D01*
G01X438591Y464203D02*
X457291Y482902D01*
G01X438591Y466536D02*
X457291Y485236D01*
G01Y443975D02*
X438591Y462675D01*
G01X452787Y446145D02*
X438591Y460342D01*
G01X449292Y447307D02*
X438591Y458008D01*
G01X446919Y447346D02*
X438591Y455674D01*
G01X444981Y446950D02*
X438591Y453341D01*
G01X443327Y446271D02*
X438591Y451008D01*
G01X441899Y445366D02*
X438591Y448674D01*
G01X440669Y444263D02*
X438591Y446341D01*
G01X444518Y446794D02*
X457291Y459567D01*
G01X438591Y445535D02*
X457291Y464235D01*
G01X438591Y447868D02*
X457291Y466568D01*
G01X438591Y450202D02*
X457291Y468901D01*
G01X438591Y452535D02*
X457291Y471235D01*
G01X438591Y454868D02*
X457291Y473568D01*
G01X459761Y485840D02*
X456083Y489518D01*
G01X457516Y485752D02*
X455029Y488239D01*
G01X457291Y483644D02*
X453780Y487154D01*
G01X457291Y481311D02*
X452327Y486274D01*
G01X457291Y478977D02*
X450642Y485625D01*
G01X457291Y476644D02*
X448659Y485275D01*
G01X457291Y474311D02*
X446196Y485404D01*
G01X457604Y485840D02*
X457291Y485526D01*
G01Y471976D02*
X442142Y487126D01*
G01X439916Y489351D02*
X437141Y492126D01*
G01X438591Y468869D02*
X461847Y492126D01*
G01X438591Y471203D02*
X459514Y492126D01*
G01X438591Y473536D02*
X450695Y485641D01*
G01X438591Y475869D02*
X447971Y485249D01*
G01X438591Y478204D02*
X445859Y485471D01*
G01X438591Y480537D02*
X444085Y486031D01*
G01X438591Y482870D02*
X442560Y486839D01*
G01X438591Y485204D02*
X441244Y487857D01*
G01X436580Y485526D02*
X440125Y489072D01*
G01X438514Y492126D02*
G03X457368I9427J3024D01*
G01D02*
X515514D01*
G01X462096Y485840D02*
X456931Y491004D01*
G01X478983Y478926D02*
X492182Y492125D01*
G01X490009Y478926D02*
X476810Y492126D01*
G01X487676Y478926D02*
X474476Y492126D01*
G01X485343Y478926D02*
X472143Y492126D01*
G01X483009Y478926D02*
X469810Y492126D01*
G01X480676Y478926D02*
X467476Y492126D01*
G01X478343Y478926D02*
X472966Y484303D01*
G01X471429Y485840D02*
X465143Y492126D01*
G01X476010Y478926D02*
X472966Y481970D01*
G01X469096Y485840D02*
X462810Y492126D01*
G01X473675Y478926D02*
X472966Y479636D01*
G01X466762Y485840D02*
X460475Y492126D01*
G01X464429Y485840D02*
X458142Y492126D01*
G01X476650Y478926D02*
X489849Y492126D01*
G01X474316Y478926D02*
X487516Y492126D01*
G01X472966Y479910D02*
X485181Y492125D01*
G01X472966Y482243D02*
X482848Y492126D01*
G01X472966Y484577D02*
X480515Y492126D01*
G01X471896Y485840D02*
X478181Y492125D01*
G01X469561Y485840D02*
X475848Y492126D01*
G01X467228Y485840D02*
X473515Y492126D01*
G01X464895Y485840D02*
X471182Y492126D01*
G01X462561Y485840D02*
X468847Y492126D01*
G01X460228Y485840D02*
X466514Y492126D01*
G01X457895Y485840D02*
X464181Y492126D01*
G01X472746Y485840D02*
X457604D01*
G01X472966Y485801D02*
X472746Y485840D01*
G01X472966Y478926D02*
Y485801D01*
G01X499916Y478926D02*
X472966D01*
G01X492343D02*
X479143Y492126D01*
G01X499916Y396684D02*
X496341Y400258D01*
G01X498626Y391230D02*
X501896Y394501D01*
G01X497458Y392397D02*
X499916Y394853D01*
G01X496341Y393612D02*
X499916Y397187D01*
G01X496341Y395946D02*
X499916Y399521D01*
G01X496341Y398280D02*
X499437Y401376D01*
G01X499916Y394501D02*
X515591D01*
G01X499916Y401376D02*
Y394501D01*
G01X496341Y393515D02*
Y401376D01*
G01X505673Y390926D02*
X502098Y394501D01*
G01X503339Y390926D02*
X496341Y397924D01*
G01X501006Y390926D02*
X496341Y395591D01*
G01X500655Y390926D02*
X504229Y394500D01*
G01X550951Y390926D02*
X498929D01*
G01D02*
X496341Y393515D01*
G01X499916Y401350D02*
X499889Y401376D01*
G01X499916Y399017D02*
X497556Y401376D01*
G01X496341Y400613D02*
X497104Y401376D01*
G01X496341D02*
X499916D01*
G01X504135Y485801D02*
X497812Y492126D01*
G01X501802Y485801D02*
X495477Y492126D01*
G01X499916Y485355D02*
X493144Y492126D01*
G01X499916Y483022D02*
X490811Y492126D01*
G01X499916Y480687D02*
X488477Y492126D01*
G01X499344Y478926D02*
X486144Y492126D01*
G01X497011Y478926D02*
X483811Y492126D01*
G01X494677Y478926D02*
X481477Y492126D01*
G01X497650Y478926D02*
X499916Y481191D01*
G01X495317Y478926D02*
X499916Y483525D01*
G01X502192Y485801D02*
X508517Y492126D01*
G01X492984Y478926D02*
X506184Y492126D01*
G01X490651Y478926D02*
X503849Y492126D01*
G01X488316Y478926D02*
X501516Y492126D01*
G01X485983Y478926D02*
X499183Y492126D01*
G01X483650Y478926D02*
X496849Y492126D01*
G01X481316Y478926D02*
X494516Y492126D01*
G01X499916Y485801D02*
Y478926D01*
G01X515591Y485801D02*
X499916D01*
G01X508803D02*
X502478Y492126D01*
G01X506470Y485801D02*
X500145Y492126D01*
G01X515591Y396529D02*
X534291Y415229D01*
G01X515591Y394501D02*
Y485801D01*
G01X531341Y390926D02*
X515591Y406676D01*
G01X529008Y390926D02*
X515591Y404343D01*
G01X526674Y390926D02*
X515591Y402009D01*
G01X524340Y390926D02*
X515591Y399676D01*
G01X522007Y390926D02*
X515591Y397343D01*
G01X519674Y390926D02*
X515591Y395008D01*
G01X517340Y390926D02*
X513765Y394501D01*
G01X523989Y390926D02*
X534291Y401228D01*
G01X521656Y390926D02*
X534291Y403561D01*
G01X519322Y390926D02*
X534291Y405894D01*
G01X516989Y390926D02*
X534291Y408228D01*
G01X514656Y390926D02*
X534291Y410561D01*
G01X512322Y390926D02*
X534291Y412894D01*
G01X515007Y390926D02*
X511432Y394501D01*
G01X512674Y390926D02*
X509099Y394501D01*
G01X510339Y390926D02*
X506764Y394501D01*
G01X508006Y390926D02*
X504431Y394501D01*
G01X509989Y390926D02*
X513564Y394501D01*
G01X507655Y390926D02*
X511229Y394500D01*
G01X505322Y390926D02*
X508896Y394501D01*
G01X502988Y390926D02*
X506563Y394500D01*
G01X534291Y411310D02*
X515591Y430010D01*
G01X534291Y408977D02*
X515591Y427677D01*
G01X534291Y406644D02*
X515591Y425344D01*
G01X534291Y404311D02*
X515591Y423010D01*
G01X534291Y401977D02*
X515591Y420677D01*
G01X534291Y399644D02*
X515591Y418344D01*
G01X534291Y397311D02*
X515591Y416010D01*
G01X534291Y394976D02*
X515591Y413676D01*
G01Y398862D02*
X534291Y417562D01*
G01X515591Y401195D02*
X534291Y419895D01*
G01X515591Y403529D02*
X534291Y422228D01*
G01X515591Y405862D02*
X534291Y424562D01*
G01X515591Y408195D02*
X534291Y426895D01*
G01X515591Y410529D02*
X534291Y429228D01*
G01X515591Y412862D02*
X534291Y431562D01*
G01X515591Y415196D02*
X534291Y433896D01*
G01X515591Y417530D02*
X534291Y436229D01*
G01X515591Y419863D02*
X534291Y438563D01*
G01X536008Y390926D02*
X515591Y411343D01*
G01X533675Y390926D02*
X515591Y409009D01*
G01X534291Y434646D02*
X515591Y453345D01*
G01X534291Y432312D02*
X515591Y451012D01*
G01X534291Y429978D02*
X515591Y448678D01*
G01X534291Y427645D02*
X515591Y446344D01*
G01X534291Y425311D02*
X515591Y444011D01*
G01Y424530D02*
X534291Y443229D01*
G01X515591Y426863D02*
X534291Y445563D01*
G01X515591Y429196D02*
X534291Y447896D01*
G01X515591Y431531D02*
X534291Y450229D01*
G01X515591Y433864D02*
X534291Y452564D01*
G01X515591Y436197D02*
X534291Y454897D01*
G01X515591Y438531D02*
X534291Y457230D01*
G01X515591Y440864D02*
X534291Y459564D01*
G01X515591Y443197D02*
X534291Y461897D01*
G01Y422978D02*
X515591Y441678D01*
G01X534291Y420645D02*
X515591Y439345D01*
G01X534291Y418311D02*
X515591Y437011D01*
G01X534291Y415978D02*
X515591Y434678D01*
G01X534291Y413645D02*
X515591Y432345D01*
G01Y422196D02*
X534291Y440896D01*
G01X515591Y457198D02*
X534291Y475898D01*
G01X515591Y459531D02*
X534291Y478231D01*
G01X515591Y461865D02*
X534291Y480564D01*
G01X515591Y464198D02*
X534291Y482898D01*
G01X515591Y466531D02*
X534291Y485231D01*
G01Y455647D02*
X515591Y474346D01*
G01X534291Y453313D02*
X515591Y472013D01*
G01X534291Y450980D02*
X515591Y469680D01*
G01X534291Y448647D02*
X515591Y467345D01*
G01X534291Y446312D02*
X515591Y465012D01*
G01X534291Y443979D02*
X515591Y462679D01*
G01X534291Y441646D02*
X515591Y460345D01*
G01X534291Y439312D02*
X515591Y458012D01*
G01X534291Y436979D02*
X515591Y455679D01*
G01Y445530D02*
X534291Y464230D01*
G01X515591Y447864D02*
X534291Y466564D01*
G01X515591Y450198D02*
X534291Y468898D01*
G01X515591Y452531D02*
X534291Y471231D01*
G01X515591Y454865D02*
X534291Y473565D01*
G01Y474314D02*
X523202Y485403D01*
G01X534291Y471981D02*
X519156Y487116D01*
G01X516906Y489364D02*
X514145Y492126D01*
G01X534291Y464980D02*
X515591Y483680D01*
G01X534291Y462647D02*
X515591Y481346D01*
G01X534291Y460313D02*
X515591Y479013D01*
G01X534291Y457980D02*
X515591Y476680D01*
G01Y468866D02*
X538851Y492125D01*
G01X515591Y471199D02*
X536518Y492126D01*
G01X515591Y473532D02*
X527701Y485642D01*
G01X515591Y475866D02*
X524975Y485249D01*
G01X515591Y478199D02*
X522862Y485470D01*
G01X515591Y480532D02*
X521088Y486030D01*
G01X515591Y482866D02*
X519563Y486837D01*
G01X515591Y485200D02*
X518246Y487855D01*
G01X513858Y485801D02*
X517128Y489069D01*
G01X515514Y492126D02*
G03X534368I9427J3024D01*
G01X534291Y469647D02*
X511811Y492126D01*
G01X534291Y467314D02*
X509478Y492126D01*
G01X513470Y485801D02*
X507145Y492126D01*
G01X511137Y485801D02*
X504812Y492126D01*
G01X511525Y485801D02*
X516208Y490484D01*
G01X509192Y485801D02*
X515514Y492123D01*
G01X506859Y485801D02*
X513184Y492126D01*
G01X504525Y485801D02*
X510850Y492126D01*
G01X550009Y390926D02*
X546434Y394501D01*
G01X547324Y390926D02*
X553541Y397142D01*
G01X544991Y390926D02*
X548566Y394501D01*
G01X547675Y390926D02*
X544101Y394501D01*
G01X545341Y390926D02*
X541766Y394501D01*
G01X534291D02*
X549966D01*
G01X534291Y485801D02*
Y394501D01*
G01X543008Y390926D02*
X539433Y394501D01*
G01X540674Y390926D02*
X537100Y394501D01*
G01X538341Y390926D02*
X534766Y394501D01*
G01X542657Y390926D02*
X546231Y394501D01*
G01X540323Y390926D02*
X543898Y394501D01*
G01X537990Y390926D02*
X541565Y394501D01*
G01X535657Y390926D02*
X539232Y394501D01*
G01X533323Y390926D02*
X536898Y394501D01*
G01X530990Y390926D02*
X534565Y394501D01*
G01X528657Y390926D02*
X534291Y396560D01*
G01X526322Y390926D02*
X534291Y398894D01*
G01X546527Y485801D02*
X551902Y491176D01*
G01X553541Y483066D02*
X544480Y492126D01*
G01X548472Y485801D02*
X542147Y492126D01*
G01X546138Y485801D02*
X539813Y492126D01*
G01X543805Y485801D02*
X537480Y492126D01*
G01X541472Y485801D02*
X535147Y492126D01*
G01X539137Y485801D02*
X533932Y491006D01*
G01X536804Y485801D02*
X533085Y489520D01*
G01X534471Y485801D02*
X532031Y488240D01*
G01X534291Y483647D02*
X530782Y487156D01*
G01X534291Y481314D02*
X529330Y486275D01*
G01X534291Y478981D02*
X527646Y485626D01*
G01X534291Y476647D02*
X525662Y485275D01*
G01X544194Y485801D02*
X550519Y492126D01*
G01X541860Y485801D02*
X548185Y492126D01*
G01X539527Y485801D02*
X545852Y492126D01*
G01X537194Y485801D02*
X543519Y492126D01*
G01X534860Y485801D02*
X541185Y492126D01*
G01X549966Y485801D02*
X534291D01*
G01X553541Y485399D02*
X546813Y492126D01*
G01X534368D02*
X550951D01*
G01X553541Y396728D02*
X549966Y400303D01*
G01X553541Y394395D02*
X549966Y397970D01*
G01X552814Y392787D02*
X549966Y395635D01*
G01X551647Y391621D02*
X548767Y394501D01*
G01X549966Y395902D02*
X553541Y399477D01*
G01X549966Y398235D02*
X553106Y401376D01*
G01X553541D02*
Y393515D01*
G01X549966Y394501D02*
Y401376D01*
G01X549658Y390926D02*
X553541Y394809D01*
G01Y393515D02*
X550951Y390926D01*
G01X553541Y399061D02*
X551226Y401375D01*
G01X549966Y400569D02*
X550773Y401376D01*
G01X549966D02*
X553541D01*
G01Y487733D02*
X549147Y492126D01*
G01X553541Y480732D02*
X549966Y484306D01*
G01X553013Y478926D02*
X549966Y481973D01*
G01X550680Y478926D02*
X549966Y479640D01*
G01X551320Y478926D02*
X553541Y481147D01*
G01X549966Y479905D02*
X553541Y483480D01*
G01X549966Y482239D02*
X553541Y485814D01*
G01X549966Y484573D02*
X553541Y488148D01*
G01X548860Y485801D02*
X553069Y490009D01*
G01X549966Y478926D02*
Y485801D01*
G01X553541Y478926D02*
X549966D01*
G01X553541Y489537D02*
Y478926D01*
G01X550951Y492126D02*
X553541Y489537D01*
G01X683914Y399176D02*
X688291Y403553D01*
G01X681580Y399176D02*
X688291Y405886D01*
G01X679247Y399176D02*
X688291Y408219D01*
G01X676914Y399176D02*
X688291Y410554D01*
G01Y415985D02*
X669591Y434685D01*
G01X688291Y413652D02*
X669591Y432352D01*
G01X674579Y399176D02*
X688291Y412887D01*
G01X672246Y399176D02*
X688291Y415220D01*
G01X669913Y399176D02*
X688291Y417554D01*
G01X669591Y401187D02*
X688291Y419887D01*
G01X669591Y403521D02*
X688291Y422220D01*
G01X669591Y405854D02*
X688291Y424554D01*
G01X669591Y408187D02*
X688291Y426887D01*
G01X669591Y410522D02*
X688291Y429221D01*
G01X669591Y412855D02*
X688291Y431555D01*
G01X669591Y415188D02*
X688291Y433888D01*
G01X669591Y417522D02*
X688291Y436221D01*
G01X669591Y419855D02*
X688291Y438555D01*
G01Y411319D02*
X669591Y430018D01*
G01X688291Y408985D02*
X669591Y427685D01*
G01X688291Y406652D02*
X669591Y425352D01*
G01X688291Y404319D02*
X669591Y423018D01*
G01X688291Y401985D02*
X669591Y420685D01*
G01X688291Y399651D02*
X669591Y418351D01*
G01X686433Y399176D02*
X669591Y416017D01*
G01X684099Y399176D02*
X669591Y413684D01*
G01X681766Y399176D02*
X669591Y411351D01*
G01X679433Y399176D02*
X669591Y409017D01*
G01X677098Y399176D02*
X669591Y406684D01*
G01X674765Y399176D02*
X669591Y404351D01*
G01X672432Y399176D02*
X669591Y402018D01*
G01X670098Y399176D02*
X669591Y399683D01*
G01X688291Y399176D02*
X669591D01*
G01D02*
Y481126D01*
G01Y424521D02*
X688291Y443221D01*
G01X669591Y426856D02*
X688291Y445556D01*
G01X669591Y429189D02*
X688291Y447889D01*
G01X669591Y431522D02*
X688291Y450222D01*
G01X669591Y433856D02*
X688291Y452555D01*
G01X669591Y436189D02*
X688291Y454889D01*
G01X669591Y438522D02*
X688291Y457222D01*
G01X669591Y440856D02*
X688291Y459555D01*
G01X669591Y443189D02*
X688291Y461889D01*
G01Y439320D02*
X669591Y458020D01*
G01X688291Y436987D02*
X669591Y455687D01*
G01X688291Y434653D02*
X669591Y453353D01*
G01X688291Y432319D02*
X669591Y451019D01*
G01X688291Y429986D02*
X669591Y448686D01*
G01X688291Y427653D02*
X669591Y446353D01*
G01X688291Y425320D02*
X669591Y444019D01*
G01X688291Y422986D02*
X669591Y441686D01*
G01X688291Y420653D02*
X669591Y439353D01*
G01X688291Y418320D02*
X669591Y437018D01*
G01Y422188D02*
X688291Y440888D01*
G01X669591Y457190D02*
X688291Y475890D01*
G01X669591Y459523D02*
X688291Y478223D01*
G01X669591Y461858D02*
X688291Y480556D01*
G01X669591Y464191D02*
X686526Y481126D01*
G01X669591Y466524D02*
X684193Y481126D01*
G01X688291Y460321D02*
X669591Y479021D01*
G01X688291Y457988D02*
X669591Y476688D01*
G01X688291Y455655D02*
X669591Y474354D01*
G01X688291Y453320D02*
X669591Y472020D01*
G01X688291Y450987D02*
X669591Y469687D01*
G01X688291Y448654D02*
X669591Y467353D01*
G01X688291Y446320D02*
X669591Y465020D01*
G01Y445523D02*
X688291Y464223D01*
G01X669591Y447857D02*
X688291Y466556D01*
G01X669591Y450190D02*
X688291Y468890D01*
G01X669591Y452523D02*
X688291Y471223D01*
G01X669591Y454857D02*
X688291Y473556D01*
G01Y443987D02*
X669591Y462687D01*
G01X688291Y441654D02*
X669591Y460354D01*
G01X688291Y476656D02*
X683820Y481126D01*
G01X688291Y474322D02*
X681486Y481126D01*
G01X688291Y471989D02*
X679153Y481126D01*
G01X669591Y468858D02*
X681859Y481126D01*
G01X669591Y471191D02*
X679526Y481126D01*
G01X669591Y473524D02*
X677193Y481126D01*
G01X669591Y475858D02*
X674859Y481126D01*
G01X669591Y478191D02*
X672526Y481126D01*
G01X669591Y480525D02*
X670193Y481126D01*
G01X688291Y469655D02*
X676820Y481126D01*
G01X688291Y467321D02*
X674486Y481126D01*
G01X688291Y464988D02*
X672153Y481126D01*
G01X688291Y462655D02*
X669820Y481126D01*
G01X669591D02*
X688291D01*
G01X686247Y399176D02*
X688291Y401219D01*
G01Y481126D02*
Y399176D01*
G01Y478989D02*
X686154Y481126D01*
G01X751584Y399176D02*
X765291Y412882D01*
G01X749251Y399176D02*
X765291Y415216D01*
G01X746916Y399176D02*
X765291Y417550D01*
G01X746591Y401184D02*
X765291Y419883D01*
G01X746591Y403517D02*
X765291Y422217D01*
G01X746591Y405850D02*
X765291Y424550D01*
G01X746591Y408184D02*
X765291Y426883D01*
G01X746591Y410517D02*
X765291Y429217D01*
G01X746591Y412850D02*
X765291Y431550D01*
G01X746591Y415185D02*
X765291Y433883D01*
G01X746591Y417518D02*
X765291Y436218D01*
G01X746591Y419851D02*
X765291Y438551D01*
G01Y406656D02*
X746591Y425355D01*
G01X765291Y404322D02*
X746591Y423022D01*
G01X765291Y401989D02*
X746591Y420689D01*
G01X765291Y399656D02*
X746591Y418355D01*
G01X763436Y399176D02*
X746591Y416022D01*
G01X761103Y399176D02*
X746591Y413689D01*
G01X758770Y399176D02*
X746591Y411354D01*
G01X756436Y399176D02*
X746591Y409021D01*
G01X754103Y399176D02*
X746591Y406688D01*
G01X751770Y399176D02*
X746591Y404354D01*
G01X749435Y399176D02*
X746591Y402021D01*
G01X747102Y399176D02*
X746591Y399688D01*
G01X765291Y399176D02*
X746591D01*
G01D02*
Y481126D01*
G01Y424518D02*
X765291Y443218D01*
G01X746591Y426851D02*
X765291Y445551D01*
G01X746591Y429185D02*
X765291Y447884D01*
G01X746591Y431518D02*
X765291Y450218D01*
G01X746591Y433852D02*
X765291Y452552D01*
G01X746591Y436185D02*
X765291Y454885D01*
G01X746591Y438519D02*
X765291Y457219D01*
G01X746591Y440852D02*
X765291Y459552D01*
G01X746591Y443185D02*
X765291Y461885D01*
G01Y429991D02*
X746591Y448689D01*
G01X765291Y427656D02*
X746591Y446356D01*
G01X765291Y425323D02*
X746591Y444023D01*
G01Y422185D02*
X765291Y440884D01*
G01Y422990D02*
X746591Y441690D01*
G01X765291Y420656D02*
X746591Y439356D01*
G01X765291Y418323D02*
X746591Y437023D01*
G01X765291Y415990D02*
X746591Y434690D01*
G01X765291Y413657D02*
X746591Y432356D01*
G01X765291Y411322D02*
X746591Y430022D01*
G01X765291Y408989D02*
X746591Y427689D01*
G01Y457186D02*
X765291Y475886D01*
G01X746591Y459520D02*
X765291Y478219D01*
G01X746591Y461853D02*
X765291Y480553D01*
G01X746591Y464186D02*
X763530Y481126D01*
G01X746591Y466520D02*
X761197Y481126D01*
G01X746591Y445519D02*
X765291Y464219D01*
G01X746591Y447852D02*
X765291Y466552D01*
G01X746591Y450185D02*
X765291Y468885D01*
G01X746591Y452520D02*
X765291Y471219D01*
G01X746591Y454853D02*
X765291Y473553D01*
G01Y453325D02*
X746591Y472025D01*
G01X765291Y450992D02*
X746591Y469691D01*
G01X765291Y448658D02*
X746591Y467358D01*
G01X765291Y446324D02*
X746591Y465024D01*
G01X765291Y443991D02*
X746591Y462690D01*
G01X765291Y441657D02*
X746591Y460357D01*
G01X765291Y439324D02*
X746591Y458024D01*
G01X765291Y436991D02*
X746591Y455690D01*
G01X765291Y434657D02*
X746591Y453357D01*
G01X765291Y432324D02*
X746591Y451024D01*
G01Y468854D02*
X758864Y481126D01*
G01X746591Y471187D02*
X756529Y481126D01*
G01X746591Y473521D02*
X754196Y481126D01*
G01X746591Y475854D02*
X751863Y481126D01*
G01X746591Y478187D02*
X749529Y481126D01*
G01X746591Y480521D02*
X747196Y481126D01*
G01X765291Y467326D02*
X751490Y481126D01*
G01X765291Y464993D02*
X749157Y481126D01*
G01X765291Y462658D02*
X746823Y481126D01*
G01X765291Y460325D02*
X746591Y479025D01*
G01X765291Y457992D02*
X746591Y476691D01*
G01Y481126D02*
X765291D01*
G01Y455658D02*
X746591Y474358D01*
G01X763251Y399176D02*
X765291Y401216D01*
G01X760917Y399176D02*
X765291Y403549D01*
G01X758584Y399176D02*
X765291Y405883D01*
G01X756251Y399176D02*
X765291Y408216D01*
G01X753917Y399176D02*
X765291Y410549D01*
G01Y481126D02*
Y399176D01*
G01Y478992D02*
X763157Y481126D01*
G01X765291Y476659D02*
X760824Y481126D01*
G01X765291Y474326D02*
X758491Y481126D01*
G01X765291Y471993D02*
X756158Y481126D01*
G01X765291Y469659D02*
X753823Y481126D01*
M02*
